PROJECT NAME:GTI
REV:C
8 RETIMER
GTI MB
DATE:2023/07/13
PCBA:
REV:V02
Thu Aug 24 10:13:28 2023<NAME_2>
<NAME_1>
MB FABCGTI V02
1 OF 365COVER PAGE
1
SHEETDATE
23
7 3 2 16 5 4
E
A
B
C
E
D
C
B
A
7 6 5 4
D
DEPARTMENT
SIZE
PROJECT DOCUMENT NUMBER REV
REVIEWER
DESIGNER
C



78
79
FPGA 1/6
CPU HW STRAP PIN
CPU1 CAVITY BOT DECOUPLING CAPS 3/3
CPU1 CAVITY BOT DECOUPLING CAPS 2/3
Blank
<NAME_1>
<NAME_2>
CPU0 GLUE LOGIC
CPU0 VSS 3/3
CPU0 VSS 2/3
CPU0 VSS 1/3
CPU0 POWER
29
120
119
118
117
116
114
113
112
111
110
109
108
107
106
105
104
103
102
101
100
99
98
97
96
95
94
93
92
91
90
89
88
87
86
85
84
83
81
80
76
73
72
71
70
69
68
67
66
65
64
63
62
61
60
59
58
57
56
55
54
53
52
51
50
49
48
47
46
45
44
43
42
41
40
39
38
37
36
35
34
33
32
31
30
28
27
26
25
24
23
22
21
20
19
18
17
16
15
14
13
12
11
10
9
8
7
6
5
4
3
2
1
PCIE - CPU1_EXAMAX_P2/P3_X16
PCIE - CPU0_EXAMAX_P0/P1_X16
PCIE - CPU0_EXAMAX_P0/P1_X16
PCIE - CPU0_EXAMAX_P2/P3_X16
PCIE - CPU0_EXAMAX_P2/P3_X16
Blank
BMC-GPU FPGA PCIE RE-DRIVER SELECT
BMC-GPU FPGA PCIE - RE-DRIVER (2nd)
BMC - GPU FPGA PCIE - RE-DRIVER (main)
Blank
DDR5 - CPU1 CHL
DDR5 - CPU1 CHK
DDR5 - CPU1 CHJ
DDR5 - CPU1 CHI
DDR5 - CPU1 CHH
DDR5 - CPU1 CHG
DDR5 - CPU1 CHF
DDR5 - CPU1 CHE
DDR5 - CPU1 CHD
DDR5 - CPU1 CHC
DDR5 - CPU1 CHB
DDR5 - CPU1 CHA
DDR5 - CPU0 CHL
DDR5 - CPU0 CHK
DDR5 - CPU0 CHJ
DDR5 - CPU0 CHI
DDR5 - CPU0 CHH
DDR5 - CPU0 CHG
DDR5 - CPU0 CHF
DDR5 - CPU0 CHE
DDR5 - CPU0 CHD
DDR5 - CPU0 CHC
DDR5 - CPU0 CHB
DDR5 - CPU0 CHA
FPGA 6/6
FPGA 5/6 (BOARD ID)
FPGA 4/6
FPGA 3/6
FPGA 2/6
CPU1 CAVITY BOT DECOUPLING CAPS 1/3
CPU1 CAVITY TOP DECOUPLING CAPS
CPU0 CAVITY BOT DECOUPLING CAPS 3/3
CPU0 CAVITY BOT DECOUPLING CAPS 2/3
CPU0 CAVITY BOT DECOUPLING CAPS 1/3
CPU0 CAVITY TOP DECOUPLING CAPS
PCIE AC-COUPLE CAPS 5/5
PCIE AC-COUPLE CAPS 4/5
PCIE AC-COUPLE CAPS 3/5
PCIE AC-COUPLE CAPS 2/5
Blank
CPU1 GLUE LOGIC
CPU1 VSS 3/3
CPU1 VSS 2/3
CPU1 VSS 1/3
CPU1 SPI/USB
CPU1 MISC 2/2
CPU1 MISC 1/2
CPU1 PCIE P4/P5/WAFL
CPU1 PCIE P2/P3
CPU1 PCIE P0/P1
CPU1 PCIE G2/G3
CPU1 PCIE G0/G1
CPU1 DDR CHL
CPU1 DDR CHK
CPU1 DDR CHJ
CPU1 DDR CHI
CPU1 DDR CHH
CPU1 DDR CHG
CPU1 DDR CHF
CPU1 DDR CHE
CPU1 DDR CHC
CPU1 DDR CHB
CPU0 SPI/USB
CPU0 MISC 2/2
CPU0 MISC 1/2
CPU0 PCIE P4/P5/WAFL
CPU0 PCIE P2/P3
CPU0 PCIE P0/P1
CPU0 PCIE G2/G3
CPU0 PCIE G0/G1
CPU0 DDR CHL
CPU0 DDR CHK
CPU0 DDR CHJ
CPU0 DDR CHI
CPU0 DDR CHH
CPU0 DDR CHG
CPU0 DDR CHF
CPU0 DDR CHE
CPU0 DDR CHD
CPU0 DDR CHC
CPU0 DDR CHB
CPU0 DDR CHA
BLOCK DIAGRAM - POWER SEQUENCE
BLOCK DIAGRAM - CLOCK
BLOCK DIAGRAM - POWER
BLOCK DIAGRAM - SYSTEM
TABLE OF CONTENT 3/3
TABLE OF CONTENT 2/3
TABLE OF CONTENT 1/3
COVER PAGE
GTI MB FABC
Thu Aug 24 10:13:29 2023 2 OF 365
V02
CPU1 DDR CHD
Blank
Blank
CPU1 DDR CHA
82
CPU1 POWER
BLOCK DIAGRAM - I2C/I3C
PCIE AC-COUPLE CAPS 1/5
115
PCIE - CPU1_EXAMAX_P2/P3_X16
77
75
74
CPU SPI LEVEL SHIFT
CPU PWROK
TABLE OF CONTENT 1/3
1
DEPARTMENT REV
7 3 26 5 4
C
A
B
7
E
D
6 45 3 2 1
E
D
C
B
A
DATE
PROJECT
SHEET
DOCUMENT NUMBERDESIGNER
SIZE
REVIEWER
C
CONTENTSPAGE(S) PAGE(S) CONTENTS PAGE(S) CONTENTS



240
239
238
237
236
235
234
233
232
231
230
229
228
227
226
225
224
223
222
221
220
219
218
217
216
215
214
213
212
211
210
209
208
207
206
205
204
203
202
201
199
198
196
195
194
193
192
191
190
189
188
187
186
185
184
183
182
181
180
179
178
177
176
175
174
173
172
171
170
169
168
166
165
164
163
162
161
160
159
158
157
156
155
154
153
152
151
150
149
148
147
146
145
144
143
142
141
140
139
138
137
136
135
134
133
132
131
130
129
128
127
126
125
124
123
122
121
POWER CONNECTOR/ISOLATED
Blank
MB FRU
POWER MONITOR (2/4)
POWER MONITOR (1/4)
TEMP SENSOR - LM75
USB HUB (BMC TO EXAMAX)
CLK-GEN(NON SSC)
Blank
Blank
HOLE
DELTA-L
Blank
Blank
PVDD18_S5_P1
PVDD11_S3_P1 VR PHASE 1&2
PVDD11_S3_P1 VR CONTROLLER
PVDDIO_P1 VR PHASE 3&4
PVDDIO_P1 VR PHASE 1&2
Blank
PVDDCR_CPU1_P1 VR PHASE 5&6
PVDDCR_CPU1_P1 VR PHASE 3&4
PVDDCR_CPU1_P1 VR PHASE 1&2
PVDDCR_CPU1_P1/PVDDIO_P1 VR CONTROLLER
PVDDCR_SOC_P1 VR PHASE 3
PVDDCR_SOC_P1 VR PHASE 1&2
Blank
PVDDCR_CPU0_P1 VR PHASE 5&6
PVDDCR_CPU0_P1 VR PHASE 3&4
PVDDCR_CPU0_P1 VR PHASE 1&2
PVDDCR_CPU0_P1/PVDDCR_SOC_P1 VR CONTROLLER
PVDD18_S5_P0
PVDD11_S3_P0 VR PHASE 1&2
Blank
PVDDCR_CPU1_P0 VR PHASE 5&6
PVDDCR_CPU1_P0 VR PHASE 1&2
PVDDCR_CPU1_P0/PVDDIO_P0 VR CONTROLLER
PVDDCR_SOC_P0 VR PHASE 3
PVDDCR_SOC_P0 VR PHASE 1&2
Blank
PVDDCR_CPU0_P0 VR PHASE 5&6
PVDDCR_CPU0_P0 VR PHASE 3&4
PVDDCR_CPU0_P0 VR PHASE 1&2
PVDDCR_CPU0_P0/PVDDCR_SOC_P0 VR CONTROLLER
PVDD_33_S5
Blank
NCP3284/P3V3_AUX
MPQ8633A/P5V_AUX
P5V & P3V3 SWITCH
BATTERY
SMBUS-RETIMER EEPROM MUX
SMBUS - RETIMER EEPROM
SMBUS - RETIMER
CLK BUFFER _ 9ZXL045 _ CPU1 RETIMER
CLK BUFFER _ 9ZXL045 _ CPU0 RETIMER
Blank
USB3.0 EXT HUB USB SIGNAL SELECT
USB3.0 EXT HUB 2ND(2/2)
USB3.0 EXT HUB 2ND(1/2)
USB3.0 EXT HUB MAIN(2/2)
USB3.0 EXT HUB MAIN(1/2)
Blank
JTAG - TDI/TDO
JTAG - BUFFER
JTAG - BMC MUX
Blank
DISCHARGE CIRCUIT
Blank
DEBUG JUMPER
LED (2/2)
LED (1/2)
UART LEVEL SHIFT
Blank
Blank
I2C MUX - APML(2/2)
I2C MUX - APML(1/2)
I3C MUX - DDR5 SPD
Blank
Blank
Blank
WAKE
Blank
SCM_SW
P12V_SCM
SCM SMBUS BUS
SCM CONN
CPU - SATA / RAID KEY
E1S_HSC_CO_LAYOUT
E1S_HSC
CPU0 - E1S - 0 CONN
CPU1 - M.2 - 0 CONN (EMPTY)
OCP3.0 NCSI
V3_2_OCP3.0 HSC(3/3)
V3_2_OCP3.0 HSC-CO-LAYOUT(2/3)
V3_2_OCP3.0 HSC(1/3)
PCIE - V3_2 OCP3.0 (3/3)
PCIE - V3_2 OCP3.0 (2/3)
PCIE - V3_2 OCP3.0_X16_CPU1 (1/3)
SFF_OCP3.0 HSC(3/3)
SFF_OCP3.0 HSC CO-LAYOUT(2/3)
SFF_OCP3.0 HSC(1/3)
PCIE - SFF OCP3.0 (3/3)
PCIE - SFF OCP3.0 (2/3)
PCIE - SFF OCP3.0_X16_CPU0 (1/3)
EXAMAX_ISO (7/7)
EXAMAX_ISO (6/7)
EXAMAX_ISO (5/7)
EXAMAX_ISO (4/7)
EXAMAX_ISO (3/7)
EXAMAX_ISO (2/7)
EXAMAX_ISO (1/7)
EXAMAX_PRESENT
PCIE - CPU1_EXAMAX_P0/P1_X16
PCIE - CPU1_EXAMAX_P0/P1_X16
3 OF 365
V02GTI
Thu Aug 24 10:13:29 2023
MB FABC
197
Blank
200
<NAME_2>
<NAME_1>
PVDDCR_CPU1_P0 VR PHASE 3&4
PVDDIO_P0_VR PHASE 1&2
PVDDIO_P0_VR PHASE 3&4
PVDD11_S3_P0 VR CONTROLLER
JTAG - HDT & BMC MUX
167
TABLE OF CONTENT 2/3
1
DEPARTMENT REV
7 3 26 5 4
C
A
B
7
E
D
6 45 3 2 1
E
D
C
B
A
DATE
PROJECT
SHEET
DOCUMENT NUMBERDESIGNER
SIZE
REVIEWER
C
CONTENTSPAGE(S) PAGE(S) CONTENTS PAGE(S) CONTENTS



<NAME_1>
<NAME_2>
POWER GOOD LED'S 3/3
PWRGD_ISOLATOR
SMBUS - PCIE1 SMBUS
Blank
246
4 OF 365Thu Aug 24 10:13:29 2023
V02GTI MB FABC
360
359
358
357
356
355
354
353
352
351
350
349
348
347
346
345
344
343
342
341
340
339
338
337
336
335
334
333
332
331
330
329
328
327
326
325
324
323
322
321
320
319
318
317
316
315
314
313
312
311
310
309
308
307
306
305
304
303
302
301
300
299
298
297
296
295
294
293
292
291
290
289
288
287
286
285
284
283
282
281
280
279
278
277
276
275
274
273
272
271
270
269
268
267
266
265
264
263
262
261
260
259
258
257
256
255
254
253
252
251
250
249
248
247
245
244
243
242
241
P1V8_CPU0_RT_1D
Blank
BOARD ID (RETIMER)
POWER MONITOR (4/4)
RETIMER_CPU1_P3 DECAPS(8)
RETIMER_CPU1_P3(7)
RETIMER_CPU1_P3 POWER(6)
RETIMER_CPU1_P3(5)
RETIMER_CPU1_P3(4)
RETIMER_CPU1_P3(3)
RETIMER_CPU1_P3(2)
RETIMER_CPU1_P3(1)
BLANK
RETIMER_CPU1_P2(10)
RETIMER_CPU1_P2(9)
RETIMER_CPU1_P2 DECAPS(8)
RETIMER_CPU1_P2(7)
RETIMER_CPU1_P2 POWER(6)
RETIMER_CPU1_P2(5)
RETIMER_CPU1_P2(4)
RETIMER_CPU1_P2(3)
RETIMER_CPU1_P2(2)
RETIMER_CPU1_P2(1)
BLANK
RETIMER_CPU1_P1(10)
RETIMER_CPU1_P1(9)
RETIMER_CPU1_P1 DECAPS(8)
RETIMER_CPU1_P1(7)
RETIMER_CPU1_P1 POWER(6)
RETIMER_CPU1_P1(5)
RETIMER_CPU1_P1(4)
RETIMER_CPU1_P1(3)
RETIMER_CPU1_P1(2)
RETIMER_CPU1_P1(1)
BLANK
RETIMER_CPU1_P0(10)
RETIMER_CPU1_P0 (9)
RETIMER_CPU1_P0 DECAPS (8)
RETIMER_CPU1_P0(7)
RETIMER_CPU1_P0 POWER(6)
RETIMER_CPU1_P0(5)
RETIMER_CPU1_P0(4)
RETIMER_CPU1_P0(3)
RETIMER_CPU1_P0(2)
RETIMER_CPU1_P0(1)
BLANK
RETIMER_CPU0_P3(10)
RETIMER_CPU0_P3(9)
RETIMER_CPU0_P3 DECAPS(8)
RETIMER_CPU0_P3(7)
RETIMER_CPU0_P3 POWER(6)
RETIMER_CPU0_P3(5)
RETIMER_CPU0_P3(4)
RETIMER_CPU0_P3(3)
RETIMER_CPU0_P3(2)
RETIMER_CPU0_P3(1)
BLANK
RETIMER_CPU0_P2(10)
RETIMER_CPU0_P2(9)
RETIMER_CPU0_P2 DECAPS(8)
RETIMER_CPU0_P2(7)
RETIMER_CPU0_P2 POWER(6)
RETIMER_CPU0_P2(5)
RETIMER_CPU0_P2(4)
RETIMER_CPU0_P2(3)
RETIMER_CPU0_P2(2)
RETIMER_CPU0_P2(1)
BLANK
RETIMER_CPU0_P1(10)
RETIMER_CPU0_P1(9)
RETIMER_CPU0_P1 DECAPS(8)
RETIMER_CPU0_P1(7)
RETIMER_CPU0_P1 POWER(6)
RETIMER_CPU0_P1(5)
RETIMER_CPU0_P1(4)
RETIMER_CPU0_P1(3)
RETIMER_CPU0_P1(2)
RETIMER_CPU0_P1(1)
BLANK
RETIMER_CPU0_P0(10)
RETIMER_CPU0_P0(9)
RETIMER_CPU0_P0 DECAPS(8)
RETIMER_CPU0_P0(7)
RETIMER_CPU0_P0 POWER(6)
RETIMER_CPU0_P0(5)
RETIMER_CPU0_P0(4)
RETIMER_CPU0_P0(3)
RETIMER_CPU0_P0(2)
RETIMER_CPU0_P0(1)
POWER MONITOR (3/4)
P1V2_AUX
P1V8_AUX
HSC Shared Circuit
P12V HOTSWAP FOR MODULE(2/2)
P12V HOTSWAP FOR MODULE(1/2)
Blank
HSC MP5990 (3/3)
HSC MP5990 (2/3)
HSC MP5990 (1/3)
TDR_2
TDR_1
P12V_MEM MOS SWITCH
VOLTAGE SENSOR (2/2)
VOLTAGE SENSOR (1/2)
POWER GOOD LED'S 2/3
POWER GOOD LED'S 1/3
SMBUS - PCIE2 SMBUS
SMBUS - PCIE0 SMBUS
SMBUS - PCIE3 SMBUS
SMBUS - ISOLATED
Blank
BMC - PCA9539
Blank
Blank
PSU POWER CONNECTORS
POWER CONNECTOR/ISOLATED
TABLE OF CONTENT 3/3
1
DEPARTMENT REV
7 3 26 5 4
C
A
B
7
E
D
6 45 3 2 1
E
D
C
B
A
DATE
PROJECT
SHEET
DOCUMENT NUMBERDESIGNER
SIZE
REVIEWER
C
CONTENTSPAGE(S) PAGE(S) CONTENTS PAGE(S) CONTENTS



Thu Aug 24 10:13:29 2023<NAME_2>
<NAME_1>
MB FABCGTI V02
5 OF 365
BLOCK DIAGRAM - SYSTEM
1
SHEETDATE
23
7 3 2 16 5 4
E
A
B
C
E
D
C
B
A
7 6 5 4
D
DEPARTMENT
SIZE
PROJECT DOCUMENT NUMBER REV
REVIEWER
DESIGNER
C



Thu Aug 24 10:13:30 2023<NAME_2>
<NAME_1>
MB FABCGTI V02
6 OF 365BLOCK DIAGRAM - POWER
1
SHEETDATE
23
7 3 2 16 5 4
E
A
B
C
E
D
C
B
A
7 6 5 4
D
DEPARTMENT
SIZE
PROJECT DOCUMENT NUMBER REV
REVIEWER
DESIGNER
C



Thu Aug 24 10:13:30 2023<NAME_2>
<NAME_1>
MB FABCGTI V02
7 OF 365BLOCK DIAGRAM - CLOCK
1
SHEETDATE
23
7 3 2 16 5 4
E
A
B
C
E
D
C
B
A
7 6 5 4
D
DEPARTMENT
SIZE
PROJECT DOCUMENT NUMBER REV
REVIEWER
DESIGNER
C



Thu Aug 24 10:13:30 2023<NAME_2>
<NAME_1>
MB FABCGTI V02
8 OF 365
BLOCK DIAGRAM - I2C/I3C
1
SHEETDATE
23
7 3 2 16 5 4
E
A
B
C
E
D
C
B
A
7 6 5 4
D
DEPARTMENT
SIZE
PROJECT DOCUMENT NUMBER REV
REVIEWER
DESIGNER
C



Thu Aug 24 10:13:30 2023<NAME_2>
<NAME_1>
MB FABCGTI V02
9 OF 365BLOCK DIAGRAM - POWER SEQUENCE
1
SHEETDATE
23
7 3 2 16 5 4
E
A
B
C
E
D
C
B
A
7 6 5 4
D
DEPARTMENT
SIZE
PROJECT DOCUMENT NUMBER REV
REVIEWER
DESIGNER
C



Thu Aug 24 14:08:32 2023<NAME_2>
<NAME_1>
MB FABCGTI V02
10 OF 365
86
86
86
86
86
86
86
86
86
86
86
86
86
86
86
86
86
86
86
86
86
86
R1941 PLACE CLOSE TO DIMM < 25MM
0402LF
15 1%
S O CK E T6096_13568-001
IO
M_A _CP U0_A LE RT_N
TP _M_A _CP U0_S A _TE S T39A
TP _M_A _CP U0_S A _TE S T40
M_A _CP U0_A LE RT_R_N
M_A _CP U0_S A _CA <6:0>
M_A _CP U0_CLK _DP <0>
M_A _CP U0_CLK _DN<0>
M_A _CP U0_S A _CS _N<0>
M_A _CP U0_S A _CS _N<1>
M_A _CP U0_S A _RS P <0>
M_A _CP U0_S B _CS _N<0>
M_A _CP U0_S A _P A R
M_A _CP U0_S B _CS _N<1>
M_A _CP U0_S B _RS P <0>
M_A _CP U0_S B _P A R
M_A _CP U0_RE S E T_N
M_A _CP U0_S A _DQ S _DN<9:0>
M_A _CP U0_S A _DQ S _DP <9:0>
M_A _CP U0_S B _DQ S _DP <9:0>
M_A _CP U0_S A _CB <7:0>
M_A _CP U0_S B _CB <7:0>
M_A _CP U0_S B _DQ <31:0>
M_A _CP U0_S A _DQ <31:0>
M_A _CP U0_S B _DQ S _DN<9:0>
M_A _CP U0_S B _CA <6:0>
CPU0 DDR CHA
SMLF
21R375
C60
BF72
BL74
BW74
DC73
CU73
CL73
CE73
BW73
DC74
CU74
CL74
CE74
BV74
DD72
CV72
CM 72
CF72
BY72
DB74
CT 74
CK74
CD74
DF74
DE74
DE73
DD74
DB72
DA74
DA73
CY74
CY72
CW74
CW73
CV74
CT 72
CR74
CR73
CP74
CP72
CN74
CN73
CM 74
CK72
CJ74
CJ73
CH74
CH72
CG74
CG73
CF74
CD72
CC74
CC73
CB74
BV72
BU74
BU73
BT 74
CB72
CA74
CA73
BY74
BK74
BK72
BJ73
BJ74
BH74
BH72
BG73
BR74
BM 74
BL73
BP74
BN74
BM 72
BC73
AM 72
AF72
Y72
P72
H72
AM 74
AF74
Y74
P74
H74
AN73
AG73
AA73
R73
J73
AL74
AE74
W74
N74
G74
AJ73
AH74
AH72
AG74
AE73
AD74
AD72
AC74
AC73
AB74
AB72
AA74
W73
V74
V72
U74
U73
T 74
T 72
R74
N73
M 74
M 72
L74
L73
K74
K72
J74
G73
F74
F72
E74
AR73
AP74
AP72
AN74
AL73
AK74
AK72
AJ74
BB72
BB74
BA74
BA73
AY72
AY74
AW74
BP72
AV72
AU74
BN73
AW73
AV74
AT 74
AR74
BG74
BF74
BD74
BC74
U25
5
6
2
3
4
0
1
5
6
3
4
2
0
1
7
8
9
5
6
4
2
3
0
1
9
8
7
6
5
4
2
3
1
0
7
8
9
5
6
2
3
4
0
1
9
8
7
6
5
4
3
2
1
0
7
6
5
4
3
2
1
6
7
0
5
4
3
1
2
0
29
30
31
27
28
24
26
25
23
19
20
21
22
18
15
17
16
14
10
12
11
13
9
6
7
8
5
4
1
2
3
0
29
30
31
27
28
24
25
26
23
20
22
21
18
19
15
17
16
14
10
11
12
13
9
6
7
8
5
4
1
2
3
0
CAD NOTE:
1/40
TEST40
TEST39A
MA1_CLK_L
MA0_CLK_L
MA1_CLK_H
MAB_DQS_H9
MA0_CLK_H
MAB_PAR
MAA_PAR
MAA0_CS_L0
MAA_DATA3
MAA_DQS_H6
MAB_CA6
MAB_DATA2
MAB_DATA17
MAB_DATA28
MAB_DQS_H0
MAB_DQS_L4
MAA_CA6
MAA_DATA2
MAA_DQS_H5
MAA_DQS_L9
MAB1_RSP_L
MAB_CA5
MAB_CHECK7
MAB_DATA1
MAB_DATA16
MAB_DATA27
MAB_DQS_L3
MAA_CA5
MAA_DATA1
MAA_DQS_H4
MAA_DQS_L8
MAB0_RSP_L
MAB_CA4
MAB_CHECK6
MAB_DATA0
MAB_DATA15
MAB_DATA26
MAB_DQS_L2
MAA_CA4
MAA_DATA0
MAA_DQS_H3
MAA_DQS_L7
MAB_CA3
MAB_CHECK5
MAB_DATA14
MAB_DATA25
MAB_DQS_L1
MAA_CA3
MAA_DATA19
MAA_DQS_H2
MAA_DQS_L6
MAB_CA2
MAB_CHECK4
MAB_DATA13
MAB_DATA24
MAB_DQS_L0
MAA_CA2
MAA_DATA18
MAA_DATA29
MAA_DQS_H1
MAA_DQS_L5
MAB_CA1
MAB_CHECK3
MAB_DATA12
MAB_DATA23
MAA_CA1
MAA_DATA17
MAA_DATA28
MAA_DQS_H0
MAA_DQS_L4
MAB_CA0
MAB_CHECK2
MAB_DATA11
MAB_DATA22
MAA1_RSP_L
MAA_CA0
MAA_CHECK7
MAA_DATA16
MAA_DATA27
MAA_DQS_L3
MAB_CHECK1
MAB_DATA10
MAB_DATA21
MAA0_RSP_L
MAA_CHECK6
MAA_DATA15
MAA_DATA26
MAA_DQS_L2
MAB_CHECK0
MAB_DATA20
MAB_DATA31
MAA_CHECK5
MAA_DATA14
MAA_DATA25
MAA_DQS_L1
MAB1_CS_L1
MAB_DATA30
MAB_DQS_H8
MAA_CHECK4
MAA_DATA13
MAA_DATA24
MAA_DQS_L0
MAB0_CS_L1
MAB1_CS_L0
MAB_DATA9
MAB_DQS_H7
MAA_CHECK3
MAA_DATA9
MAA_DATA12
MAA_DATA23
MAB0_CS_L0
MAB_DATA8
MAB_DQS_H6
MAA_CHECK2
MAA_DATA8
MAA_DATA11
MAA_DATA22
MAB_DATA7
MAB_DQS_H5
MAB_DQS_L9
MAA_CHECK1
MAA_DATA7
MAA_DATA10
MAA_DATA21
MAB_DATA6
MAB_DQS_H4
MAB_DQS_L8
MAA_CHECK0
MAA_DATA6
MAA_DATA20
MAA_DATA31
MAA_DQS_H9
MAB_DATA5
MAB_DQS_H3
MAB_DQS_L7
MAA1_CS_L1
MAA_DATA5
MAA_DATA30
MAA_DQS_H8
MAB_DATA4
MAB_DATA19
MAB_DQS_H2
MAB_DQS_L6
MAA0_CS_L1
MAA1_CS_L0
MAA_DATA4
MAA_DQS_H7
MAB_DATA3
MAB_DATA18
MAB_DATA29
MAB_DQS_H1
MAB_DQS_L5
MA_RESET_L
MA_ALERT_L
1
SHEETDATE
23
7 3 2 16 5 4
E
A
B
C
E
D
C
B
A
7 6 5 4
D
DEPARTMENT
SIZE
PROJECT DOCUMENT NUMBER REV
REVIEWER
DESIGNER
IN
OUT
OUT
IN
OUT
OUT
OUT
IN
OUT
OUT
OUT
OUT
OUT
OUT
BI
BI
BI
BI
BI
BI
BI
BI
C



Thu Aug 24 14:08:32 2023<NAME_2>
<NAME_1>
MB FABCGTI V02
11 OF 365
87
87
87
87
87
87
87
87
87
87
87
87
87
87
87
87
87
87
87
87
87
87
M_B _CP U0_S B _CA <6:0>
M_B _CP U0_CLK _DN<0>
M_B _CP U0_S A _CS _N<0>
M_B _CP U0_S B _CS _N<0>
M_B _CP U0_S B _RS P <0>
15 M_B _CP U0_A LE RT_R_NM_B _CP U0_A LE RT_N 1%
0402LF
S O CK E T6096_13568-001
IO
TP _M_B _CP U0_S A _TE S T39B
M_B _CP U0_S A _CA <6:0>
M_B _CP U0_CLK _DP <0>
M_B _CP U0_S A _CS _N<1>
M_B _CP U0_S A _P A R
M_B _CP U0_S A _RS P <0>
M_B _CP U0_S B _CS _N<1>
M_B _CP U0_S B _P A R
M_B _CP U0_RE S E T_N
M_B _CP U0_S A _DQ S _DP <9:0>
M_B _CP U0_S B _DQ S _DP <9:0>
M_B _CP U0_S B _DQ S _DN<9:0>
M_B _CP U0_S A _DQ S _DN<9:0>
M_B _CP U0_S B _CB <7:0>
M_B _CP U0_S A _CB <7:0>
M_B _CP U0_S A _DQ <31:0>
M_B _CP U0_S B _DQ <31:0>
CPU0 DDR CHB
R1946 PLACE CLOSE TO CPU < 25MM
SMLF
21R376
BF62
BL64
BW64
DC62
CU62
CL62
CE62
BW62
DC64
CU64
CL64
CE64
BV63
DD62
CV62
CM 62
CF62
BY62
DB63
CT 63
CK63
CD63
DF62
DE64
DE62
DD63
DB62
DA64
DA62
CY63
CY62
CW64
CW62
CV63
CT 62
CR64
CR62
CP63
CP62
CN64
CN62
CM 63
CK62
CJ64
CJ62
CH63
CH62
CG64
CG62
CF63
CD62
CC64
CC62
CB63
BV62
BU64
BU62
BT 63
CB62
CA64
CA62
BY63
BK63
BK62
BJ62
BJ64
BH63
BH62
BG62
BR64
BM 63
BL62
BP63
BN64
BM 62
BC62
AM 62
AF62
Y62
P62
H62
AM 63
AF63
Y63
P63
H63
AN62
AG62
AA62
R62
J62
AL64
AE64
W64
N64
G64
AJ62
AH63
AH62
AG64
AE62
AD63
AD62
AC64
AC62
AB63
AB62
AA64
W62
V63
V62
U64
U62
T 63
T 62
R64
N62
M 63
M 62
L64
L62
K63
K62
J64
G62
F63
F62
E64
AR62
AP63
AP62
AN64
AL62
AK63
AK62
AJ64
BB62
BB63
BA64
BA62
AY62
AY63
AW64
BP62
AV62
AU64
BN62
AW62
AV63
AU62
AT 62
BG64
BF63
BD63
BC64
U25
6
5
4
3
2
1
0
6
3
5
4
2
1
0
7
8
9
9
8
5
6
5
7
6
4
3
2
4
3
0
1
1
0
2
9
8
8
9
7
6
5
6
7
3
2
4
4
5
3
0
1
2
1
0
6
7
5
4
3
2
1
0
6
5
7
3
2
4
1
0
31
30
29
28
27
25
26
24
22
21
23
19
20
18
17
16
14
15
13
12
10
9
11
8
6
7
5
4
3
0
1
2
31
28
30
29
27
26
25
24
23
22
21
19
20
18
17
16
15
14
13
12
9
10
11
8
7
6
5
3
4
0
1
2
CAD NOTE:
2/40
TEST39B
MBB_DATA20
MBA_DATA24
MBB_DATA19
MB1_CLK_L
MB1_CLK_H
MB0_CLK_L
MB0_CLK_H
MBB_PAR
MBA_PAR
MBB_DQS_H9
MBA_CHECK1
MBA_DATA10
MBA_DATA21
MBB_DQS_H4
MBB_DQS_L8
MBA1_CS_L1
MBA_CHECK0
MBA_DATA20
MBA_DATA31
MBA_DQS_H9
MBB_CA6
MBB_DQS_H3
MBB_DQS_L7
MBA0_CS_L1
MBA1_CS_L0
MBA_CA6
MBA_DATA30
MBA_DQS_H8
MBB_CA5
MBB_DQS_H2
MBB_DQS_L6
MBA0_CS_L0
MBA_CA5
MBA_DQS_H7
MBB_CA4
MBB_DATA18
MBB_DATA29
MBB_DQS_H1
MBB_DQS_L5
MBA_CA4
MBA_DQS_H6
MBB1_RSP_L
MBB_CA3
MBB_DATA9
MBB_DATA17
MBB_DATA28
MBB_DQS_H0
MBB_DQS_L4
MBA_CA3
MBA_DATA9MBA_DQS_H5
MBA_DQS_L9
MBB0_RSP_L
MBB_CA2
MBB_CHECK7
MBB_DATA8
MBB_DATA16
MBB_DATA27
MBB_DQS_L3
MBA_CA2
MBA_DATA8
MBA_DQS_H4
MBA_DQS_L8
MBB_CA1
MBB_CHECK6
MBB_DATA7
MBB_DATA15
MBB_DATA26
MBB_DQS_L2
MBA_CA1
MBA_DATA7
MBA_DQS_H3
MBA_DQS_L7
MBB_CA0
MBB_CHECK5
MBB_DATA6
MBB_DATA14
MBB_DATA25
MBB_DQS_L1
MBA_CA0
MBA_DATA6
MBA_DATA19
MBA_DQS_H2
MBA_DQS_L6
MBB_CHECK4
MBB_DATA5
MBB_DATA13
MBB_DATA24
MBB_DQS_L0
MBA_DATA5
MBA_DATA18
MBA_DATA29
MBA_DQS_H1
MBA_DQS_L5
MBB_CHECK3
MBB_DATA4
MBB_DATA12
MBB_DATA23
MBA1_RSP_L
MBA_DATA4
MBA_DATA17
MBA_DATA28
MBA_DQS_H0
MBA_DQS_L4
MBB_CHECK2
MBB_DATA3
MBB_DATA11
MBB_DATA22
MBA0_RSP_L
MBA_CHECK7
MBA_DATA3
MBA_DATA16
MBA_DATA27
MBA_DQS_L3
MBB_CHECK1
MBB_DATA2
MBB_DATA10
MBB_DATA21
MBA_CHECK6
MBA_DATA2
MBA_DATA15
MBA_DATA26
MBA_DQS_L2
MBB1_CS_L1
MBB_CHECK0
MBB_DATA1
MBB_DATA31
MBA_CHECK5
MBA_DATA1
MBA_DATA14
MBA_DATA25
MBA_DQS_L1
MBB0_CS_L1
MBB1_CS_L0
MBB_DATA0
MBB_DATA30
MBB_DQS_H8
MBA_CHECK4
MBA_DATA0
MBA_DATA13
MBA_DQS_L0
MBB0_CS_L0
MBB_DQS_H7
MBA_CHECK3
MBA_DATA12
MBA_DATA23
MBB_DQS_H6
MBA_CHECK2
MBA_DATA11
MBA_DATA22
MBB_DQS_H5
MBB_DQS_L9
MB_RESET_L
MB_ALERT_L
1
SHEETDATE
23
7 3 2 16 5 4
E
A
B
C
E
D
C
B
A
7 6 5 4
D
DEPARTMENT
SIZE
PROJECT DOCUMENT NUMBER REV
REVIEWER
DESIGNER
IN
OUT
IN
OUT
OUT
IN
OUT
OUT
OUT
OUT
OUT
OUT
OUT
OUT
BI
BI
BI
BI
BI
BI
BI
BI
C



Thu Aug 24 14:08:33 2023<NAME_2>
<NAME_1>
MB FABCGTI V02
12 OF 365
88
88
88
88
88
88
88
88
88
88
88
88
88
88
88
88
88
88
88
88
88
88
15 M_C_CP U0_A LE RT_R_NM_C_CP U0_A LE RT_N 1%
0402LF
S O CK E T6096_13568-001
IO
M_C_CP U0_S A _CA <6:0>
M_C_CP U0_S B _CA <6:0>
TP _M_C_CP U0_S A _TE S T39C
M_C_CP U0_CLK _DP <0>
M_C_CP U0_CLK _DN<0>
M_C_CP U0_S A _RS P <0>
M_C_CP U0_S A _CS _N<0>
M_C_CP U0_S A _CS _N<1>
M_C_CP U0_S A _P A R
M_C_CP U0_S B _CS _N<0>
M_C_CP U0_S B _CS _N<1>
M_C_CP U0_S B _RS P <0>
M_C_CP U0_S B _P A R
M_C_CP U0_RE S E T_N
M_C_CP U0_S B _DQ S _DN<9:0>
M_C_CP U0_S A _DQ S _DN<9:0>
M_C_CP U0_S A _DQ S _DP <9:0>
M_C_CP U0_S B _DQ S _DP <9:0>
M_C_CP U0_S B _CB <7:0>
M_C_CP U0_S A _CB <7:0>
M_C_CP U0_S A _DQ <31:0>
M_C_CP U0_S B _DQ <31:0>
R1951 PLACE CLOSE TO CPU < 25MM
CPU0 DDR CHC
SMLF
21R377
BF55
BL57
BW57
DC55
CU55
CL55
CE55
BW55
DC57
CU57
CL57
CE57
BV56
DD55
CV55
CM 55
CF55
BY55
DB56
CT 56
CK56
CD56
DF55
DE57
DE55
DD56
DB55
DA57
DA55
CY56
CY55
CW57
CW55
CV56
CT 55
CR57
CR55
CP56
CP55
CN57
CN55
CM 56
CK55
CJ57
CJ55
CH56
CH55
CG57
CG55
CF56
CD55
CC57
CC55
CB56
BV55
BU57
BU55
BT 56
CB55
CA57
CA55
BY56
BK56
BK55
BJ55
BJ57
BH56
BH55
BG55
BR57
BM 56
BL55
BP56
BN57
BM 55
BC55
AM 55
AF55
Y55
P55
H55
AM 56
AF56
Y56
P56
H56
AN55
AG55
AA55
R55
J55
AL57
AE57
W57
N57
G57
AJ55
AH56
AH55
AG57
AE55
AD56
AD55
AC57
AC55
AB56
AB55
AA57
W55
V56
V55
U57
U55
T 56
T 55
R57
N55
M 56
M 55
L57
L55
K56
K55
J57
G55
F56
F55
E57
AR55
AP56
AP55
AN57
AL55
AK56
AK55
AJ57
BB55
BB56
BA57
BA55
AY55
AY56
AW57
BP55
AV55
AU57
BN55
AW55
AV56
AU55
AT 55
BG57
BF56
BD56
BC57
U25
6
5
4
2
3
1
0
6
5
4
3
2
0
1
8
9
9
6
7
4
3
5
1
2
9
0
6
7
8
4
3
5
0
2
1
7
8
6
5
3
4
2
1
0
9
8
7
6
5
4
3
2
1
0
6
7
5
4
3
2
1
0
7
6
5
4
3
2
1
0
31
30
29
28
27
25
26
24
21
23
20
22
19
18
17
16
13
15
14
12
11
10
9
8
7
6
5
4
3
2
0
1
31
30
29
28
27
26
25
24
23
22
21
20
19
18
17
16
15
14
13
12
11
9
10
8
7
6
5
4
3
2
0
1
CAD NOTE:
3/40
TEST39C
MC1_CLK_L
MC1_CLK_H
MC0_CLK_L
MC0_CLK_H
MCB_PAR
MCA_PAR
MCB_DQS_H9
MCA_CHECK4
MCA_DATA8
MCA_DATA13
MCA_DATA24
MCA_DQS_L0
MCB0_CS_L0
MCB1_CS_L0
MCB_DATA7
MCB_DQS_H7
MCA_CHECK3
MCA_DATA7
MCA_DATA12
MCA_DATA23
MCB_DATA6
MCB_DQS_H6
MCA_CHECK2
MCA_DATA6
MCA_DATA11
MCA_DATA22
MCB_CA6
MCB_DATA5
MCB_DQS_H5
MCB_DQS_L9
MCA_CA6
MCA_CHECK1
MCA_DATA5
MCA_DATA10
MCA_DATA21
MCB_CA5
MCB_DATA4
MCB_DQS_H4
MCB_DQS_L8
MCA_CA5
MCA_CHECK0
MCA_DATA4
MCA_DATA20
MCA_DATA31
MCA_DQS_H9
MCB_CA4
MCB_DATA3
MCB_DQS_H3
MCB_DQS_L7
MCA1_CS_L1
MCA_CA4
MCA_DATA3
MCA_DATA30
MCA_DQS_H8
MCB_CA3
MCB_DATA2
MCB_DATA19
MCB_DQS_H2
MCB_DQS_L6
MCA0_CS_L1
MCA1_CS_L0
MCA_CA3
MCA_DATA2
MCA_DQS_H7
MCB_CA2
MCB_DATA1
MCB_DATA18
MCB_DATA29
MCB_DQS_H1
MCB_DQS_L5
MCA0_CS_L0
MCA_CA2
MCA_DATA1
MCA_DQS_H6
MCB_CA1
MCB_DATA0
MCB_DATA17
MCB_DATA28
MCB_DQS_H0
MCB_DQS_L4
MCA_CA1
MCA_DATA0
MCA_DQS_H5
MCA_DQS_L9
MCB0_RSP_L
MCB1_RSP_L
MCB_CA0
MCB_CHECK7
MCB_DATA16
MCB_DATA27
MCB_DQS_L3
MCA_CA0
MCA_DQS_H4
MCA_DQS_L8
MCB_CHECK6
MCB_DATA15
MCB_DATA26
MCB_DQS_L2
MCA_DQS_H3
MCA_DQS_L7
MCB_CHECK5
MCB_DATA14
MCB_DATA25
MCB_DQS_L1
MCA_DATA19
MCA_DQS_H2
MCA_DQS_L6
MCB_CHECK4
MCB_DATA13
MCB_DATA24
MCB_DQS_L0
MCA_DATA18
MCA_DATA29
MCA_DQS_H1
MCA_DQS_L5
MCB_CHECK3
MCB_DATA12
MCB_DATA23
MCA_DATA17
MCA_DATA28
MCA_DQS_H0
MCA_DQS_L4
MCB_CHECK2
MCB_DATA11
MCB_DATA22
MCA1_RSP_L
MCA_CHECK7
MCA_DATA16
MCA_DATA27
MCA_DQS_L3
MCB_CHECK1
MCB_DATA10
MCB_DATA21
MCA0_RSP_L
MCA_CHECK6
MCA_DATA15
MCA_DATA26
MCA_DQS_L2
MCB_CHECK0
MCB_DATA9
MCB_DATA20
MCB_DATA31
MCA_CHECK5
MCA_DATA9
MCA_DATA14
MCA_DATA25
MCA_DQS_L1
MCB0_CS_L1
MCB1_CS_L1
MCB_DATA8
MCB_DATA30
MCB_DQS_H8
MC_RESET_L
MC_ALERT_L
1
SHEETDATE
23
7 3 2 16 5 4
E
A
B
C
E
D
C
B
A
7 6 5 4
D
DEPARTMENT
SIZE
PROJECT DOCUMENT NUMBER REV
REVIEWER
DESIGNER
OUT
IN
OUT
IN
OUT
OUT
OUT
OUT
OUT
IN
OUT
OUT
OUT
OUT
BI
BI
BI
BI
BI
BI
BI
BI
C



Thu Aug 24 14:08:33 2023<NAME_2>
<NAME_1>
MB FABCGTI V02
13 OF 365
89
89
89
89
89
89
89
89
89
89
89
89
89
89
89
89
89
89
89
89
89
89
15 M_D_CP U0_A LE RT_R_NM_D_CP U0_A LE RT_N 1%
0402LF
M_D_CP U0_S B _CA <6:0>
M_D_CP U0_S A _CA <6:0>
M_D_CP U0_S B _DQ S _DP <9:0>
SMLF
CPU0 DDR CHD
R1952 PLACE CLOSE TO CPU < 25MM
M_D_CP U0_S B _DQ <31:0>
M_D_CP U0_S A _DQ <31:0>
M_D_CP U0_S A _CB <7:0>
M_D_CP U0_S B _CB <7:0>
M_D_CP U0_S A _DQ S _DN<9:0>
M_D_CP U0_S B _DQ S _DN<9:0>
M_D_CP U0_S A _DQ S _DP <9:0>
M_D_CP U0_RE S E T_N
M_D_CP U0_S B _P A R
M_D_CP U0_S B _RS P <0>
M_D_CP U0_S B _CS _N<1>
M_D_CP U0_S B _CS _N<0>
M_D_CP U0_S A _P A R
M_D_CP U0_S A _RS P <0>
M_D_CP U0_S A _CS _N<1>
M_D_CP U0_S A _CS _N<0>
M_D_CP U0_CLK _DN<0>
M_D_CP U0_CLK _DP <0>
TP _M_D_CP U0_S A _TE S T39D
IO
S O CK E T6096_13568-001
21R378
BF58
BL60
BW60
DC59
CU59
CL59
CE59
BW59
DC60
CU60
CL60
CE60
BV60
DD58
CV58
CM 58
CF58
BY58
DB60
CT 60
CK60
CD60
DF60
DE60
DE59
DD60
DB58
DA60
DA59
CY60
CY58
CW60
CW59
CV60
CT 58
CR60
CR59
CP60
CP58
CN60
CN59
CM 60
CK58
CJ60
CJ59
CH60
CH58
CG60
CG59
CF60
CD58
CC60
CC59
CB60
BV58
BU60
BU59
BT 60
CB58
CA60
CA59
BY60
BK60
BK58
BJ59
BJ60
BH60
BH58
BG59
BR60
BM 60
BL59
BP60
BN60
BM 58
BC59
AM 58
AF58
Y58
P58
H58
AM 60
AF60
Y60
P60
H60
AN59
AG59
AA59
R59
J59
AL60
AE60
W60
N60
G60
AJ59
AH60
AH58
AG60
AE59
AD60
AD58
AC60
AC59
AB60
AB58
AA60
W59
V60
V58
U60
U59
T 60
T 58
R60
N59
M 60
M 58
L60
L59
K60
K58
J60
G59
F60
F58
E60
AR59
AP60
AP58
AN60
AL59
AK60
AK58
AJ60
BB58
BB60
BA60
BA59
AY58
AY60
AW60
BP58
AV58
AU60
BN59
AW59
AV60
AU59
AT 58
BG60
BF60
BD60
BC60
U25
0
24
27
20
2
0
1
5
3
4
6
7
9
8
10
11
14
12
13
15
16
18
17
19
21
25
23
22
26
28
30
29
2
0
31
1
5
3
4
6
7
8
9
10
11
14
12
13
15
18
17
16
21
19
20
23
24
22
25
26
27
28
30
29
2
1
0
31
4
3
5
6
7
3
2
0
1
6
4
5
7
0
1
2
3
0
1
2
3
5
4
6
7
9
8
4
5
6
7
8
1
0
2
3
9
1
2
3
4
5
6
7
8
4
5
6
7
8
9
1
9
0
2
3
4
5
6
1
0
3
2
4
5
6
CAD NOTE:
4/40
TEST39D
MD1_CLK_L
MD1_CLK_H
MD0_CLK_L
MD0_CLK_H
MDB_DQS_H9
MDB_CA3
MDB_PAR
MDA_PAR
MDA1_RSP_L
MDA_DATA2
MDA_DATA17
MDA_DATA28
MDA_DQS_H0
MDA_DQS_L4
MDB_CHECK2
MDB_DATA1
MDB_DATA11
MDB_DATA22
MDA0_RSP_L
MDA_CHECK7
MDA_DATA1
MDA_DATA16
MDA_DATA27
MDA_DQS_L3
MDB_CHECK1
MDB_DATA0
MDB_DATA10
MDB_DATA21
MDA_CHECK6
MDA_DATA0
MDA_DATA15
MDA_DATA26
MDA_DQS_L2
MDB1_CS_L1
MDB_CHECK0
MDB_DATA20
MDB_DATA31
MDA_CHECK5
MDA_DATA14
MDA_DATA25
MDA_DQS_L1
MDB0_CS_L1
MDB1_CS_L0
MDB_CA6
MDB_DATA30
MDB_DQS_H8
MDA_CA6
MDA_CHECK4
MDA_DATA13
MDA_DATA24
MDA_DQS_L0
MDB0_CS_L0
MDB_CA5
MDB_DQS_H7
MDA_CA5
MDA_CHECK3
MDA_DATA12
MDA_DATA23
MDB_CA4
MDB_DQS_H6
MDA_CA4
MDA_CHECK2
MDA_DATA11
MDA_DATA22
MDB_DQS_H5
MDB_DQS_L9
MDA_CA3
MDA_CHECK1
MDA_DATA10
MDA_DATA21
MDB_CA2
MDB_DQS_H4
MDB_DQS_L8
MDA1_CS_L1
MDA_CA2
MDA_CHECK0
MDA_DATA20
MDA_DATA31
MDA_DQS_H9
MDB_CA1
MDB_DQS_H3
MDB_DQS_L7
MDA0_CS_L1
MDA1_CS_L0
MDA_CA1
MDA_DATA30
MDA_DQS_H8
MDB_CA0
MDB_DATA9
MDB_DATA19
MDB_DQS_H2
MDB_DQS_L6
MDA0_CS_L0
MDA_CA0
MDA_DATA9
MDA_DQS_H7
MDB_DATA8
MDB_DATA18
MDB_DATA29
MDB_DQS_H1
MDB_DQS_L5
MDA_DATA8
MDA_DQS_H6
MDB1_RSP_L
MDB_DATA7
MDB_DATA17
MDB_DATA28
MDB_DQS_H0
MDB_DQS_L4
MDA_DATA7
MDA_DQS_H5
MDA_DQS_L9
MDB0_RSP_L
MDB_CHECK7
MDB_DATA6
MDB_DATA16
MDB_DATA27
MDB_DQS_L3
MDA_DATA6
MDA_DQS_H4
MDA_DQS_L8
MDB_CHECK6
MDB_DATA5
MDB_DATA15
MDB_DATA26
MDB_DQS_L2
MDA_DATA5
MDA_DQS_H3
MDA_DQS_L7
MDB_CHECK5
MDB_DATA4
MDB_DATA14
MDB_DATA25
MDB_DQS_L1
MDA_DATA4
MDA_DATA19
MDA_DQS_H2
MDA_DQS_L6
MDB_CHECK4
MDB_DATA3
MDB_DATA13
MDB_DATA24
MDB_DQS_L0
MDA_DATA3
MDA_DATA18
MDA_DATA29
MDA_DQS_H1
MDA_DQS_L5
MDB_CHECK3
MDB_DATA2
MDB_DATA12
MDB_DATA23
MD_RESET_L
MD_ALERT_L
1
SHEETDATE
23
7 3 2 16 5 4
E
A
B
C
E
D
C
B
A
7 6 5 4
D
DEPARTMENT
SIZE
PROJECT DOCUMENT NUMBER REV
REVIEWER
DESIGNER
OUT
IN
OUT
IN
OUT
OUT
OUT
IN
OUT
OUT
OUT
OUT
OUT
OUT
BI
BI
BI
BI
BI
BI
BI
BI
C



Thu Aug 24 14:08:33 2023<NAME_2>
<NAME_1>
MB FABCGTI V02
14 OF 365
TP _M_E _CP U0_S A _TE S T39E
M_E _CP U0_CLK _DN<0>
M_E _CP U0_CLK _DP <0>
M_E _CP U0_S B _P A R
M_E _CP U0_S A _P A R
M_E _CP U0_S A _RS P <0>
M_E _CP U0_S B _CS _N<1>
M_E _CP U0_S B _CS _N<0>
M_E _CP U0_S A _CS _N<1>
M_E _CP U0_S A _CS _N<0>
M_E _CP U0_S B _RS P <0>
M_E _CP U0_RE S E T_N
M_E _CP U0_A LE RT_R_N
SMLF
IO
S O CK E T6096_13568-001
90
90
90
90
90
90
90
90
90
90
90
90
90
90
90
90
90
90
90
90
90
90
15M_E _CP U0_A LE RT_N 1%
0402LF
M_E _CP U0_S B _CA <6:0>
M_E _CP U0_S A _CA <6:0>
M_E _CP U0_S A _DQ S _DP <9:0>
M_E _CP U0_S B _DQ S _DP <9:0>
M_E _CP U0_S B _DQ S _DN<9:0>
M_E _CP U0_S A _DQ S _DN<9:0>
M_E _CP U0_S A _CB <7:0>
M_E _CP U0_S B _CB <7:0>
M_E _CP U0_S A _DQ <31:0>
M_E _CP U0_S B _DQ <31:0>
R1953 PLACE CLOSE TO CPU < 25MM
CPU0 DDR CHE
21R379
BF69
BL71
BW71
DC69
CU69
CL69
CE69
BW69
DC71
CU71
CL71
CE71
BV70
DD69
CV69
CM 69
CF69
BY69
DB70
CT 70
CK70
CD70
DF69
DE71
DE69
DD70
DB69
DA71
DA69
CY70
CY69
CW71
CW69
CV70
CT 69
CR71
CR69
CP70
CP69
CN71
CN69
CM 70
CK69
CJ71
CJ69
CH70
CH69
CG71
CG69
CF70
CD69
CC71
CC69
CB70
BV69
BU71
BU69
BT 70
CB69
CA71
CA69
BY70
BK70
BK69
BJ69
BJ71
BH70
BH69
BG69
BR71
BM 70
BL69
BP70
BN71
BM 69
BC69
AM 69
AF69
Y69
P69
H69
AM 70
AF70
Y70
P70
H70
AN69
AG69
AA69
R69
J69
AL71
AE71
W71
N71
G71
AJ69
AH70
AH69
AG71
AE69
AD70
AD69
AC71
AC69
AB70
AB69
AA71
W69
V70
V69
U71
U69
T 70
T 69
R71
N69
M 70
M 69
L71
L69
K70
K69
J71
G69
F70
F69
E71
AR69
AP70
AP69
AN71
AL69
AK70
AK69
AJ71
BB69
BB70
BA71
BA69
AY69
AY70
AW71
BP69
AV69
AU71
BN69
AW69
AV70
AU69
AT 69
BG71
BF70
BD70
BC71
U25
6
5
4
2
3
1
0
4
5
6
3
2
1
0
9
8
7
6
5
4
9
7
8
6
5
4
3
2
1
9
0
3
2
0
1
8
7
6
5
4
9
7
8
6
5
3
2
1
0
4
2
3
1
0
7
5
6
3
2
4
0
1
7
6
5
3
4
1
2
31
0
30
29
28
27
26
25
24
22
23
21
20
19
18
17
16
15
13
14
10
11
12
9
8
7
6
4
5
2
1
3
0
31
30
29
28
27
26
24
25
22
23
21
20
19
17
18
16
13
14
15
10
11
12
8
9
7
6
4
5
2
1
3
0
CAD NOTE:
5/40
TEST39E
ME1_CLK_L
ME1_CLK_H
ME0_CLK_L
ME0_CLK_H
MEB_DQS_H9
MEB_PAR
MEA_PAR
MEA_DQS_H3
MEA_DQS_L7
MEB_CHECK5
MEB_DATA14
MEB_DATA25
MEB_DQS_L1
MEA_DATA19
MEA_DQS_H2
MEA_DQS_L6
MEB_CHECK4
MEB_DATA13
MEB_DATA24
MEB_DQS_L0
MEA_DATA18
MEA_DATA29
MEA_DQS_H1
MEA_DQS_L5
MEB_CHECK3
MEB_DATA12
MEB_DATA23
MEA_DATA17
MEA_DATA28
MEA_DQS_H0
MEA_DQS_L4
MEB_CHECK2
MEB_DATA9
MEB_DATA11
MEB_DATA22
MEA0_RSP_L
MEA1_RSP_L
MEA_CHECK7
MEA_DATA9
MEA_DATA16
MEA_DATA27
MEA_DQS_L3
MEB_CA6
MEB_CHECK1
MEB_DATA8
MEB_DATA10
MEB_DATA21
MEA_CA6
MEA_CHECK6
MEA_DATA8
MEA_DATA15
MEA_DATA26
MEA_DQS_L2
MEB_CA5
MEB_CHECK0
MEB_DATA7
MEB_DATA20
MEB_DATA31
MEA_CA5
MEA_CHECK5
MEA_DATA7
MEA_DATA14
MEA_DATA25
MEA_DQS_L1
MEB0_CS_L1
MEB1_CS_L1
MEB_CA4
MEB_DATA6
MEB_DATA30
MEB_DQS_H8
MEA_CA4
MEA_CHECK4
MEA_DATA6
MEA_DATA13
MEA_DATA24
MEA_DQS_L0
MEB0_CS_L0
MEB1_CS_L0
MEB_CA3
MEB_DATA5
MEB_DQS_H7
MEA_CA3
MEA_CHECK3
MEA_DATA5
MEA_DATA12
MEA_DATA23
MEB_CA2
MEB_DATA4
MEB_DQS_H6
MEA_CA2
MEA_CHECK2
MEA_DATA4
MEA_DATA11
MEA_DATA22
MEB_CA1
MEB_DATA3
MEB_DQS_H5
MEB_DQS_L9
MEA_CA1
MEA_CHECK1
MEA_DATA3
MEA_DATA10
MEA_DATA21
MEB_CA0
MEB_DATA2
MEB_DQS_H4
MEB_DQS_L8
MEA_CA0
MEA_CHECK0
MEA_DATA2
MEA_DATA20
MEA_DATA31
MEA_DQS_H9
MEB_DATA1
MEB_DQS_H3
MEB_DQS_L7
MEA0_CS_L1
MEA1_CS_L1
MEA_DATA1
MEA_DATA30
MEA_DQS_H8
MEB_DATA0
MEB_DATA19
MEB_DQS_H2
MEB_DQS_L6
MEA0_CS_L0
MEA1_CS_L0
MEA_DATA0
MEA_DQS_H7
MEB_DATA18
MEB_DATA29
MEB_DQS_H1
MEB_DQS_L5
MEA_DQS_H6
MEB_DATA17
MEB_DATA28
MEB_DQS_H0
MEB_DQS_L4
MEA_DQS_H5
MEA_DQS_L9
MEB0_RSP_L
MEB1_RSP_L
MEB_CHECK7
MEB_DATA16
MEB_DATA27
MEB_DQS_L3
MEA_DQS_H4
MEA_DQS_L8
MEB_CHECK6
MEB_DATA15
MEB_DATA26
MEB_DQS_L2
ME_RESET_L
ME_ALERT_L
1
SHEETDATE
23
7 3 2 16 5 4
E
A
B
C
E
D
C
B
A
7 6 5 4
D
DEPARTMENT
SIZE
PROJECT DOCUMENT NUMBER REV
REVIEWER
DESIGNER
IN
IN
IN
OUT
OUT
OUT
OUT
OUT
OUT
OUT
OUT
OUT
OUT
OUT
BI
BI
BI
BI
BI
BI
BI
BI
C



Thu Aug 24 14:08:34 2023<NAME_2>
<NAME_1>
MB FABCGTI V02
15 OF 365
91
91
91
91
91
91
91
91
91
91
91
91
91
91
91
91
91
91
91
91
91
91
15 M_F_CP U0_A LE RT_R_NM_F_CP U0_A LE RT_N 1%
0402LF
S O CK E T6096_13568-001
IO
TP _M_F_CP U0_S A _TE S T39F
M_F_CP U0_S A _CA <6:0>
M_F_CP U0_S B _CA <6:0>
M_F_CP U0_CLK _DP <0>
M_F_CP U0_CLK _DN<0>
M_F_CP U0_S A _CS _N<0>
M_F_CP U0_S A _CS _N<1>
M_F_CP U0_S B _RS P <0>
M_F_CP U0_S A _RS P <0>
M_F_CP U0_S A _P A R
M_F_CP U0_S B _CS _N<0>
M_F_CP U0_S B _CS _N<1>
M_F_CP U0_S B _P A R
M_F_CP U0_RE S E T_N
M_F_CP U0_S A _DQ S _DP <9:0>
M_F_CP U0_S B _DQ S _DP <9:0>
M_F_CP U0_S B _DQ S _DN<9:0>
M_F_CP U0_S A _DQ S _DN<9:0>
M_F_CP U0_S B _CB <7:0>
M_F_CP U0_S A _CB <7:0>
M_F_CP U0_S A _DQ <31:0>
M_F_CP U0_S B _DQ <31:0>
R1954 PLACE CLOSE TO CPU < 25MM
CPU0 DDR CHF
SMLF
21R380
BF65
BL67
BW67
DC66
CU66
CL66
CE66
BW66
DC67
CU67
CL67
CE67
BV67
DD65
CV65
CM 65
CF65
BY65
DB67
CT 67
CK67
CD67
DF67
DE67
DE66
DD67
DB65
DA67
DA66
CY67
CY65
CW67
CW66
CV67
CT 65
CR67
CR66
CP67
CP65
CN67
CN66
CM 67
CK65
CJ67
CJ66
CH67
CH65
CG67
CG66
CF67
CD65
CC67
CC66
CB67
BV65
BU67
BU66
BT 67
CB65
CA67
CA66
BY67
BK67
BK65
BJ66
BJ67
BH67
BH65
BG66
BR67
BM 67
BL66
BP67
BN67
BM 65
BC66
AM 65
AF65
Y65
P65
H65
AM 67
AF67
Y67
P67
H67
AN66
AG66
AA66
R66
J66
AL67
AE67
W67
N67
G67
AJ66
AH67
AH65
AG67
AE66
AD67
AD65
AC67
AC66
AB67
AB65
AA67
W66
V67
V65
U67
U66
T 67
T 65
R67
N66
M 67
M 65
L67
L66
K67
K65
J67
G66
F67
F65
E67
AR66
AP67
AP65
AN67
AL66
AK67
AK65
AJ67
BB65
BB67
BA67
BA66
AY65
AY67
AW67
BP65
AV65
AU67
BN66
AW66
AV67
AU66
AT 65
BG67
BF67
BD67
BC67
U25
5
6
4
3
2
1
0
6
5
4
3
2
1
0
8
9
9
7
6
5
4
3
8
7
6
5
4
2
1
0
9
3
2
1
0
9
7
8
6
5
4
3
8
7
6
5
4
2
1
0
3
2
1
0
6
7
3
4
5
1
2
0
7
4
5
6
3
2
0
1
31
30
27
28
29
26
25
23
24
21
22
18
19
20
17
16
15
14
11
12
13
9
10
7
8
5
6
2
3
4
0
1
30
31
27
28
29
26
25
24
23
21
22
18
19
20
16
17
14
15
11
12
13
10
9
7
8
5
6
2
3
4
1
0
CAD NOTE:
6/40
TEST39F
MF1_CLK_L
MF1_CLK_H
MF0_CLK_L
MF0_CLK_H
MFB_DQS_H9
MFB_PAR
MFA_PAR
MFA0_CS_L0
MFA_DATA7
MFA_DQS_H7
MFB_DATA6
MFB_DATA18
MFB_DATA29
MFB_DQS_H1
MFB_DQS_L5
MFA_DATA6
MFA_DQS_H6
MFB1_RSP_L
MFB_DATA5
MFB_DATA17
MFB_DATA28
MFB_DQS_H0
MFB_DQS_L4
MFA_DATA5
MFA_DQS_H5
MFA_DQS_L9
MFB0_RSP_L
MFB_CHECK7
MFB_DATA4
MFB_DATA16
MFB_DATA27
MFB_DQS_L3
MFA_DATA4
MFA_DQS_H4
MFA_DQS_L8
MFB_CHECK6
MFB_DATA3
MFB_DATA15
MFB_DATA26
MFB_DQS_L2
MFA_DATA3
MFA_DQS_H3
MFA_DQS_L7
MFB_CHECK5
MFB_DATA2
MFB_DATA14
MFB_DATA25
MFB_DQS_L1
MFA_DATA2
MFA_DATA19
MFA_DQS_H2
MFA_DQS_L6
MFB_CA6
MFB_CHECK4
MFB_DATA1
MFB_DATA13
MFB_DATA24
MFB_DQS_L0
MFA_CA6
MFA_DATA1
MFA_DATA18
MFA_DATA29
MFA_DQS_H1
MFA_DQS_L5
MFB_CA5
MFB_CHECK3
MFB_DATA0
MFB_DATA12
MFB_DATA23
MFA1_RSP_L
MFA_CA5
MFA_DATA0
MFA_DATA17
MFA_DATA28
MFA_DQS_H0
MFA_DQS_L4
MFB_CA4
MFB_CHECK2
MFB_DATA11
MFB_DATA22
MFA0_RSP_L
MFA_CA4
MFA_CHECK7
MFA_DATA16
MFA_DATA27
MFA_DQS_L3
MFB_CA3
MFB_CHECK1
MFB_DATA10
MFB_DATA21
MFA_CA3
MFA_CHECK6
MFA_DATA15
MFA_DATA26
MFA_DQS_L2
MFB1_CS_L1
MFB_CA2
MFB_CHECK0
MFB_DATA20
MFB_DATA31
MFA_CA2
MFA_CHECK5
MFA_DATA14
MFA_DATA25
MFA_DQS_L1
MFB0_CS_L1
MFB1_CS_L0
MFB_CA1
MFB_DATA30
MFB_DQS_H8
MFA_CA1
MFA_CHECK4
MFA_DATA13
MFA_DATA24
MFA_DQS_L0
MFB0_CS_L0
MFB_CA0
MFB_DQS_H7
MFA_CA0
MFA_CHECK3
MFA_DATA12
MFA_DATA23
MFB_DQS_H6
MFA_CHECK2
MFA_DATA11
MFA_DATA22
MFB_DQS_H5
MFB_DQS_L9
MFA_CHECK1
MFA_DATA10
MFA_DATA21
MFB_DATA9
MFB_DQS_H4
MFB_DQS_L8
MFA1_CS_L1
MFA_CHECK0
MFA_DATA9
MFA_DATA20
MFA_DATA31
MFA_DQS_H9
MFB_DATA8
MFB_DQS_H3
MFB_DQS_L7
MFA0_CS_L1
MFA1_CS_L0
MFA_DATA8
MFA_DATA30
MFA_DQS_H8
MFB_DATA7
MFB_DATA19
MFB_DQS_H2
MFB_DQS_L6
MF_RESET_L
MF_ALERT_L
1
SHEETDATE
23
7 3 2 16 5 4
E
A
B
C
E
D
C
B
A
7 6 5 4
D
DEPARTMENT
SIZE
PROJECT DOCUMENT NUMBER REV
REVIEWER
DESIGNER
OUT
IN
OUT
OUT
OUT
OUT
IN
IN
OUT
OUT
OUT
OUT
OUT
OUT
BI
BI
BI
BI
BI
BI
BI
BI
C



Thu Aug 24 14:08:34 2023<NAME_2>
<NAME_1>
MB FABCGTI V02
16 OF 365
92
92
92
92
92
92
92
92
92
92
92
92
92
92
92
92
92
92
92
92
92
92
15 M_G _CP U0_A LE RT_R_NM_G _CP U0_A LE RT_N 1%
0402LF
S O CK E T6096_13568-001
IO
TP _M_G _CP U0_S A _TE S T39G
M_G _CP U0_S A _CA <6:0>
M_G _CP U0_S B _CA <6:0>
M_G _CP U0_CLK _DN<0>
M_G _CP U0_CLK _DP <0>
M_G _CP U0_S A _CS _N<1>
M_G _CP U0_S A _CS _N<0>
M_G _CP U0_S A _P A R
M_G _CP U0_S A _RS P <0>
M_G _CP U0_S B _RS P <0>
M_G _CP U0_S B _CS _N<0>
M_G _CP U0_S B _CS _N<1>
M_G _CP U0_S B _P A R
M_G _CP U0_RE S E T_N
M_G _CP U0_S A _DQ S _DP <9:0>
M_G _CP U0_S B _DQ S _DP <9:0>
M_G _CP U0_S B _DQ S _DN<9:0>
M_G _CP U0_S A _DQ S _DN<9:0>
M_G _CP U0_S A _CB <7:0>
M_G _CP U0_S B _CB <7:0>
M_G _CP U0_S A _DQ <31:0>
M_G _CP U0_S B _DQ <31:0>
CPU0 DDR CHG
R1955 PLACE CLOSE TO CPU < 25MM
SMLF
21R381
BF4
BL3
BW2
DC3
CU3
CL3
CE3
BW3
DC2
CU2
CL2
CE2
BV2
DD4
CV4
CM 4
CF4
BY4
DB2
CT 2
CK2
CD2
DF2
DE2
DE3
DD2
DB4
DA2
DA3
CY2
CY4
CW2
CW3
CV2
CT 4
CR2
CR3
CP2
CP4
CN2
CN3
CM 2
CK4
CJ2
CJ3
CH2
CH4
CG2
CG3
CF2
CD4
CC2
CC3
CB2
BV4
BU2
BU3
BT 2
CB4
CA2
CA3
BY2
BK2
BK4
BJ3
BJ2
BH2
BH4
BG3
BR2
BM 2
BL2
BP2
BN2
BM 4
BC3
AM 4
AF4
Y4
P4
H4
AM 2
AF2
Y2
P2
H2
AN3
AG3
AA3
R3
J3
AL2
AE2
W2
N2
G2
AJ3
AH2
AH4
AG2
AE3
AD2
AD4
AC2
AC3
AB2
AB4
AA2
W3
V2
V4
U2
U3
T 2
T 4
R2
N3
M 2
M 4
L2
L3
K2
K4
J2
G3
F2
F4
E2
AR3
AP2
AP4
AN2
AL3
AK2
AK4
AJ2
BB4
BB2
BA2
BA3
AY4
AY2
AW2
BP4
AW3
AV2
BN3
AV4
AU2
AT 2
AR2
BG2
BF2
BD2
BC2
U25
6
5
4
3
2
1
0
6
5
4
3
2
1
0
9
8
6
7
5
4
9
8
7
5
6
4
3
2
1
0
9
3
2
1
0
8
7
6
5
4
9
8
7
5
6
3
2
1
0
4
3
2
1
0
7
6
5
4
3
2
1
0
6
7
5
3
4
2
1
31
0
30
29
28
27
26
25
24
23
22
21
20
19
18
17
15
16
14
13
12
10
11
9
8
6
7
5
4
3
2
1
31
0
30
29
28
26
27
25
24
22
23
21
20
19
18
17
16
14
15
13
12
10
11
9
8
6
7
5
4
3
2
1
0
CAD NOTE:
7/40
TEST39G
MG1_CLK_L
MG1_CLK_H
MG0_CLK_L
MG0_CLK_H
MGA_PAR
MGB_DQS_H9
MGB_PAR
MGA_CHECK1
MGA_DATA0
MGA_DATA10
MGA_DATA21
MGB_DATA0
MGB_DQS_H4
MGB_DQS_L8
MGA_CHECK0
MGA_DATA20
MGA_DATA31
MGA_DQS_H9
MGB_DQS_H3
MGB_DQS_L7
MGA0_CS_L1
MGA1_CS_L1
MGA_DATA30
MGA_DQS_H8
MGB_DATA19
MGB_DQS_H2
MGB_DQS_L6
MGA0_CS_L0
MGA1_CS_L0
MGA_DQS_H7
MGB_DATA18
MGB_DATA29
MGB_DQS_H1
MGB_DQS_L5
MGA_DQS_H6
MGB_DATA17
MGB_DATA28
MGB_DQS_H0
MGB_DQS_L4
MGA_DQS_H5
MGA_DQS_L9
MGB0_RSP_L
MGB1_RSP_L
MGB_CHECK7
MGB_DATA16
MGB_DATA27
MGB_DQS_L3
MGA_DQS_H4
MGA_DQS_L8
MGB_CA6
MGB_CHECK6
MGB_DATA15
MGB_DATA26
MGB_DQS_L2
MGA_CA6
MGA_DQS_H3
MGA_DQS_L7
MGB_CA5
MGB_CHECK5
MGB_DATA14
MGB_DATA25
MGB_DQS_L1
MGA_CA5
MGA_DATA9
MGA_DATA19
MGA_DQS_H2
MGA_DQS_L6
MGB_CA4
MGB_CHECK4
MGB_DATA9
MGB_DATA13
MGB_DATA24
MGB_DQS_L0
MGA_CA4
MGA_DATA8
MGA_DATA18
MGA_DATA29
MGA_DQS_H1
MGA_DQS_L5
MGB_CA3
MGB_CHECK3
MGB_DATA8
MGB_DATA12
MGB_DATA23
MGA_CA3
MGA_DATA7
MGA_DATA17
MGA_DATA28
MGA_DQS_H0
MGA_DQS_L4
MGB_CA2
MGB_CHECK2
MGB_DATA7
MGB_DATA11
MGB_DATA22
MGA0_RSP_L
MGA1_RSP_L
MGA_CA2
MGA_CHECK7
MGA_DATA6
MGA_DATA16
MGA_DATA27
MGA_DQS_L3
MGB_CA1
MGB_CHECK1
MGB_DATA6
MGB_DATA10
MGB_DATA21
MGA_CA1
MGA_CHECK6
MGA_DATA5
MGA_DATA15
MGA_DATA26
MGA_DQS_L2
MGB_CA0
MGB_CHECK0
MGB_DATA5
MGB_DATA20
MGB_DATA31
MGA_CA0
MGA_CHECK5
MGA_DATA4
MGA_DATA14
MGA_DATA25
MGA_DQS_L1
MGB0_CS_L1
MGB1_CS_L1
MGB_DATA4
MGB_DATA30
MGB_DQS_H8
MGA_CHECK4
MGA_DATA3
MGA_DATA13
MGA_DATA24
MGA_DQS_L0
MGB0_CS_L0
MGB1_CS_L0
MGB_DATA3
MGB_DQS_H7
MGA_CHECK3
MGA_DATA2
MGA_DATA12
MGA_DATA23
MGB_DATA2
MGB_DQS_H6
MGA_CHECK2
MGA_DATA1
MGA_DATA11
MGA_DATA22
MGB_DATA1
MGB_DQS_H5
MGB_DQS_L9
MG_RESET_L
MG_ALERT_L
1
SHEETDATE
23
7 3 2 16 5 4
E
A
B
C
E
D
C
B
A
7 6 5 4
D
DEPARTMENT
SIZE
PROJECT DOCUMENT NUMBER REV
REVIEWER
DESIGNER
IN
OUT
OUT
OUT
OUT
IN
IN
OUT
OUT
OUT
OUT
OUT
OUT
OUT
BI
BI
BI
BI
BI
BI
BI
BI
C



Thu Aug 24 14:08:34 2023<NAME_2>
<NAME_1>
MB FABCGTI V02
17 OF 365
93
93
93
93
93
93
93
93
93
93
93
93
93
93
93
93
93
93
93
93
93
93
15 M_H_CP U0_A LE RT_R_NM_H_CP U0_A LE RT_N 1%
0402LF
S O CK E T6096_13568-001
IO
TP _M_H_CP U0_S A _TE S T39H
M_H_CP U0_S A _CA <6:0>
M_H_CP U0_S B _CA <6:0>
M_H_CP U0_CLK _DP <0>
M_H_CP U0_CLK _DN<0>
M_H_CP U0_S A _CS _N<0>
M_H_CP U0_S A _CS _N<1>
M_H_CP U0_S A _RS P <0>
M_H_CP U0_S A _P A R
M_H_CP U0_S B _CS _N<1>
M_H_CP U0_S B _CS _N<0>
M_H_CP U0_S B _RS P <0>
M_H_CP U0_S B _P A R
M_H_CP U0_RE S E T_N
M_H_CP U0_S A _DQ S _DP <9:0>
M_H_CP U0_S B _DQ S _DP <9:0>
M_H_CP U0_S B _DQ S _DN<9:0>
M_H_CP U0_S A _DQ S _DN<9:0>
M_H_CP U0_S B _CB <7:0>
M_H_CP U0_S A _CB <7:0>
M_H_CP U0_S A _DQ <31:0>
M_H_CP U0_S B _DQ <31:0>
R1947 PLACE CLOSE TO CPU < 25MM
CPU0 DDR CHH
SMLF
21R382
BF14
BL14
BW12
DC14
CU14
CL14
CE14
BW14
DC12
CU12
CL12
CE12
BV13
DD14
CV14
CM 14
CF14
BY14
DB13
CT 13
CK13
CD13
DF14
DE12
DE14
DD13
DB14
DA12
DA14
CY13
CY14
CW12
CW14
CV13
CT 14
CR12
CR14
CP13
CP14
CN12
CN14
CM 13
CK14
CJ12
CJ14
CH13
CH14
CG12
CG14
CF13
CD14
CC12
CC14
CB13
BV14
BU12
BU14
BT 13
CB14
CA12
CA14
BY13
BK13
BK14
BJ14
BJ12
BH13
BH14
BG14
BR12
BM 13
BL12
BP13
BN12
BM 14
BC14
AM 14
AF14
Y14
P14
H14
AM 13
AF13
Y13
P13
H13
AN14
AG14
AA14
R14
J14
AL12
AE12
W12
N12
G12
AJ14
AH13
AH14
AG12
AE14
AD13
AD14
AC12
AC14
AB13
AB14
AA12
W14
V13
V14
U12
U14
T 13
T 14
R12
N14
M 13
M 14
L12
L14
K13
K14
J12
G14
F13
F14
E12
AR14
AP13
AP14
AN12
AL14
AK13
AK14
AJ12
BB14
BB13
BA12
BA14
AY14
AY13
AW12
BP14
AW14
AV13
BN14
AV14
AU12
AU14
AT 14
BG12
BF13
BD13
BC12
U25
5
6
4
3
1
0
2
6
5
4
3
2
1
0
9
8
9
7
6
5
4
3
8
7
6
5
4
2
1
0
9
3
2
1
0
9
7
8
6
5
4
8
7
6
3
5
4
2
1
0
3
1
2
0
6
7
5
4
3
2
7
0
1
4
5
6
2
3
31
30
1
0
26
25
29
28
27
24
21
23
22
17
16
20
19
18
11
12
13
14
15
10
7
8
9
5
6
4
3
2
30
31
1
0
26
25
29
28
27
21
22
23
24
16
17
20
19
18
11
12
13
15
14
9
7
8
10
5
6
4
3
2
1
0
CAD NOTE:
8/40
TEST39H
MH1_CLK_L
MH1_CLK_H
MH0_CLK_L
MH0_CLK_H
MHB_PAR
MHA_PAR
MHB_DQS_H9
MHA_CHECK5
MHA_DATA14
MHA_DATA25
MHA_DQS_L1
MHB0_CS_L1
MHB1_CS_L0
MHB_DATA30
MHB_DQS_H8
MHA_CHECK4
MHA_DATA13
MHA_DATA24
MHA_DQS_L0
MHB0_CS_L0
MHB_DQS_H7
MHA_CHECK3
MHA_DATA9
MHA_DATA12
MHA_DATA23
MHB_DATA9
MHB_DQS_H6
MHA_CHECK2
MHA_DATA8
MHA_DATA11
MHA_DATA22
MHB_DATA8
MHB_DQS_H5
MHB_DQS_L9
MHA_CHECK1
MHA_DATA7
MHA_DATA10
MHA_DATA21
MHB_DATA7
MHB_DQS_H4
MHB_DQS_L8
MHA1_CS_L1
MHA_CHECK0
MHA_DATA6
MHA_DATA20
MHA_DATA31
MHA_DQS_H9
MHB_DATA6
MHB_DQS_H3
MHB_DQS_L7
MHA0_CS_L1
MHA1_CS_L0
MHA_DATA5
MHA_DATA30
MHA_DQS_H8
MHB_DATA5
MHB_DATA19
MHB_DQS_H2
MHB_DQS_L6
MHA0_CS_L0
MHA_DATA4
MHA_DQS_H7
MHB_CA6
MHB_DATA4
MHB_DATA18
MHB_DATA29
MHB_DQS_H1
MHB_DQS_L5
MHA_CA6
MHA_DATA3
MHA_DQS_H6
MHB1_RSP_L
MHB_CA5
MHB_DATA3
MHB_DATA17
MHB_DATA28
MHB_DQS_H0
MHB_DQS_L4
MHA_CA5
MHA_DATA2
MHA_DQS_H5
MHA_DQS_L9
MHB0_RSP_L
MHB_CA4
MHB_CHECK7
MHB_DATA2
MHB_DATA16
MHB_DATA27
MHB_DQS_L3
MHA_CA4
MHA_DATA1
MHA_DQS_H4
MHA_DQS_L8
MHB_CA3
MHB_CHECK6
MHB_DATA1
MHB_DATA15
MHB_DATA26
MHB_DQS_L2
MHA_CA3
MHA_DATA0
MHA_DQS_H3
MHA_DQS_L7
MHB_CA2
MHB_CHECK5
MHB_DATA0
MHB_DATA14
MHB_DATA25
MHB_DQS_L1
MHA_CA2
MHA_DATA19
MHA_DQS_H2
MHA_DQS_L6
MHB_CA1
MHB_CHECK4
MHB_DATA13
MHB_DATA24
MHB_DQS_L0
MHA_CA1
MHA_DATA18
MHA_DATA29
MHA_DQS_H1
MHA_DQS_L5
MHB_CA0
MHB_CHECK3
MHB_DATA12
MHB_DATA23
MHA1_RSP_L
MHA_CA0
MHA_DATA17
MHA_DATA28
MHA_DQS_H0
MHA_DQS_L4
MHB_CHECK2
MHB_DATA11
MHB_DATA22
MHA0_RSP_L
MHA_CHECK7
MHA_DATA16
MHA_DATA27
MHA_DQS_L3
MHB_CHECK1
MHB_DATA10
MHB_DATA21
MHA_CHECK6
MHA_DATA15
MHA_DATA26
MHA_DQS_L2
MHB1_CS_L1
MHB_CHECK0
MHB_DATA20
MHB_DATA31
MH_RESET_L
MH_ALERT_L
1
SHEETDATE
23
7 3 2 16 5 4
E
A
B
C
E
D
C
B
A
7 6 5 4
D
DEPARTMENT
SIZE
PROJECT DOCUMENT NUMBER REV
REVIEWER
DESIGNER
OUT
IN
OUT
IN
OUT
OUT
OUT
IN
OUT
OUT
OUT
OUT
OUT
OUT
BI
BI
BI
BI
BI
BI
BI
BI
C



Thu Aug 24 14:08:35 2023<NAME_2>
<NAME_1>
MB FABCGTI V02
18 OF 365
94
94
94
94
94
94
94
94
94
94
94
94
94
94
94
94
94
94
94
94
94
94
15 M_I_CP U0_A LE RT_R_NM_I_CP U0_A LE RT_N 1%
0402LF
S O CK E T6096_13568-001
IO
TP _M_I_CP U0_S A _TE S T39I
M_I_CP U0_S A _CA <6:0>
M_I_CP U0_S B _CA <6:0>
M_I_CP U0_CLK _DP <0>
M_I_CP U0_CLK _DN<0>
M_I_CP U0_S A _CS _N<0>
M_I_CP U0_S A _CS _N<1>
M_I_CP U0_S A _RS P <0>
M_I_CP U0_S A _P A R
M_I_CP U0_S B _CS _N<0>
M_I_CP U0_S B _CS _N<1>
M_I_CP U0_S B _RS P <0>
M_I_CP U0_S B _P A R
M_I_CP U0_RE S E T_N
M_I_CP U0_S A _DQ S _DP <9:0>
M_I_CP U0_S B _DQ S _DP <9:0>
M_I_CP U0_S B _DQ S _DN<9:0>
M_I_CP U0_S A _DQ S _DN<9:0>
M_I_CP U0_S B _CB <7:0>
M_I_CP U0_S A _CB <7:0>
M_I_CP U0_S A _DQ <31:0>
M_I_CP U0_S B _DQ <31:0>
R1948 PLACE CLOSE TO CPU < 25MM
CPU0 DDR CHI
SMLF
21R383
BF21
BL21
BW19
DC21
CU21
CL21
CE21
BW21
DC19
CU19
CL19
CE19
BV20
DD21
CV21
CM 21
CF21
BY21
DB20
CT 20
CK20
CD20
DF21
DE19
DE21
DD20
DB21
DA19
DA21
CY20
CY21
CW19
CW21
CV20
CT 21
CR19
CR21
CP20
CP21
CN19
CN21
CM 20
CK21
CJ19
CJ21
CH20
CH21
CG19
CG21
CF20
CD21
CC19
CC21
CB20
BV21
BU19
BU21
BT 20
CB21
CA19
CA21
BY20
BK20
BK21
BJ21
BJ19
BH20
BH21
BG21
BR19
BM 20
BL19
BP20
BN19
BM 21
BC21
AM 21
AF21
Y21
P21
H21
AM 20
AF20
Y20
P20
H20
AN21
AG21
AA21
R21
J21
AL19
AE19
W19
N19
G19
AJ21
AH20
AH21
AG19
AE21
AD20
AD21
AC19
AC21
AB20
AB21
AA19
W21
V20
V21
U19
U21
T 20
T 21
R19
N21
M 20
M 21
L19
L21
K20
K21
J19
G21
F20
F21
E19
AR21
AP20
AP21
AN19
AL21
AK20
AK21
AJ19
BB21
BB20
BA19
BA21
AY21
AY20
AW19
BP21
AW21
AV20
BN21
AV21
AU19
AU21
AT 21
BG19
BF20
BD20
BC19
U25
5
6
4
3
2
0
1
5
6
3
4
2
1
0
9
8
9
7
6
4
5
3
2
1
9
0
8
7
6
5
4
3
2
1
0
9
8
7
6
5
3
4
2
1
0
8
7
6
5
4
3
2
1
0
6
7
5
4
3
1
2
7
0
4
5
6
2
3
0
1
31
30
27
28
29
26
25
24
23
21
22
20
19
18
17
16
14
15
13
12
11
10
9
8
7
6
5
3
2
4
1
0
31
30
27
28
29
25
26
24
23
21
22
18
19
20
17
16
15
14
11
12
13
9
10
7
8
5
6
2
3
4
1
0
CAD NOTE:
9/40
TEST39I
MIA_DATA5
MIA_DATA17
MIA_DATA28
MIA_DQS_H0
MIA_DQS_L4
MIB_CHECK2
MIB_DATA5
MIB_DATA11
MIB_DATA22
MI_ALERT_L
MIA0_RSP_L
MIA1_RSP_L
MIA_CHECK7
MIA_DATA4
MIA_DATA16
MIA_DATA27
MIA_DQS_L3
MIB_CHECK1
MIB_DATA4
MIB_DATA10
MIB_DATA21
MIB_PAR
MIA_CHECK6
MIA_DATA3
MIA_DATA15
MIA_DATA26
MIA_DQS_L2
MIA_PAR
MIB1_CS_L1
MIB_CHECK0
MIB_DATA3
MIB_DATA20
MIB_DATA31
MIB_DQS_H9
MIA_CHECK5
MIA_DATA2
MIA_DATA14
MIA_DATA25
MIA_DQS_L1
MIB0_CS_L1
MIB1_CS_L0
MIB_DATA2
MIB_DATA30
MIB_DQS_H8
MIA_CHECK4
MIA_DATA1
MIA_DATA13
MIA_DATA24
MIA_DQS_L0
MIB0_CS_L0
MIB_DATA1
MIB_DQS_H7
MIA_CHECK3
MIA_DATA0
MIA_DATA12
MIA_DATA23
MIB_DATA0
MIB_DQS_H6
MI_RESET_L
MI0_CLK_L
MI1_CLK_L
MIA_CHECK2
MIA_DATA11
MIA_DATA22
MIB_DQS_H5
MIB_DQS_L9
MIA_CHECK1
MIA_DATA10
MIA_DATA21
MIB_DQS_H4
MIB_DQS_L8
MIA_CHECK0
MIA_DATA20
MIA_DATA31
MIA_DQS_H9
MIB_CA6
MIB_DQS_H3
MIB_DQS_L7
MIA0_CS_L1
MIA1_CS_L1
MIA_CA6
MIA_DATA30
MIA_DQS_H8
MIB_CA5
MIB_DATA19
MIB_DQS_H2
MIB_DQS_L6
MI0_CLK_H
MI1_CLK_H
MIA0_CS_L0
MIA1_CS_L0
MIA_CA5
MIA_DQS_H7
MIB_CA4
MIB_DATA18
MIB_DATA29
MIB_DQS_H1
MIB_DQS_L5
MIA_CA4
MIA_DQS_H6
MIB1_RSP_L
MIB_CA3
MIB_DATA17
MIB_DATA28
MIB_DQS_H0
MIB_DQS_L4
MIA_CA3
MIA_DQS_H5
MIA_DQS_L9
MIB0_RSP_L
MIB_CA2
MIB_CHECK7
MIB_DATA16
MIB_DATA27
MIB_DQS_L3
MIA_CA2
MIA_DATA9
MIA_DQS_H4
MIA_DQS_L8
MIB_CA1
MIB_CHECK6
MIB_DATA9
MIB_DATA15
MIB_DATA26
MIB_DQS_L2
MIA_CA1
MIA_DATA8
MIA_DQS_H3
MIA_DQS_L7
MIB_CA0
MIB_CHECK5
MIB_DATA8
MIB_DATA14
MIB_DATA25
MIB_DQS_L1
MIA_CA0
MIA_DATA7
MIA_DATA19
MIA_DQS_H2
MIA_DQS_L6
MIB_CHECK4
MIB_DATA7
MIB_DATA13
MIB_DATA24
MIB_DQS_L0
MIA_DATA6
MIA_DATA18
MIA_DATA29
MIA_DQS_H1
MIA_DQS_L5
MIB_CHECK3
MIB_DATA6
MIB_DATA12
MIB_DATA23
1
SHEETDATE
23
7 3 2 16 5 4
E
A
B
C
E
D
C
B
A
7 6 5 4
D
DEPARTMENT
SIZE
PROJECT DOCUMENT NUMBER REV
REVIEWER
DESIGNER
OUT
IN
OUT
IN
OUT
OUT
OUT
IN
OUT
OUT
OUT
OUT
OUT
OUT
BI
BI
BI
BI
BI
BI
BI
BI
C



Thu Aug 24 14:08:35 2023<NAME_2>
<NAME_1>
MB FABCGTI V02
19 OF 365
95
95
95
95
95
95
95
95
95
95
95
95
95
95
95
95
95
95
95
95
95
95
15 M_J_CP U0_A LE RT_R_NM_J_CP U0_A LE RT_N 1%
0402LF
S O CK E T6096_13568-001
IO
TP _M_J_CP U0_S A _TE S T39J
M_J_CP U0_S A _CA <6:0>
M_J_CP U0_S B _CA <6:0>
M_J_CP U0_CLK _DP <0>
M_J_CP U0_CLK _DN<0>
M_J_CP U0_S A _CS _N<0>
M_J_CP U0_S A _P A R
M_J_CP U0_S A _CS _N<1>
M_J_CP U0_S A _RS P <0>
M_J_CP U0_S B _CS _N<0>
M_J_CP U0_S B _CS _N<1>
M_J_CP U0_S B _RS P <0>
M_J_CP U0_S B _P A R
M_J_CP U0_RE S E T_N
M_J_CP U0_S A _DQ S _DP <9:0>
M_J_CP U0_S B _DQ S _DP <9:0>
M_J_CP U0_S B _DQ S _DN<9:0>
M_J_CP U0_S A _DQ S _DN<9:0>
M_J_CP U0_S B _CB <7:0>
M_J_CP U0_S A _CB <7:0>
M_J_CP U0_S A _DQ <31:0>
M_J_CP U0_S B _DQ <31:0>
R1949 PLACE CLOSE TO CPU < 25MM
CPU0 DDR CHJ
SMLF
21R384
BF18
BL17
BW16
DC17
CU17
CL17
CE17
BW17
DC16
CU16
CL16
CE16
BV16
DD18
CV18
CM 18
CF18
BY18
DB16
CT 16
CK16
CD16
DF16
DE16
DE17
DD16
DB18
DA16
DA17
CY16
CY18
CW16
CW17
CV16
CT 18
CR16
CR17
CP16
CP18
CN16
CN17
CM 16
CK18
CJ16
CJ17
CH16
CH18
CG16
CG17
CF16
CD18
CC16
CC17
CB16
BV18
BU16
BU17
BT 16
CB18
CA16
CA17
BY16
BK16
BK18
BJ17
BJ16
BH16
BH18
BG17
BR16
BM 16
BL16
BP16
BN16
BM 18
BC17
AM 18
AF18
Y18
P18
H18
AM 16
AF16
Y16
P16
H16
AN17
AG17
AA17
R17
J17
AL16
AE16
W16
N16
G16
AJ17
AH16
AH18
AG16
AE17
AD16
AD18
AC16
AC17
AB16
AB18
AA16
W17
V16
V18
U16
U17
T 16
T 18
R16
N17
M 16
M 18
L16
L17
K16
K18
J16
G17
F16
F18
E16
AR17
AP16
AP18
AN16
AL17
AK16
AK18
AJ16
BB18
BB16
BA16
BA17
AY18
AY16
AW16
BP18
AW17
AV16
BN17
AV18
AU16
AU17
AT 18
BG16
BF16
BD16
BC16
U25
3
4
6
5
6
0
2
1
5
4
1
2
3
9
0
9
6
7
8
4
5
8
7
6
3
5
4
2
1
9
0
3
2
1
9
0
7
6
8
4
5
8
7
6
5
4
1
2
3
0
3
2
0
1
7
6
5
4
2
1
3
0
7
5
6
4
3
2
1
0
31
30
29
28
27
26
25
24
21
22
23
19
20
18
16
17
14
15
12
13
11
10
9
8
5
6
7
4
3
2
1
0
30
31
29
28
25
26
27
24
23
21
22
20
19
17
16
18
15
14
13
12
11
10
9
8
7
5
6
4
3
1
0
2
CAD NOTE:
10/40
TEST39J
MJB_DATA7
MJB_DATA6
MJB_DATA5
MJB_DQS_H5
MJB_DQS_L4
MJB_DQS_L0
MJA_DATA31
MJB_DATA0
MJB_DATA3
MJB_DATA4
MJA_DQS_H4
MJA_DQS_H8
MJA_DQS_L4
MJA_DQS_L5
MJA_DQS_L7
MJA_DATA22
MJA_CA5
MJA_CA6
MJ0_CLK_H
MJ0_CLK_L
MJ1_CLK_H
MJ1_CLK_L
MJA0_CS_L0
MJA0_CS_L1
MJA0_RSP_L
MJA1_CS_L0
MJA1_CS_L1
MJA1_RSP_L
MJA_CA0
MJA_CA1
MJA_CA2
MJA_CA3
MJA_CA4
MJA_CHECK0
MJA_CHECK1
MJA_CHECK2
MJA_CHECK3
MJA_CHECK4
MJA_CHECK5
MJA_CHECK6
MJA_CHECK7
MJA_DATA0
MJA_DATA1
MJA_DATA2
MJA_DATA3
MJA_DATA4
MJA_DATA5
MJA_DATA6
MJA_DATA7
MJA_DATA8
MJA_DATA9
MJA_DATA10
MJA_DATA11
MJA_DATA12
MJA_DATA13
MJA_DATA14
MJA_DATA15
MJA_DATA16
MJA_DATA17
MJA_DATA18
MJA_DATA19
MJA_DATA20
MJA_DATA21
MJA_DATA23
MJA_DATA24
MJA_DATA25
MJA_DATA26
MJA_DATA27
MJA_DATA28
MJA_DATA29
MJA_DATA30
MJA_DQS_H0
MJA_DQS_H1
MJA_DQS_H2
MJA_DQS_H3
MJA_DQS_H5
MJA_DQS_H6
MJA_DQS_H7
MJA_DQS_H9
MJA_DQS_L0
MJA_DQS_L1
MJA_DQS_L2
MJA_DQS_L3
MJA_DQS_L6
MJA_DQS_L8
MJA_DQS_L9
MJA_PAR
MJB0_CS_L0
MJB0_CS_L1
MJB0_RSP_L
MJB1_CS_L0
MJB1_CS_L1
MJB1_RSP_L
MJB_CA0
MJB_CA1
MJB_CA2
MJB_CA3
MJB_CA4
MJB_CA5
MJB_CA6
MJB_CHECK0
MJB_CHECK1
MJB_CHECK2
MJB_CHECK3
MJB_CHECK4
MJB_CHECK5
MJB_CHECK6
MJB_CHECK7
MJB_DATA1
MJB_DATA2
MJB_DATA8
MJB_DATA9
MJB_DATA10
MJB_DATA11
MJB_DATA12
MJB_DATA13
MJB_DATA14
MJB_DATA15
MJB_DATA16
MJB_DATA17
MJB_DATA18
MJB_DATA19
MJB_DATA20
MJB_DATA21
MJB_DATA22
MJB_DATA23
MJB_DATA24
MJB_DATA25
MJB_DATA26
MJB_DATA27
MJB_DATA28
MJB_DATA29
MJB_DATA30
MJB_DATA31
MJB_DQS_H0
MJB_DQS_H1
MJB_DQS_H2
MJB_DQS_H3
MJB_DQS_H4
MJB_DQS_H6
MJB_DQS_H7
MJB_DQS_H8
MJB_DQS_H9
MJB_DQS_L1
MJB_DQS_L2
MJB_DQS_L3
MJB_DQS_L5
MJB_DQS_L6
MJB_DQS_L7
MJB_DQS_L8
MJB_DQS_L9
MJB_PAR
MJ_ALERT_L
MJ_RESET_L
1
SHEETDATE
23
7 3 2 16 5 4
E
A
B
C
E
D
C
B
A
7 6 5 4
D
DEPARTMENT
SIZE
PROJECT DOCUMENT NUMBER REV
REVIEWER
DESIGNER
OUT
IN
OUT
IN
OUT
OUT
IN
OUT
OUT
OUT
OUT
OUT
OUT
OUT
BI
BI
BI
BI
BI
BI
BI
BI
C



Thu Aug 24 14:08:35 2023<NAME_2>
<NAME_1>
MB FABCGTI V02
20 OF 365
96
96
96
96
96
96
96
96
96
96
96
96
96
96
96
96
96
96
96
96
96
96
15 M_K _CP U0_A LE RT_R_NM_K _CP U0_A LE RT_N 1%
0402LF
S O CK E T6096_13568-001
IO
TP _M_K _CP U0_S A _TE S T39K
M_K _CP U0_S A _CA <6:0>
M_K _CP U0_S B _CA <6:0>
M_K _CP U0_CLK _DP <0>
M_K _CP U0_CLK _DN<0>
M_K _CP U0_S A _CS _N<0>
M_K _CP U0_S A _RS P <0>
M_K _CP U0_S A _CS _N<1>
M_K _CP U0_S A _P A R
M_K _CP U0_S B _CS _N<0>
M_K _CP U0_S B _CS _N<1>
M_K _CP U0_S B _RS P <0>
M_K _CP U0_S B _P A R
M_K _CP U0_RE S E T_N
M_K _CP U0_S A _DQ S _DP <9:0>
M_K _CP U0_S B _DQ S _DP <9:0>
M_K _CP U0_S B _DQ S _DN<9:0>
M_K _CP U0_S A _DQ S _DN<9:0>
M_K _CP U0_S B _CB <7:0>
M_K _CP U0_S A _CB <7:0>
M_K _CP U0_S A _DQ <31:0>
M_K _CP U0_S B _DQ <31:0>
CPU0 DDR CHK
R1950 PLACE CLOSE TO CPU < 25MM
SMLF
21R385
BF7
BL7
BW5
DC7
CU7
CL7
CE7
BW7
DC5
CU5
CL5
CE5
BV6
DD7
CV7
CM 7
CF7
BY7
DB6
CT 6
CK6
CD6
DF7
DE5
DE7
DD6
DB7
DA5
DA7
CY6
CY7
CW5
CW7
CV6
CT 7
CR5
CR7
CP6
CP7
CN5
CN7
CM 6
CK7
CJ5
CJ7
CH6
CH7
CG5
CG7
CF6
CD7
CC5
CC7
CB6
BV7
BU5
BU7
BT 6
CB7
CA5
CA7
BY6
BK6
BK7
BJ7
BJ5
BH6
BH7
BG7
BR5
BM 6
BL5
BP6
BN5
BM 7
BC7
AM 7
AF7
Y7
P7
H7
AM 6
AF6
Y6
P6
H6
AN7
AG7
AA7
R7
J7
AL5
AE5
W5
N5
G5
AJ7
AH6
AH7
AG5
AE7
AD6
AD7
AC5
AC7
AB6
AB7
AA5
W7
V6
V7
U5
U7
T 6
T 7
R5
N7
M 6
M 7
L5
L7
K6
K7
J5
G7
F6
F7
E5
AR7
AP6
AP7
AN5
AL7
AK6
AK7
AJ5
BB7
BB6
BA5
BA7
AY7
AY6
AW5
BP7
AW7
AV6
BN7
AV7
AU5
AU7
AT 7
BG5
BF6
BD6
BC5
U25
5
6
4
3
2
1
0
5
6
4
3
2
1
0
9
8
9
7
5
6
4
3
2
1
0
9
8
8
6
7
4
5
3
2
1
9
0
7
6
4
5
3
2
1
0
8
6
7
4
5
3
2
1
0
5
6
7
4
3
0
1
2
7
5
4
6
3
2
1
0
31
30
29
27
28
26
25
24
23
22
20
21
18
19
17
16
13
15
14
11
12
8
9
10
7
4
6
5
3
2
0
1
30
31
29
27
28
26
24
25
23
21
22
20
18
19
16
17
14
15
12
11
13
8
9
10
7
4
6
5
3
2
1
0
CAD NOTE:
36/40
TEST39K
MKA0_CS_L0
MKA_CA0
MKA_DQS_H7
MKB_DATA9
MKB_DATA18
MKB_DATA29
MKB_DQS_H1
MKB_DQS_L5
MKA_DATA9
MKA_DQS_H6
MKB1_RSP_L
MKB_DATA8
MKB_DATA17
MKB_DATA28
MKB_DQS_H0
MKB_DQS_L4
MKA_DATA8
MKA_DQS_H5
MKA_DQS_L9
MKB0_RSP_L
MKB_CHECK7
MKB_DATA7
MKB_DATA16
MKB_DATA27
MKB_DQS_L3
MKA_DATA7
MKA_DQS_H4
MKA_DQS_L8
MKB_CHECK6
MKB_DATA6
MKB_DATA15
MKB_DATA26
MKB_DQS_L2
MKB_PAR
MKA_DATA6MKA_DQS_H3
MKA_DQS_L7
MKA_PAR
MKB_CHECK5
MKB_DATA5
MKB_DATA14
MKB_DATA25
MKB_DQS_L1
MKA_DATA5
MKA_DATA19
MKA_DQS_H2
MKA_DQS_L6
MKB_CHECK4
MKB_DATA4
MKB_DATA13
MKB_DATA24
MKB_DQS_L0
MKA_DATA4
MKA_DATA18
MKA_DATA29
MKA_DQS_H1
MKA_DQS_L5
MKB_CHECK3
MKB_DATA3
MKB_DATA12
MKB_DATA23
MKA1_RSP_L
MKA_DATA3
MKA_DATA17
MKA_DATA28
MKA_DQS_H0
MKA_DQS_L4
MKB_CHECK2
MKB_DATA2
MKB_DATA11
MKB_DATA22
MK_ALERT_L
MKA0_RSP_L
MKA_CHECK7
MKA_DATA2
MKA_DATA16
MKA_DATA27
MKA_DQS_L3
MKB_CHECK1
MKB_DATA1
MKB_DATA10
MKB_DATA21
MKA_CHECK6
MKA_DATA1
MKA_DATA15
MKA_DATA26
MKA_DQS_L2
MKB1_CS_L1
MKB_CHECK0
MKB_DATA0
MKB_DATA20
MKB_DATA31
MKB_DQS_H9
MK1_CLK_L
MKA_CHECK5
MKA_DATA0
MKA_DATA14
MKA_DATA25
MKA_DQS_L1
MKB0_CS_L1
MKB1_CS_L0
MKB_CA6
MKB_DATA30
MKB_DQS_H8
MK0_CLK_L
MKA_CA6
MKA_CHECK4
MKA_DATA13
MKA_DATA24
MKA_DQS_L0
MKB0_CS_L0
MKB_CA5
MKB_DQS_H7
MKA_CA5
MKA_CHECK3
MKA_DATA12
MKA_DATA23
MKB_CA4
MKB_DQS_H6
MK_RESET_L
MKA_CA4
MKA_CHECK2
MKA_DATA11
MKA_DATA22
MKB_CA3
MKB_DQS_H5
MKB_DQS_L9
MK1_CLK_H
MKA_CA3
MKA_CHECK1
MKA_DATA10
MKA_DATA21
MKB_CA2
MKB_DQS_H4
MKB_DQS_L8
MK0_CLK_H
MKA1_CS_L1
MKA_CA2
MKA_CHECK0
MKA_DATA20
MKA_DATA31
MKA_DQS_H9
MKB_CA1
MKB_DQS_H3
MKB_DQS_L7
MKA0_CS_L1
MKA1_CS_L0
MKA_CA1
MKA_DATA30
MKA_DQS_H8
MKB_CA0
MKB_DATA19
MKB_DQS_H2
MKB_DQS_L6
1
SHEETDATE
23
7 3 2 16 5 4
E
A
B
C
E
D
C
B
A
7 6 5 4
D
DEPARTMENT
SIZE
PROJECT DOCUMENT NUMBER REV
REVIEWER
DESIGNER
OUT
IN
OUT
IN
OUT
OUT
OUT
OUT
IN
OUT
OUT
OUT
OUT
OUT
BI
BI
BI
BI
BI
BI
BI
BI
C



Thu Aug 24 14:08:36 2023<NAME_2>
<NAME_1>
MB FABCGTI V02
21 OF 365
97
97
97
97
97
97
97
97
97
97
97
97
97
97
97
97
97
97
97
97
97
97
15 M_L_CP U0_A LE RT_R_NM_L_CP U0_A LE RT_N 1%
0402LF
R1982 PLACE CLOSE TO CPU < 25MM
S O CK E T6096_13568-001
IO
TP _M_L_CP U0_S A _TE S T39L
M_L_CP U0_S A _CA <6:0>
M_L_CP U0_S B _CA <6:0>
M_L_CP U0_CLK _DP <0>
M_L_CP U0_CLK _DN<0>
M_L_CP U0_S A _CS _N<0>
M_L_CP U0_S A _P A R
M_L_CP U0_S A _RS P <0>
M_L_CP U0_S A _CS _N<1>
M_L_CP U0_S B _CS _N<0>
M_L_CP U0_S B _CS _N<1>
M_L_CP U0_S B _RS P <0>
M_L_CP U0_S B _P A R
M_L_CP U0_RE S E T_N
M_L_CP U0_S A _DQ S _DP <9:0>
M_L_CP U0_S B _DQ S _DP <9:0>
M_L_CP U0_S B _DQ S _DN<9:0>
M_L_CP U0_S A _DQ S _DN<9:0>
M_L_CP U0_S B _CB <7:0>
M_L_CP U0_S A _CB <7:0>
M_L_CP U0_S A _DQ <31:0>
M_L_CP U0_S B _DQ <31:0>
CPU0 DDR CHL
SMLF
21R386
BF11
BL10
BW9
DC10
CU10
CL10
CE10
BW10
DC9
CU9
CL9
CE9
BV9
DD11
CV11
CM 11
CF11
BY11
DB9
CT 9
CK9
CD9
DF9
DE9
DE10
DD9
DB11
DA9
DA10
CY9
CY11
CW9
CW10
CV9
CT 11
CR9
CR10
CP9
CP11
CN9
CN10
CM 9
CK11
CJ9
CJ10
CH9
CH11
CG9
CG10
CF9
CD11
CC9
CC10
CB9
BV11
BU9
BU10
BT 9
CB11
CA9
CA10
BY9
BK9
BK11
BJ10
BJ9
BH9
BH11
BG10
BR9
BM 9
BL9
BP9
BN9
BM 11
BC10
AM 11
AF11
Y11
P11
H11
AM 9
AF9
Y9
P9
H9
AN10
AG10
AA10
R10
J10
AL9
AE9
W9
N9
G9
AJ10
AH9
AH11
AG9
AE10
AD9
AD11
AC9
AC10
AB9
AB11
AA9
W10
V9
V11
U9
U10
T 9
T 11
R9
N10
M 9
M 11
L9
L10
K9
K11
J9
G10
F9
F11
E9
AR10
AP9
AP11
AN9
AL10
AK9
AK11
AJ9
BB11
BB9
BA9
BA10
AY11
AY9
AW9
BP11
AW10
AV9
BN10
AV11
AU9
AU10
AT 11
BG9
BF9
BD9
BC9
U25
6
4
3
5
1
0
6
2
5
4
3
1
2
0
9
9
8
7
6
5
4
3
2
1
9
0
8
7
6
5
4
3
2
1
0
9
8
7
6
4
5
3
2
1
0
8
7
5
6
4
3
2
1
0
5
6
7
4
3
0
1
2
7
5
6
4
3
2
1
0
30
31
29
28
27
26
25
23
22
21
24
20
19
18
17
16
13
15
14
12
11
8
9
10
7
6
5
4
3
2
0
1
30
31
29
28
27
25
26
24
23
21
22
20
19
18
17
16
14
15
12
13
11
8
9
10
7
6
5
4
3
2
0
1
CAD NOTE:
35/40
TEST39L
MLA_CA1
MLA_CHECK1
MLA_DATA4
MLA_DATA10
MLA_DATA21
MLB_CA0
MLB_DATA3
MLB_DQS_H4
MLB_DQS_L8
MLA_CA0
MLA_CHECK0
MLA_DATA3
MLA_DATA20
MLA_DATA31
MLA_DQS_H9
MLB_DATA2
MLB_DQS_H3
MLB_DQS_L7
MLA1_CS_L1
MLA_DATA2
MLA_DATA30
MLA_DQS_H8
MLB_DATA1
MLB_DATA19
MLB_DQS_H2
MLB_DQS_L6
MLA0_CS_L1
MLA1_CS_L0
MLA_DATA1
MLA_DQS_H7
MLB_DATA0
MLB_DATA18
MLB_DATA29
MLB_DQS_H1
MLB_DQS_L5
ML1_CLK_L
MLA0_CS_L0
MLA_DATA0
MLA_DQS_H6
MLB_DATA17
MLB_DATA28
MLB_DQS_H0
MLB_DQS_L4
MLB_PAR
ML0_CLK_L
MLA_DQS_H5
MLA_DQS_L9
MLA_PAR
MLB1_RSP_L
MLB_CHECK7
MLB_DATA16
MLB_DATA27
MLB_DQS_L3
MLA_DQS_H4
MLA_DQS_L8
MLB0_RSP_L
MLB_CHECK6
MLB_DATA15
MLB_DATA26
MLB_DQS_L2
MLA_DQS_H3
MLA_DQS_L7
MLB_CHECK5
MLB_DATA14
MLB_DATA25
MLB_DQS_L1
ML1_CLK_H
MLA_DATA19
MLA_DQS_H2
MLA_DQS_L6
MLB_CHECK4
MLB_DATA13
MLB_DATA24
MLB_DQS_L0
ML0_CLK_H
MLA_DATA18
MLA_DATA29
MLA_DQS_H1
MLA_DQS_L5
MLB_CHECK3
MLB_DATA12
MLB_DATA23
MLA_DATA17
MLA_DATA28
MLA_DQS_H0
MLA_DQS_L4
MLB_CHECK2
MLB_DATA11
MLB_DATA22
ML_ALERT_L
MLA1_RSP_L
MLA_CHECK7
MLA_DATA16
MLA_DATA27
MLA_DQS_L3
MLB_CA6
MLB_CHECK1
MLB_DATA9
MLB_DATA10
MLB_DATA21
MLA0_RSP_L
MLA_CA6
MLA_CHECK6
MLA_DATA9
MLA_DATA15
MLA_DATA26
MLA_DQS_L2
MLB_CA5
MLB_CHECK0
MLB_DATA8
MLB_DATA20
MLB_DATA31
MLB_DQS_H9
MLA_CA5
MLA_CHECK5
MLA_DATA8
MLA_DATA14
MLA_DATA25
MLA_DQS_L1
MLB1_CS_L1
MLB_CA4
MLB_DATA7
MLB_DATA30
MLB_DQS_H8
MLA_CA4
MLA_CHECK4
MLA_DATA7
MLA_DATA13
MLA_DATA24
MLA_DQS_L0
MLB0_CS_L1
MLB1_CS_L0
MLB_CA3
MLB_DATA6
MLB_DQS_H7
MLA_CA3
MLA_CHECK3
MLA_DATA6
MLA_DATA12
MLA_DATA23
MLB0_CS_L0
MLB_CA2
MLB_DATA5
MLB_DQS_H6
ML_RESET_L
MLA_CA2
MLA_CHECK2
MLA_DATA5
MLA_DATA11
MLA_DATA22
MLB_CA1
MLB_DATA4
MLB_DQS_H5
MLB_DQS_L9
1
SHEETDATE
23
7 3 2 16 5 4
E
A
B
C
E
D
C
B
A
7 6 5 4
D
DEPARTMENT
SIZE
PROJECT DOCUMENT NUMBER REV
REVIEWER
DESIGNER
OUT
IN
OUT
IN
OUT
OUT
OUT
IN
OUT
OUT
OUT
OUT
OUT
OUT
BI
BI
BI
BI
BI
BI
BI
BI
C



Thu Aug 24 14:08:36 2023<NAME_2>
<NAME_1>
MB FABCGTI V02
22 OF 365
50
50
50
50
50
50
50
50
S O CK E T6096_13568-001
S O CK E T6096_13568-001
IO
IO
G MI_CP U1_G 3_CP U0_G 1_TX _DP <15:0>
G MI_CP U1_G 2_CP U0_G 0_TX _DP <15:0>
G MI_CP U1_G 2_CP U0_G 0_TX _DN<15:0>
G MI_CP U0_G 1_CP U1_G 3_TX _DN<15:0>
G MI_CP U0_G 1_CP U1_G 3_TX _DP <15:0>
G MI_CP U0_G 0_CP U1_G 2_TX _DP <15:0>
G MI_CP U0_G 0_CP U1_G 2_TX _DN<15:0>
G MI_CP U1_G 3_CP U0_G 1_TX _DN<15:0>
CPU0 PCIE G0/G1
SMLF
SMLF
AL52
AJ52
AN52
AL49
AJ49
AN49
AL46
AJ46
AN46
AL43
AJ43
AN43
AK40
AH40
AM 40
AP40
AL53
AJ53
AN53
AL50
AJ50
AN50
AL47
AJ47
AN47
AL44
AJ44
AN44
AK41
AH41
AM 41
AP41
U53
R53
W53
U50
R50
N50
W50
R47
N47
U47
R44
N44
U44
P41
T 41
V41
U52
R52
W52
U49
R49
N49
W49
R46
N46
U46
R43
N43
U43
P40
T 40
V40
U25
AE52
AC52
AG52
AE49
AC49
AG49
AE46
AC46
AG46
AE43
AC43
AA43
AG43
AB40
AD40
AF40
AE53
AC53
AG53
AE50
AC50
AG50
AE47
AC47
AG47
AE44
AC44
AA44
AG44
AB41
AD41
AF41
N53
J53
G53
L53
J50
G50
L50
J47
G47
L47
J44
G44
L44
H41
K41
M 41
N52
J52
G52
L52
J49
G49
L49
J46
G46
L46
J43
G43
L43
H40
K40
M 40
U25
6
14
15
15
13
12
14
13
12
11
10
9
11
10
8
6
7
9
8
7
5
4
6
5
4
3
1
2
3
2
0
1
0
15
14
15
12
13
14
13
12
10
11
11
10
9
7
9
8
8
6
7
4
5
6
4
5
2
3
3
2
1
0
1
0
15
14
13
15
14
12
11
13
12
11
10
9
8
10
9
7
8
7
6
5
4
3
5
3
4
2
1
0
2
1
0
14
15
13
15
14
11
12
13
12
11
9
10
10
9
8
6
7
8
7
6
3
5
4
5
4
3
1
2
2
1
0
0
12/40
G1_RXN7
G1_RXN6
G1_RXN5
G1_RXP7
G1_TXN7
G1_RXN4
G1_RXP6
G1_TXN6
G1_RXN3
G1_RXP5
G1_TXN5
G1_TXP7
G1_RXN2
G1_RXP4
G1_TXN4
G1_TXP6
G1_RXN1
G1_RXP3
G1_TXN3
G1_TXP5
G1_RXN0
G1_RXP2
G1_TXN2
G1_TXP4
G1_RXP1
G1_TXN1
G1_TXP3
G1_RXP0
G1_TXN0
G1_TXP2
G1_TXP1
G1_TXP0
G1_RXN8
G1_RXN9
G1_RXN10
G1_RXN11
G1_RXN12
G1_RXN13
G1_RXN14
G1_RXN15
G1_RXP8
G1_RXP9
G1_RXP10
G1_RXP11
G1_RXP12
G1_RXP13
G1_RXP14
G1_RXP15
G1_TXN8
G1_TXN9
G1_TXN10
G1_TXN11
G1_TXN12
G1_TXN13
G1_TXN14
G1_TXN15
G1_TXP8
G1_TXP9
G1_TXP10
G1_TXP11
G1_TXP12
G1_TXP13
G1_TXP14
G1_TXP15
11/40
G0_TXP15
G0_TXP14
G0_TXP13
G0_TXP12
G0_TXP11
G0_TXP10
G0_TXP9
G0_TXP8
G0_TXP7
G0_TXP6
G0_TXP5
G0_TXP4
G0_TXP3
G0_TXP2
G0_TXP1
G0_TXP0
G0_TXN15
G0_TXN14
G0_TXN13
G0_TXN12
G0_TXN11
G0_TXN10
G0_TXN9
G0_TXN8
G0_TXN7
G0_TXN6
G0_TXN5
G0_TXN4
G0_TXN3
G0_TXN2
G0_TXN1
G0_TXN0
G0_RXP15
G0_RXP14
G0_RXP13
G0_RXP12
G0_RXP11
G0_RXP10
G0_RXP9
G0_RXP8
G0_RXP7
G0_RXP6
G0_RXP5
G0_RXP4
G0_RXP3
G0_RXP2
G0_RXP1
G0_RXP0
G0_RXN15
G0_RXN14
G0_RXN13
G0_RXN12
G0_RXN11
G0_RXN10
G0_RXN9
G0_RXN8
G0_RXN7
G0_RXN6
G0_RXN5
G0_RXN4
G0_RXN3
G0_RXN2
G0_RXN1
G0_RXN0
1
SHEETDATE
23
7 3 2 16 5 4
E
A
B
C
E
D
C
B
A
7 6 5 4
D
DEPARTMENT
SIZE
PROJECT DOCUMENT NUMBER REV
REVIEWER
DESIGNER
IN
IN OUT
OUT
IN
IN
OUT
OUT
C



CPU0 G3[15:0] TO OCP SLOT#0
Thu Aug 24 14:08:36 2023<NAME_2>
<NAME_1>
MB FABCGTI V02
23 OF 365
65
65131
131
49
49 49
49
P 5E _CP U0_G 3_TX _DN<15:0>
P 5E _CP U0_G 3_TX _DP <15:0>
S O CK E T6096_13568-001
P 5E _CP U0_G 3_RX _DP <15:0> IO
P 5E _CP U0_G 3_RX _DN<15:0>
IO
S O CK E T6096_13568-001
G MI_CP U1_G 0_CP U0_G 2_TX _DN<15:0>
G MI_CP U1_G 0_CP U0_G 2_TX _DP <15:0> G MI_CP U0_G 2_CP U1_G 0_TX _DP <15:0>
G MI_CP U0_G 2_CP U1_G 0_TX _DN<15:0>
CPU0 PCIE G2/G3
SMLF
SMLF
V35
T 35
P35
U32
N32
R32
U29
N29
R29
W26
N26
R26
U26
W23
R23
U23
V36
T 36
P36
U33
N33
R33
U30
N30
R30
W27
N27
R27
U27
W24
R24
U24
AP36
AM 36
AH36
AK36
AN33
AJ33
AL33
AN30
AJ30
AL30
AN27
AJ27
AL27
AN24
AJ24
AL24
AP35
AM 35
AH35
AK35
AN32
AJ32
AL32
AN29
AJ29
AL29
AN26
AJ26
AL26
AN23
AJ23
AL23
U25
M 35
K35
H35
L32
G32
J32
L29
G29
J29
L26
G26
J26
L23
G23
J23
N23
M 36
K36
H36
L33
G33
J33
L30
G30
J30
L27
G27
J27
L24
G24
J24
N24
AF36
AD36
AB36
AG33
AA33
AC33
AE33
AG30
AC30
AE30
AG27
AC27
AE27
AG24
AC24
AE24
AF35
AD35
AB35
AG32
AA32
AC32
AE32
AG29
AC29
AE29
AG26
AC26
AE26
AG23
AC23
AE23
U25
1
1
3
2
7
6
5
4
3
2
12
0
1
9
11
8
7
14
13
13
4
5
11
3
14
15
12
14
15
13
12
13
10
10
6
9
8
7
5
6
4
2
3
2
0
1
15
15
14
14
12
13
13
11
10
10
11
9
9
8
8
7
0
0
6
5
4
15
15
12
14
11
10
11
12
10
9
8
7
9
8
6
4
5
7
6
5
3
2
4
2
3
1
0
1
0
15
15
13
14
13
14
12
11
10
12
11
10
9
8
8
9
7
6
5
7
6
4
5
4
3
2
3
2
1
0
1
0
14/40
G3_RXN2||SATA22_RXN
G3_TXN9||SATA31_TXN
G3_RXN12||SATA34_RXN
G3_RXN15||SATA37_RXN
G3_TXP5||SATA25_TXP
G3_RXN9||SATA31_RXN
G3_TXP2||SATA22_TXPG3_RXP2||SATA22_RXP
G3_RXP5||SATA25_RXP
G3_RXP14||SATA36_RXP
G3_TXN4||SATA24_TXN
G3_TXN7||SATA27_TXN
G3_TXN10||SATA32_TXN
G3_TXN13||SATA35_TXN
G3_RXP11||SATA33_RXP
G3_TXN1||SATA21_TXN
G3_TXP9||SATA31_TXP
G3_TXP15||SATA37_TXP
G3_RXN1||SATA21_RXN
G3_RXN4||SATA24_RXN
G3_RXN7||SATA27_RXN
G3_TXP12||SATA34_TXP
G3_RXP9||SATA31_RXP
G3_TXP7||SATA27_TXP
G3_TXN8||SATA30_TXN
G3_RXN11||SATA33_RXN
G3_RXN14||SATA36_RXN
G3_TXP1||SATA21_TXP
G3_TXP4||SATA24_TXP
G3_RXP7||SATA27_RXP
G3_RXN8||SATA30_RXN
G3_TXN12||SATA34_TXN
G3_TXN15||SATA37_TXN
G3_RXP1||SATA21_RXP
G3_RXP4||SATA24_RXP
G3_RXP10||SATA32_RXP
G3_RXP13||SATA35_RXP
G3_TXN3||SATA23_TXN
G3_TXN6||SATA26_TXNG3_RXN6||SATA26_RXN
G3_TXN0||SATA20_TXN
G3_TXP8||SATA30_TXP
G3_TXP14||SATA36_TXP
G3_RXN0||SATA20_RXN
G3_RXN3||SATA23_RXN
G3_RXP8||SATA30_RXP
G3_TXP11||SATA33_TXP
G3_RXN13||SATA35_RXN
G3_TXP6||SATA26_TXP
G3_RXN10||SATA32_RXN
G3_TXP0||SATA20_TXP
G3_TXP3||SATA23_TXPG3_RXP3||SATA23_RXP
G3_RXP6||SATA26_RXP
G3_RXP15||SATA37_RXP
G3_TXN5||SATA25_TXN
G3_TXN11||SATA33_TXN
G3_TXN14||SATA36_TXN
G3_RXP0||SATA20_RXP
G3_RXP12||SATA34_RXP
G3_TXN2||SATA22_TXN
G3_RXN5||SATA25_RXN
G3_TXP10||SATA32_TXP
G3_TXP13||SATA35_TXP
13/40
G2_TXP0
G2_RXN7
G2_RXN6
G2_RXN5
G2_RXP7
G2_TXN7
G2_RXN4
G2_RXP6
G2_TXN6
G2_RXN3
G2_RXP5
G2_TXN5
G2_TXP7
G2_RXN2
G2_RXP4
G2_TXN4
G2_TXP6
G2_RXN1
G2_RXP3
G2_TXN3
G2_TXP5
G2_RXN0
G2_RXP2
G2_TXN2
G2_TXP4
G2_RXP1
G2_TXN1
G2_TXP3
G2_RXP0
G2_TXN0
G2_TXP2
G2_TXP1
G2_RXN15
G2_RXP15
G2_RXN13
G2_RXP13
G2_RXN11
G2_RXP11
G2_RXN9
G2_RXP9
G2_RXN14
G2_RXP14
G2_RXN12
G2_RXP12
G2_RXN10
G2_RXP10
G2_RXN8
G2_RXP8
G2_TXN15
G2_TXP15
G2_TXN13
G2_TXP13
G2_TXN11
G2_TXP11
G2_TXN9
G2_TXP9
G2_TXN14
G2_TXP14
G2_TXN12
G2_TXP12
G2_TXN10
G2_TXP10
G2_TXN8
G2_TXP8
1
SHEETDATE
23
7 3 2 16 5 4
E
A
B
C
E
D
C
B
A
7 6 5 4
D
DEPARTMENT
SIZE
PROJECT DOCUMENT NUMBER REV
REVIEWER
DESIGNER
IN
IN OUT
OUT
IN
IN OUT
OUT
C



CPU0 P0[15:0] TO EXAMAX
CPU0 P1[15:0] TO EXAMAX
Thu Aug 24 14:08:37 2023<NAME_2>
<NAME_1>
MB FABCGTI V02
24 OF 365
63
63285
285
63
63
274
274
S O CK E T6096_13568-001 P 5E _CP U0_P 1_TX _DP <15:0>
P 5E _CP U0_P 1_TX _DN<15:0>P 5E _CP U0_P 1_RX _DN<15:0> IO
P 5E _CP U0_P 1_RX _DP <15:0>
P 5E _CP U0_P 0_TX _DN<15:0>
P 5E _CP U0_P 0_TX _DP <15:0>
P 5E _CP U0_P 0_RX _DN<15:0>
P 5E _CP U0_P 0_RX _DP <15:0>
SMLF
IO
SMLF
CPU0 PCIE P0/P1
S O CK E T6096_13568-001
CV41
CY41
DB41
CW44
DC44
DA44
CW47
DC47
DA47
CW50
DC50
DA50
CW53
DC53
DA53
CU53
CV40
CY40
DB40
CW43
DC43
DA43
CW46
DC46
DA46
CW49
DC49
DA49
CW52
DC52
DA52
CU52
CD40
CF40
CH40
CC43
CJ43
CG43
CE43
CC46
CG46
CE46
CC49
CG49
CE49
CC52
CG52
CE52
CD41
CF41
CH41
CC44
CJ44
CG44
CE44
CC47
CG47
CE47
CC50
CG50
CE50
CC53
CG53
CE53
U25
CM 41
CP41
CT 41
CN44
CU44
CR44
CN47
CU47
CR47
CL50
CU50
CR50
CN50
CL53
CR53
CN53
CM 40
CP40
CT 40
CN43
CU43
CR43
CN46
CU46
CR46
CL49
CU49
CR49
CN49
CL52
CR52
CN52
BT 40
BV40
CB40
BY40
BU43
CA43
BW43
BU46
CA46
BW46
BU49
CA49
BW49
BU52
CA52
BW52
BT 41
BV41
CB41
BY41
BU44
CA44
BW44
BU47
CA47
BW47
BU50
CA50
BW50
BU53
CA53
BW53
U25
3
2
0
1
0
1
0
0
1
5
1
2
4
6
7
5
4
3
7
6
8
9
11
10
12
10
9
8
13
11
12
13
15
14
14
15
13
15
2
2
3
4
5
6
7
4
5
6
7
8
9
10
11
13
12
8
9
10
11
12
14
15
14
3
13
12
7
5
9
10
6
14
3
2
4
4
15
0
00
1
11
10
7
6
1
14
13
12
11
8
5
3
0
1
1
15
14
13
12
11
10
9
8
7
6
5
4
3
2
2
3
4
5
6
7
8
9
11
10
12
14
13
15 15
2
8
9
16/40
P1_RXN6
P1_RXN5
P1_RXP7
P1_TXN7
P1_RXN4
P1_RXP6
P1_TXN6
P1_RXN3
P1_RXP5
P1_TXN5
P1_TXP7
P1_RXN2
P1_RXP4
P1_TXN4
P1_TXP6
P1_RXN1
P1_RXP3
P1_TXN3
P1_TXP5
P1_RXN0
P1_RXP2
P1_TXN2
P1_TXP4
P1_RXP1
P1_TXN1
P1_TXP3
P1_RXP0
P1_TXN0
P1_TXP2
P1_TXP1
P1_TXP0
P1_RXN7
P1_TXN15
P1_TXP15
P1_TXN14
P1_TXP14
P1_TXN13
P1_TXP13
P1_TXN12
P1_TXP12
P1_TXN11
P1_TXP11
P1_TXN10
P1_TXP10
P1_TXN9
P1_TXP9
P1_TXN8
P1_TXP8
P1_RXN15
P1_RXP15
P1_RXN14
P1_RXP14
P1_RXN13
P1_RXP13
P1_RXN12
P1_RXP12
P1_RXN11
P1_RXP11
P1_RXN10
P1_RXP10
P1_RXN9
P1_RXP9
P1_RXN8
P1_RXP8
15/40
P0_RXP11||SATA13_RXP
P0_TXP12||SATA14_TXP
P0_TXP15||SATA17_TXP
P0_RXN11||SATA13_RXN
P0_RXN14||SATA16_RXN
P0_TXN15||SATA17_TXN
P0_RXP13||SATA15_RXP
P0_TXN9||SATA11_TXN
P0_TXN12||SATA14_TXN
P0_RXP10||SATA12_RXP
P0_RXN9||SATA11_RXN
P0_TXP11||SATA13_TXP
P0_TXP14||SATA16_TXP
P0_RXN10||SATA12_RXN
P0_RXN13||SATA15_RXN
P0_TXP9||SATA11_TXPP0_RXP9||SATA11_RXP
P0_TXN14||SATA16_TXN
P0_RXP12||SATA14_RXP
P0_RXP15||SATA17_RXP
P0_TXN8||SATA10_TXN
P0_TXN11||SATA13_TXN
P0_RXN8||SATA10_RXN
P0_TXP13||SATA15_TXP
P0_TXP10||SATA12_TXP
P0_RXN15||SATA17_RXN
P0_TXP8||SATA10_TXP
P0_RXN12||SATA14_RXN
P0_RXP8||SATA10_RXP
P0_RXP14||SATA16_RXP
P0_TXN10||SATA12_TXN
P0_TXN13||SATA15_TXN
P0_TXP3||SATA03_TXP
P0_TXP6||SATA06_TXP
P0_TXP0||SATA00_TXP
P0_RXP3||SATA03_RXP
P0_RXP6||SATA06_RXP
P0_TXN5||SATA05_TXN
P0_RXP0||SATA00_RXP
P0_TXN2||SATA02_TXNP0_RXN2||SATA02_RXN
P0_RXN5||SATA05_RXN
P0_TXP2||SATA02_TXP
P0_TXP5||SATA05_TXPP0_RXP5||SATA05_RXP
P0_RXP2||SATA02_RXP
P0_TXN1||SATA01_TXN
P0_TXN7||SATA07_TXN
P0_TXN4||SATA04_TXN
P0_RXN7||SATA07_RXN
P0_RXN1||SATA01_RXN
P0_RXN4||SATA04_RXN
P0_TXP7||SATA07_TXP
P0_TXP1||SATA01_TXP
P0_TXP4||SATA04_TXPP0_RXP4||SATA04_RXP
P0_RXP7||SATA07_RXP
P0_TXN6||SATA06_TXN
P0_RXP1||SATA01_RXP
P0_TXN0||SATA00_TXN
P0_TXN3||SATA03_TXNP0_RXN3||SATA03_RXN
P0_RXN6||SATA06_RXN
P0_RXN0||SATA00_RXN
1
SHEETDATE
23
7 3 2 16 5 4
E
A
B
C
E
D
C
B
A
7 6 5 4
D
DEPARTMENT
SIZE
PROJECT DOCUMENT NUMBER REV
REVIEWER
DESIGNER
OUT
OUTIN
IN
IN
IN OUT
OUT
C



CPU0 P2[15:0] TO EXAMAX
CPU0 P3[15:0] TO EXAMAX
Thu Aug 24 14:08:37 2023<NAME_2>
<NAME_1>
MB FABCGTI V02
25 OF 365
64
64
64
64
307
296
296
307
P 5E _CP U0_P 2_TX _DP <15:0>
P 5E _CP U0_P 2_TX _DN<15:0>
P 5E _CP U0_P 3_TX _DP <15:0>
P 5E _CP U0_P 3_TX _DN<15:0>
P 5E _CP U0_P 3_RX _DP <15:0>
S O CK E T6096_13568-001IO
SMLF
SMLF
CPU0 PCIE P2/P3
IO
S O CK E T6096_13568-001P 5E _CP U0_P 2_RX _DP <15:0>
P 5E _CP U0_P 2_RX _DN<15:0>
P 5E _CP U0_P 3_RX _DN<15:0>
CE24
CG24
CC24
CE27
CG27
CC27
CE30
CG30
CC30
CE33
CG33
CJ33
CC33
CH36
CF36
CD36
CE23
CG23
CC23
CE26
CG26
CC26
CE29
CG29
CC29
CE32
CG32
CJ32
CC32
CH35
CF35
CD35
CU23
DA23
DC23
CW23
DA26
DC26
CW26
DA29
DC29
CW29
DA32
DC32
CW32
DB35
CY35
CV35
CU24
DA24
DC24
CW24
DA27
DC27
CW27
DA30
DC30
CW30
DA33
DC33
CW33
DB36
CY36
CV36
U25
BW24
CA24
BU24
BW27
CA27
BU27
BW30
CA30
BU30
BW33
CA33
BU33
BY36
CB36
BV36
BT 36
BW23
CA23
BU23
BW26
CA26
BU26
BW29
CA29
BU29
BW32
CA32
BU32
BY35
CB35
BV35
BT 35
CN23
CR23
CL23
CN26
CR26
CU26
CL26
CR29
CU29
CN29
CR32
CU32
CN32
CT 35
CP35
CM 35
CN24
CR24
CL24
CN27
CR27
CU27
CL27
CR30
CU30
CN30
CR33
CU33
CN33
CT 36
CP36
CM 36
U25
4
1
0
2
0
1
3
4
5
6
7
3
2
4
5
6
7
8
9
10
11
12
8
9
10
11
12
13
15
14
13
14
15
0
1
1
0
2
3
2
5
7
6
3
4
6
5
7
9
8
10
12
11
8
10
9
11
12
14
13
13
14
15
15
2
2
4
3
1
0
4
3
0
1
6
6
12
13
15
8
5
0
1
2
3
6
4
9
7
12
11
10
13
14
15
1
2
3
4
6
7
8
9
10
11
12
13
14
15
0
5
7
8
10
9
11
12
14
15
5
7
8
9
10
11
13
14
5
18/40
P3_TXN15
P3_TXP15
P3_TXN14
P3_TXP14
P3_TXN13
P3_TXP13
P3_TXN12
P3_TXP12
P3_TXN11
P3_TXP11
P3_TXN10
P3_TXP10
P3_TXN9
P3_TXP9
P3_TXN8
P3_TXP8
P3_TXN7
P3_TXP7
P3_TXN6
P3_TXP6
P3_TXN5
P3_TXP5
P3_TXN4
P3_TXP4
P3_TXN3
P3_TXP3
P3_TXN2
P3_TXP2
P3_TXN1
P3_TXP1
P3_TXN0
P3_TXP0
P3_RXN15
P3_RXP15
P3_RXN14
P3_RXP14
P3_RXN13
P3_RXP13
P3_RXN12
P3_RXP12
P3_RXN11
P3_RXP11
P3_RXN10
P3_RXP10
P3_RXN9
P3_RXP9
P3_RXN8
P3_RXP8
P3_RXN7
P3_RXP7
P3_RXN6
P3_RXP6
P3_RXN5
P3_RXP5
P3_RXN4
P3_RXP4
P3_RXN3
P3_RXP3
P3_RXN2
P3_RXP2
P3_RXN1
P3_RXP1
P3_RXN0
P3_RXP0
17/40
P2_RXN7
P2_RXN6
P2_RXN5
P2_RXP7
P2_TXN7
P2_RXN4
P2_RXP6
P2_TXN6
P2_RXN3
P2_RXP5
P2_TXN5
P2_TXP7
P2_RXN2
P2_RXP4
P2_TXN4
P2_TXP6
P2_RXN1
P2_RXP3
P2_TXN3
P2_TXP5
P2_RXN0
P2_RXP2
P2_TXN2
P2_TXP4
P2_RXP1
P2_TXN1
P2_TXP3
P2_RXP0
P2_TXN0
P2_TXP2
P2_TXP1
P2_TXP0
P2_TXN15
P2_TXP15
P2_TXN14
P2_TXP14
P2_TXN13
P2_TXP13
P2_TXN12
P2_TXP12
P2_TXN11
P2_TXP11
P2_TXN10
P2_TXP10
P2_TXN9
P2_TXP9
P2_TXN8
P2_TXP8
P2_RXN15
P2_RXP15
P2_RXN14
P2_RXP14
P2_RXN13
P2_RXP13
P2_RXN12
P2_RXP12
P2_RXN11
P2_RXP11
P2_RXN10
P2_RXP10
P2_RXN9
P2_RXP9
P2_RXN8
P2_RXP8
1
SHEETDATE
23
7 3 2 16 5 4
E
A
B
C
E
D
C
B
A
7 6 5 4
D
DEPARTMENT
SIZE
PROJECT DOCUMENT NUMBER REV
REVIEWER
DESIGNER
OUT
OUTIN
IN
IN
IN
OUT
OUT
C



CPU0 P4[3:0] TO E1.S
CPU0 P5[2] TO SCM CONN
Thu Aug 24 14:08:37 2023<NAME_2>
<NAME_1>
MB FABCGTI V02
26 OF 365
150
150
53
53
150
150
67
67
145
145
53
53
P2E_CPU0_P5_TX_C_DN
P2E_CPU0_P5_TX_C_DP
DIFF BUS_0.22UF
C0201
W A FL_CP U0_TX 0_CP U1_RX 1_DP
W A FL_CP U0_TX 0_CP U1_RX 1_DN
P2E_CPU0_P5_TX_DP
6.3V
P 2E _CP U0_P 5_RX _DN
P 2E _CP U0_P 5_RX _DP
P2E_CPU0_P5_TX_DN
SMLF
S O CK E T6096_13568-001
IO
X6S
20%
P 3E _CP U0_P 4_TX _DN<3:0>
CPU0 PCIE P4/P5/WAFL
P 3E _CP U0_P 4_TX _DP <3:0>
P 3E _CP U0_P 4_RX _DN<3:0>
P 3E _CP U0_P 4_RX _DP <3:0>
W A FL_CP U1_TX 1_CP U0_RX 0_DP
W A FL_CP U1_TX 1_CP U0_RX 0_DN
C47
C50
C48
C51
E46
E49
E47
E50
C41
C44
C42
C45
E40
E43
E41
E44
DE44
DE47
DE50
DE53
DE43
DE46
DE49
DE52
DG45
DG48
DG51
DG54
DG44
DG47
DG50
DG53
U25
21
21
21
21
0
1
3
1
0
2
2
1
2
3
3
2
1
3
0
0
C2078
C2077
19/40
WAFL_TXP1||P5_TXP1
WAFL_TXN1||P5_TXN1
WAFL_TXP0||P5_TXP0
WAFL_TXN0||P5_TXN0
WAFL_RXP1||P5_RXP1
WAFL_RXN1||P5_RXN1
WAFL_RXP0||P5_RXP0
WAFL_RXN0||P5_RXN0
P4_RXN1
P4_RXN0
P4_RXP1
P4_TXN1
P4_RXP0
P4_TXN0
P4_TXP1
P4_TXP0
P5_TXP3
P5_TXP2
P5_TXN3
P5_TXN2
P5_RXP3
P5_RXP2
P5_RXN3
P5_RXN2
P4_TXP3
P4_TXP2
P4_TXN3
P4_TXN2
P4_RXP3
P4_RXP2
P4_RXN3
P4_RXN2
1
SHEETDATE
23
7 3 2 16 5 4
E
A
B
C
E
D
C
B
A
7 6 5 4
D
DEPARTMENT
SIZE
PROJECT DOCUMENT NUMBER REV
REVIEWER
DESIGNER
IN
IN
OUT
OUT
IN
IN
OUT
OUT
IN
IN
OUT
OUT
C



CAD NOTE: IF DEPOP R1533, PLEASE POP R536
20220411:
XTRIG_L[7:4] OF THE BP ARE CONNECTED TO
XTRIG_L[7:4] OF THE ASP RESPECTIVELY)
LOW: VDDBT_RTC_G POWERED FROM 1.8 OR 1.5V SOURCE
HIGH: VDDBT_RTC_G POWERED FROM 3.0V SOURCE
Thu Aug 24 14:08:38 2023<NAME_2>
<NAME_1>
MB FABCGTI V02
27 OF 365
P 1V 5_B A T
P V DD18_S 5_P 0
P V DD18_S 5_P 0
P V DD18_S 5_P 0
P 3V 3_A UX
2782 54 82
200
200
193
193
27 82
27 82 172
193
209
207
54 82
54 82
54 82
2782172
2782172
27
27
27
27
2782172
164
76 164
164
2782 54 82
2782172
2782172
27
27
2782172
2782172
2782
2782172
8227
27
27
27
27
27 82
27
27
27
2782
2782
2782
2782
2782
2782
167
2782
200207
193
193
209
200
27 82
27 82
27 82
27 82
27 82
27 82
27 82
17327
17327
17327
27
8183
8183
27173
27173
27173
27174
200
161
27174
17427
17327
27173
2782
2782
200
200
82 27
82 27
161
27174
27 82 172
27 82 172
167 81
193
2782
81
27 82
164
2782172
33
33
CHIP
0402LF1/16W
0
5%
C PU 0_TH ER MTR IP_R _N C PU 1_TH ER MTR IP_R _N
NA
1/16W
CP U0_RTC_LDO _S E LE CT
10K
E MP TY
5%
0402LF
1/16W
CHIP
5%
0402LF
10K
0402LF
TP _CP U0_TE S T47_CCD3
TP _CP U0_TE S T47_CCD2
E MP TY
S V ID_P V DDCR_CP U1_P 0_S V D_R
S V ID_P V DDCR_CP U1_P 0_S V C_R
0S V ID_P V DDCR_CP U0_P 0_S V D_R S V ID_P V DDCR_CP U0_P 0_S V D
S V ID_P V DDCR_CP U0_P 0_S V TO
S V ID_P V DDCR_CP U1_P 0_S V C0
0
CP U0_X TRIG _L4
CP U0_X TRIG _L6
V S E NS E _P V DDCR_S O C_P 0_DP
V S E NS E _P V DD18_S 5_P 0_DP
TP _V S E NS E _P V DD33_S 5_P 0
V S E NS E _P V DD11_S 3_P 0_DP
UA RT_CP U0_S CM_UA RT1_R_TX
TP _CP U0_TE S T41_IDO
CP U1_X TRIG _L7
CP U1_X TRIG _L6
CP U1_X TRIG _L5
CONN10_HBC1051-L300D-8H
CP U0_X TRIG _L7
CP U0_X TRIG _L5
IO
CP U0_X TRIG _R1_L7
CP U0_B P 2
CP U0_B P 1
CP U0_X TRIG _R1_L6
SMLF
IO
CP U0_X TRIG _R1_L5
SMLF
CP U0_B P 0
CP U0_B P 3
CP U0_X TRIG _L6
UA RT_CP U0_UA RT0_RX
UA RT_CP U0_S CM_UA RT1_TX
UA RT_CP U0_S CM_UA RT1_RX
THLF
IO
CP U0_X TRIG _L4 CP U1_X TRIG _L4
CP U0_X TRIG _L5
CP U0_X TRIG _L7
SMLF
CPU0 MISC 1/2
A P ML_CP U0_A LE RT_N
CP U0_THE RMTRIP _N
CP U0_X TRIG _L7
CP U0_X TRIG _L6
CP U0_X TRIG _L4
CP U0_X TRIG _L5
CP U0_P RO CHO T_N
CP U0_B P 3
CP U0_B P 2
CP U0_B P 0
CP U0_B P 1
CP U0_P RO CHO T_N
CP U0_B P 1
CP U0_B P 0
NC_CP U0_A Z_B ITCLK
CP U0_B P 3
TP _CP U0_TE S T5_CCD2
TP _CP U0_TE S T6_X 3D3
TP _CP U0_TE S T6_X 3D2
TP _CP U0_TE S T6_X 3D1
TP _CP U0_TE S T6_X 3D0
TP _CP U0_TE S T4_CCD11
TP _CP U0_TE S T4_CCD9
TP _CP U0_TE S T4_CCD10
TP _CP U0_TE S T4_CCD8
TP _CP U0_TE S T4_CCD6
TP _CP U0_TE S T5_CCD7
TP _CP U0_TE S T4_CCD5
TP _CP U0_TE S T5_CCD6
TP _CP U0_TE S T4_CCD4
TP _CP U0_TE S T4_CCD3
TP _CP U0_TE S T5_CCD4
TP _CP U0_TE S T4_CCD2
TP _CP U0_TE S T5_CCD3
TP _CP U0_TE S T4_CCD1
TP _CP U0_TE S T4_CCD0
TP _CP U0_TE S T5_CCD1
TP _CP U0_TE S T6_X 3D5
TP _CP U0_TE S T5_CCD0
TP _CP U0_TE S T6_X 3D4
TP _CP U0_TE S T5_CCD11
TP _CP U0_TE S T5_CCD10
TP _CP U0_TE S T5_CCD9
TP _CP U0_TE S T4_IO D
CP U0_S P 5R4
CP U0_S P 5R3
CP U0_S P 5R2
CP U0_S P 5R1
CP U0_CO RE TY P E 1
CP U0_CO RE TY P E 0
P RS NT_CP U0_N
CP U0_CO RE TY P E 2
TP _CP U0_TE S T50_IO D
V S E NS E _V S S _S E NS E _C_P 0
V S E NS E _P V DDCR_CP U0_P 0_DP
V S E NS E _V S S _S E NS E _A _P 0
V S E NS E _P V DD18_S 5_P 0_DN
V S E NS E _V S S _S E NS E _B _P 0
CP U0_S P 5R4
CP U0_S P 5R3
CP U0_S P 5R1
CP U0_S P 5R2
CP U0_CO RE TY P E 2
CP U0_CO RE TY P E 1
CP U0_CO RE TY P E 0
JTA G _CP U0_DB RE Q _N
JTA G _CP U0_TCK
JTA G _CP U0_TMS
IO
NA
CHIP CHIP
E MP TYE MP TYE MP TYE MP TYE MP TYE MP TY
10%10%10%10%10%10%
S O CK E T6096_13568-001
0.001UF0.001UF0.001UF0.001UF0.001UF
2.2K
2.2K
2.2K
2.2K
2.2K
2.2K
2.2K
2.2K
2.2K
2.2K
2.2K
2.2K
2.2K
2.2K
2.2K
2.2K
2.2K
2.2K
2.2K
2.2K 2.2K
50V50V50V50V
C0402C0402C0402C0402C0402C0402
0402LF 0402LF
NC_CP U0_A Z_RS T_N
NC_CP U0_A Z_S DIN0
NC_CP U0_A Z_S DIN1
NC_CP U0_A Z_S DIN2
NC_CP U0_A Z_S DO UT
NC_CP U0_A Z_S Y NC
TP _CP U0_TE S T47_CCD1
TP _CP U0_TE S T47_CCD0 TP _CP U0_TE S T6_CCD1
CP U0_B P 2
FM_P 0_P CC0_N
FM_P 0_P CC1_N
JTA G _CP U0_TMS
JTA G _CP U0_TCK
JTA G _CP U0_TRS T_N
JTA G _CP U0_TDI
S V ID_P V DDCR_CP U1_P 0_S V TO
S MB _A P ML_CP U0_S CL
JTA G _CP U0_TDO
JTA G _CP U0_TDI
JTA G _CP U0_TRS T_N
JTA G _CP U0_DB RE Q _N
CP U0_S A 0
CP U0_S A 1
V S E NS E _P V DDCR_CP U1_P 0_DP
V S E NS E _P V DDIO _P 0_DP
NA
CP U0_S A 1
CP U0_S A 0
NA NA NA NA
S MB _A P ML_CP U0_S DA
TP _CP U0_TE S T5_IO D
NA
TP _CP U0_TE S T47_IO D1
NA
0.001UF
50V
NA
50V
0402LF
TP _CP U0_TE S T47_IO D0
TP _CP U0_TE S T6_CCD0
TP _CP U0_TE S T5_CCD5
0 JTA G _CP U0_R_TDOJTA G _CP U0_TDO
0
0CP U0_X TRIG _R2_L4
0CP U0_X TRIG _R2_L5 CP U0_X TRIG _L5
0CP U0_X TRIG _R2_L7 CP U0_X TRIG _L7
0CP U0_X TRIG _R2_L6
0FM_B IO S _US B _RE CO V E RY _R FM_B IO S _US B _RE CO V E RY
0
S V ID_P V DDCR_CP U1_P 0_S V D
0
0S V ID_P V DDCR_CP U0_P 0_S V C_R S V ID_P V DDCR_CP U0_P 0_S V C
0
0CP U0_X TRIG _L4
0
0402LF
1K
CHIP
1/16W
1%
CHIP
1/16W
1K
1%
0402LF
CHIP
1K
1/16W
1%
1/16W
0402LF
CHIP
1K
1%
0402LF
1K
CHIP
1/16W
1%
0402LF
1K
CHIP
1/16W
1%
A P ML_CP U0_A LE RT_N A P ML_CP U0_A LE RT_R_N
CP U0_THE RMTRIP _N CP U0_THE RMTRIP _R_N
TP _CP U0_TE S T6_IO D
TP _UA RT_CP U0_UA RT0_RTS _N
TP _CP U0_UA RT0_INTR
UA RT_CP U0_UA RT0_R_TX UA RT_CP U0_UA RT0_TX
CP U0_X TRIG _L6
TP _CP U0_TE S T5_CCD8
TP _CP U0_TE S T4_CCD7
SCONN8_G802M0083150RD3HR
SCONN8_G802M0083150RD3HR
TP _CP U0_TE S T6_CCD3
TP _CP U0_TE S T6_CCD2
CP U0_X TRIG _R1_L4
27
27
R5056
R5055
T P1 T P10
21 R247
21 R489
2
1 R394
2
1R393
2
1R392
21R397
21R396
21R391
21R389
21R390
21R388
21R387
21R416
21R415
21R414
21R413
21R411
21R410
21R409
21R408
21R417
21R418
21R412
T P2 T P3 T P4 T P5 T P6 T P7 T P8 T P9
21
R1204
21 R356
21 R357
21 R157
21 R156
21 R485
21 R484
21 R481
21 R483
21PR302
21PR303
21PR60
21PR59
2
1 C207
2
1 C208
2
1
R398
2
1
R399
2
1 C209
2
1 C210
2
1
R400
2
1
R401
2
1 C211
2
1
R402
2
1 C212
2
1
R403 21R2318
2 1R405
A65
A66
C65
C66
B73
DJ3
BR54
C3
BR53
B3
DG3
C2
BP53
C74
DH3
DJ32
DH33
DJ34
DG35
DF34
DG34
DJ33
A17
A16
DJ9
B61
D7
B58
E32
CK46
CJ24
B60
W31
CJ53
AA23
CJ52
AA29
CJ29
AA47
AA49
Y46
CJ46
CJ30
AA46
AA24
Y29
CK47
CK29
Y47
AA26
CJ51
CJ25
AA53
Y30
CJ49
CJ27
AA51
AA25
AA28
CJ47
CK30
AA48
AA27
CJ50
CJ26
AA52
AA30
CJ48
CJ28
AA50
C18
C17
B17
DG73
B21
DH72
A22
DJ72
A23
DH10
DH73
C68
C19
DH71
DJ71
DJ56
DJ55
DH8
A69
DG72
C22
C16
B66
D68
B69
C70
A62
A63
C62
C63
D32
A32
A33
D33
C33
A34
C32
A68
U25
2 1R404
1
1
1
1
1
1
1
1
1
1
R1533
87
65
43
21
87
65
43
21
109
87
65
43
21
J5
J48
J212
87
65
43
21
87
65
43
21
10
8
9
7
65
43
21
20/40
CORETYPE2
BP3
BP2
BP1
BP0
TEST41_IOD
TEST47_CCD3
TEST6_CCD0
TEST6_X3D3
TEST6_X3D2
TEST47_IOD1 TEST6_X3D1
TEST47_IOD0 TEST6_X3D0
TEST5_CCD11
TEST4_CCD11
TEST5_CCD10
TEST4_CCD9
TEST4_CCD10
TEST47_CCD2
TEST4_CCD8
TEST5_CCD9
TEST47_CCD1
TEST4_CCD7
TEST50_IOD
TEST5_CCD8
TEST47_CCD0
TEST4_CCD6
TEST5_CCD7
TEST4_CCD5
TEST5_CCD6
TEST4_CCD4
TEST5_CCD5
TEST6_IOD
TEST4_CCD3
TEST5_CCD4
TEST5_IOD
TEST4_CCD2
TEST4_IOD
TEST5_CCD3
TEST4_CCD1
TEST5_CCD2
TEST6_CCD3
TEST4_CCD0
TEST5_CCD1
TEST6_CCD2
TEST6_X3D5
TEST5_CCD0
TEST6_CCD1
TEST6_X3D4
VDDCR_CPU0_SENSE
VDDCR_CPU1_SENSE
VDDCR_SOC_SENSE
VDD_33_S5_SENSE
VDD_18_S5_SENSE
VDD_11_S3_SENSE
VDDIO_SENSE
VSS_SENSE_D
VSS_SENSE_C
VSS_SENSE_B
VSS_SENSE_A
UART1_TXD||AGPIO142
UART1_RXD||AGPIO141
RTC_LDO_SELECT
TCK
SP5R1
AZ_SDIN1||SW_MCLK
AZ_SDIN0||SW_MDATA3
AZ_RST_L||SW_MDATA1
AZ_SDOUT||SW_MDATA2
AZ_SDIN2||SW_MDATA0
UART0_CTS_L||UART2_TXD||AGPIO135
UART0_TXD||AGPIO138
UART0_INTR||AGPIO139
UART0_RTS_L||UART2_RXD||AGPIO137
UART0_RXD||AGPIO136
SVC1
SVT1
SVC0
SVD1
SVT0
SVD0 AZ_SYNC
AZ_BITCLK
PCC1_L
PCC0_L
SP5R4
SP5R3
SP5R2
CORETYPE1
CORETYPE0
SA1
XTRIG_L7
XTRIG_L6
XTRIG_L5
XTRIG_L4
TRST_L
TMS
THERMTRIP_L
TDO
TDI
SID
SIC
SA0
PROCHOT_L
DBREQ_L
CPU_PRESENT_L
ALERT_L
21
2
1
2
1
1
SHEETDATE
23
7 3 2 16 5 4
E
A
B
C
E
D
C
B
A
7 6 5 4
D
DEPARTMENT
SIZE
PROJECT DOCUMENT NUMBER REV
REVIEWER
DESIGNER
IN
IN
OUT
OUT
OUT
OUT
OUT
OUT
OUT
OUT
OUT
OUT
OUT
OUT
OUT
IN
IN
OUT
OUT
IN
IN
OUT
OUT
OUT
OUT
OUT
OUT
OUT
OUT
IN
IN
BI
BI
BI
BI
BI
BI
BI
BI
IN OUT
OUT
OUT
OUT
OUT
OUT
IN
BI
BI
BI
BI
OUT
OUT
OUT
OUT
OUT
OUT
OUT
OUT
OUT
OUT
OUT
OUT
OUT
OUT
OUT
OUT
OUT
OUT
BI
BI
OUT
IN
IN
OUT
BI
BI
IN
OUT
OUT
OUT
OUT
OUT
OUT
OUT
OUT
OUT
OUT
OUT
OUT
OUT
IN
IN
IN
IN
IN
C



20220926 ADD R6502
Thu Aug 24 14:09:23 2023<NAME_2>
<NAME_1>
MB FABCGTI V02
28 OF 365
P V DD18_S 5_P 0
P V DD11_S 3_P 0
P V DD18_S 5_P 0
P V DD11_S 3_P 0
P V DD18_S 5_P 0
165
0402LF
10M
0402LF
0.1P
50V
NPO
3.9P
C0402
NPO
50V
0.1P
3.9P
C0402
CHIP
1%
X TA L_CP U0_X 48M_X 2_R
1/16W
4.7K
CHIPCHIP
C PU 0_FOR C E_SELFR EFR ESH
151
28159
28159
182
145
122
122
182
131
84
131
28159
28
28
288185
28817885
2881
2881
2881
8128255
84
84
16184
34166
81167
2882
28166
76
84
84
84
2881
2881
2881
28
28
131
131
131
150
131
131
150
76 55
28 81
28 81
8228
8228
2881
28
81 83
81 83
28 81
28 81
155 55
28 81 85
28 81 78 85
8228
8228
28
8128
28
28
2881
2881255
28
2882
28159
28
55
55
151
34
34
81
81
55 81
161
28
8228
28166
8128
2881
28 159
28 159
84
2882
2882
2882
167
2881
28 81
28 81
2881
28 159
28 159
131
145
33
33
33S MB _CP U_5_S CL S MB _CP U_5_R_S CL
I3C_1_S P D_DDRG L_CP U0_R_S CL
I3C_1_S P D_DDRG L_CP U0_R_S DA
S MB _CP U0_3_R_S CL
S MB _CP U0_3_R_S DA
0
CHIP
8.2PF
0.1P
NP0
C0402
50V8.2PF
0.1P
NP0
C0402
50V
1%
1/16W
0402LF
5%
1/16W C LK_100M_C PU 0_C LK13_D P
CLK _100M_CP U0_CLK 12_DP
CLK _100M_CP U0_CLK 11_DN
CLK _100M_CP U0_CLK 11_DP
0402LF
5%
1/16W
C LK_100M_C PU 0_C LK13_D N
1/16W
5%
0402LF
0402LF
0402LF
0402LF
CLK _100M_CP U0_CLK 11_R_DN
CLK _100M_CP U0_CLK 11_R_DP
CLK _100M_CP U0_CLK 05_R_DN
CLK _100M_CP U0_CLK 05_R_DP
CLK _100M_CP U0_CLK 04_R_DP
C LK_100M_C PU 0_C LK13_R _D N
C LK_100M_C PU 0_C LK13_R _D P
CLK _100M_CP U0_CLK 12_R_DN
0 1/16W
5%
CLK _100M_CP U0_CLK 05_DP1/16W
CLK _100M_CP U0_CLK 12_R_DP
0402LF
1/16W
FA B _RE V _ID0
0
5%
1/16W
0
0
0402LF
1/16W
CLK _100M_CP U0_CLK 04_DN
0
0
I3C_0_S P D_DDRA F_CP U0_R_S DA
MIS C
49.9
X TA L_CP U0_X 48M_X 2
X TA L_CP U0_X 48M_X 1
SMLF
48MHZ
E MP TY
RS T_CP U0_RE S E TL_N
P W RG D_CP U0_P W RO K
CP U0_FO RCE _S E LFRE FRE S H
4.7K
4.7K
E MP TY
4.7K
E MP TY
4.7K
CHIP
CP U0_NV _S A V E _N
CP U0_S ME RR_N
RS T_CP U0_RS MRS T_N
4.7K
4.7K
E MP TY
4.7K
4.7K
E MP TY
1K
S MLF
32.768K HZ
FA B _RE V _ID2
FA B _RE V _ID1
S MB _CP U0_S E C_S CLFM_B O A RD_S K U_ID0
FM_B IO S _P O S T_CMP LT_N
B IO S _DE B UG _MO DE
IRQ _S MI_A CTIV E _N
B O O T_RDY _H
CP U0_RO M_TY P E _S E LE CT
FM_B O A RD_S K U_ID3
FM_B O A RD_S K U_ID2
FM_B O A RD_S K U_ID4
S MB _CP U0_2_R_S CL
50V
5%
CP U0_P W R_B TN_N
RS T_CP U0_S Y S _N
CP U0_P W R_G O O D
X TA L_CP U0_X 48M_X 1
X TA L_CP U0_X 48M_X 2
0
00402LF
CLK _100M_CP U0_CLK 04_DP
CLK _100M_CP U0_CLK 03_DP
CLK _100M_CP U0_CLK 03_DN
CLK _100M_CP U0_CLK 01_DP
CLK _100M_CP U0_CLK 02_DN
CLK _100M_CP U0_CLK 02_DP
CLK _100M_CP U0_CLK 01_DNCLK _100M_CP U0_CLK 01_R_DN
0402LF
5%
1/16W
5%
CLK _CP U0_RTCCLK
CP U0_P W R_B TN_N
RS T_CP U0_S Y S _N
IRQ_B MC_S MI_N
IR Q_TPM_SPI_R _N
CP U0_S ME RR_N
X TA L_CP U0_X 32K _X 1
RS T_CP U0_P E RS T1_N
RS T_CP U0_P E RS T0_N
CP U0_FO RCE _S E LFRE FRE S H
CP U0_NV _S A V E _N
IRQ _W A K E _N
RS T_CP U0_RE S E TL_N
P W RG D_CP U0_P W RO K
THLF
IO
2.2K
2.2K RST_SYS PU BY STRAP PIN
5%
5%0 1/16W
5%0 1/16W
1/16W5%
0
CHIP
1/16W
5% 1/16W0
CHIP
0
0402LF 1/16W0 5%
0
0
IO
S O CK E T6096_13568-001
CPU0 MISC 2/2
0402LF
IR Q_SMI_AC TIVE_N
FM_SMM_C R ASH D U MP
CP U0_P W R_G D_O UT
CP U0_P W R_G O O D
5%
CO NN6_HB C1031-L200D-8H
X TA L_CP U0_X 32K _X 2
X TA L_CP U0_X 32K _X 1
CP U0_NMI_S Y NC_FLO O D_N
RS T_CP U0_RS MRS T_N
1000P F
X 7R
X TA L_CP U0_X 32K _X 2
SMLF
IC
FM_INT_CP U0_HP _UB M_N
I3C_0_S P D_DDRA F_CP U0_R_S CL
E MP TY
4.7K
E MP TY
4.7K
CP U0_S LP _S 3_N
4.7K
E MP TY E MP TY
4.7K 4.7K
E MP TY
4.7K
CHIPCHIP
4.7K
4.7K
4.7K
4.7K
4.7K
0CLK _100M_RE F_O UT_DN CLK _100M_RE F_IN_DN
0CLK _100M_RE F_O UT_DP CLK _100M_RE F_IN_DP
0
0 B O O T_RDY _R_H
0 S MB _CP U_5_R_S DAS MB _CP U_5_S DA
0 S MB _CP U0_4_R_S DAS MB _CP U0_4_S DA
0 S MB _CP U0_4_R_S CLS MB _CP U0_4_S CL
FM_P A S S W O RD_CLE A R_R_N
0S MB _CP U0_2_S CL
S MB _CP U0_2_R_S DAS MB _CP U0_2_S DA
0S MB _CP U0_3_S CL
0S MB _CP U0_3_S DA
E MP TY
1K
1%
1K
E MP TY
1%
1K
E MP TY
1%
1K
E MP TY
1%
FM_CP U0_S LP _S 5_N CP U0_S LP _S 5_N
FM_CP U0_S LP _S 3_N CP U0_S LP _S 3_N
CP U0_P W R_G D_O UT CP U1_P W R_G D_IN
S MB _CP U0_S E C_S DA
20M
0402LF
0402LF
CLK _100M_CP U0_CLK 02_R_DN
CLK _100M_CP U0_CLK 02_R_DP
33
0402LFCLK _100M_CP U0_CLK 01_R_DP
0402LF
0402LF
CLK _100M_CP U0_CLK 03_R_DP
CLK _100M_CP U0_CLK 03_R_DN
4.7K
2.2K
CP U0_S LP _S 5_N
4.7K
E MP TY
4.7K4.7K
E MP TY
FM_INT_CP U0_HP _UB M_N
B O O T_RDY _H
CP U0_NMI_S Y NC_FLO O D_N
4.7K
CP U0_S P D_HO S T_CTRL_N
2.2K
1K
I3C_0_S P D_DDRA F_CP U0_R_S CL
I3C_1_S P D_DDRG L_CP U0_R_S DA
FM_B O A RD_S K U_ID1
IRQ _TP M_S P I_R_N
IRQ _B MC_S MI_N
FM_SMM_C R ASH D U MP
FM_P A S S W O RD_CLE A R_N
CP U0_S P D_HO S T_CTRL_N
0
RS T_CP U0_S Y S _N
CP U0_P W R_B TN_N
0402
FM_B IO S _P O S T_CMP LT_R_N
1/16W
5%
2.2K
CHIP
I3C_1_S P D_DDRG L_CP U0_R_S CL
I3C_0_S P D_DDRA F_CP U0_R_S DA
CLK _100M_CP U0_CLK 05_DN
1/16W
5% CLK _100M_CP U0_CLK 12_DN
5%
CLK _100M_CP U0_CLK 04_R_DN
28
28
28
R8305
R8306
21R438
21R6084
21R6083
21R6082
21R6081
2 1 R30
2 1 R29
2 1 R28
2 1 R27
2
1 C5023
R4304
R4303
DJ16
DJ17
DJ13
DJ14
DJ10
DH6
DJ11
DG4
DJ5
B15
D15
D14
B14
DH9
DG10
B67
A19
A20
D69
DH36
DJ8
DH7
DG36
D18
B64
DJ31
B4
A4
B72
C72
A5
C7
B71
A71
DJ20
DJ21
DH12
DG12
DJ51
DJ50
DJ48
DJ47
DJ53
DJ54
DJ45
DJ44
DJ41
DJ42
B9
C9
B12
C12
A10
A11
B6
C6
A8
A7DJ35
B63
B16
A13
C14
A14
DH15
DH16
DG32
DG31
DF31
DE30
DH30
DJ29
DG11
DE32
DF33
DH4
DE40
DF40
DF36
DE36
U25
R9276
R9275
21R434
R4536
R4535
R8565
R8563
R9274
R9273
R2659
21 R249
21
R432
31
42
Y2
2 1R1205
2 1 R430
2 1 R431
2 1 R213
2 1R940
2 1R939
21R938
R445 R447R446
R5029R5028R5027
21R442
21R441
21R448
21R449
21R450
21R451
21R452
21R207
R444R288R276
R5026R440R287
R581
R582
2
1
R424
2
1
R422
6 5
4 3
2 1
J6
2
1 R423
2
1 R421
21R436
21R435
R8564
R8566
R2660
21
Y3
21 R248
2 1 R212
21R443
2
1 R425
2
1 R420
21
21
21
21
21
21
21
21
21
21
21
21
2121
C215
21
21
21
R433
R5102
DESIGN NOTE:
6 5
4 3
2 1
21/40
AGPIO7
NMI_SYNC_FLOOD_L
SEC_SCL||AGPIO262
SEC_SDA||AGPIO263
AGPIO257||SGPIO1_CLK||CLK_REQ01_L
PWROK||SVI_RST_L
AGPIO6||DEVSLP1||SATA_ZP1_L
AGPIO5||DEVSLP0||SATA_ZP0_L
GENINT_L||PM_INTR_L||UBM_CPRSNT_CHANGE_DET_L||AGPIO89
AGPIO22
AGPIO88
AGPIO21
AGPIO87
AGPIO109
AGPIO107
AGPIO106
AGPIO105
AGPIO104
RESET_L
REFCLK100SSC_N||GPP_CLK10N
REFCLK100SSC_P||GPP_CLK10P
SMERR_L||AGPIO24
I2C5_SDA||BMC_SDA||SMBUS1_SDA||AGPIO20
I2C5_SCL||BMC_SCL||SMBUS1_SCL||AGPIO19
I2C4_SDA||HP_SDA||UBM_SDA||AGPIO14
I2C4_SCL||HP_SCL||UBM_SCL||AGPIO13
I3C3_SCL||I2C3_SCL||SPD3_SCL||AGPIO151
I3C1_SDA||I2C1_SDA||SPD1_SDA||AGPIO148
AGPIO116||CLK_REQ12_L
PWRGD_OUT||AGPIO12
AGPIO259||SGPIO3_CLK
I3C0_SCL||I2C0_SCL||SPD0_SCL||SMBUS0_SCL||AGPIO145
I3C2_SCL||I2C2_SCL||SPD2_SCL||AGPIO149
I3C1_SCL||I2C1_SCL||SPD1_SCL||AGPIO147
I3C0_SDA||I2C0_SDA||SPD0_SDA||SMBUS0_SDA||AGPIO146
AGPIO115||CLK_REQ11_L
PCIE_RST0_L||AGPIO266
AGPIO256||SGPIO0_CLK
AGPIO258||SGPIO2_CLK||CLK_REQ02_L
I3C3_SDA||I2C3_SDA||SPD3_SDA||AGPIO152
SGPIO_DATAOUT||AGPIO260
I3C2_SDA||I2C2_SDA||SPD2_SDA||AGPIO150
SGPIO_LOAD||AGPIO261
PCIE_RST1_L||AGPIO26
AGPIO3||SPD_HOST_CTRL_L
AGPIO4||SATA_ACT_L
GPP_CLK11P
GPP_CLK01P
GPP_CLK12P
GPP_CLK02P
GPP_CLK11N
GPP_CLK13P
GPP_CLK01N
GPP_CLK03P
GPP_CLK12N
GPP_CLK14P
GPP_CLK02N
GPP_CLK04P
GPP_CLK13N
GPP_CLK15P
GPP_CLK03N
GPP_CLK05P
GPP_CLK14N
GPP_CLK04N
GPP_CLK15N
GPP_CLK05N
RTCCLK
FORCE_SELFREFRESH
NV_SAVE_L
PWR_BTN_L||AGPIO0
X48M_X2
X48M_X1
X32K_X2
X32K_X1
WAKE_L||AGPIO2
SYS_RESET_L||AGPIO1
SLP_S5_L
SLP_S3_L
RSMRST_L
PWR_GOOD
21
X2
G2G1
X1
2
1
2
1 2
1 C216
2
1
2
1
R6502 2
1
21
21
21
21
21
21
21
21
21
21
21
21
21
21
1
SHEETDATE
23
7 3 2 16 5 4
E
A
B
C
E
D
C
B
A
7 6 5 4
D
DEPARTMENT
SIZE
PROJECT DOCUMENT NUMBER REV
REVIEWER
DESIGNER
IN
OUT
IN
OUT
IN
IN
IN
OUT
BI
BI
OUT
OUT
OUT
OUT
IN
IN
OUT
OUT
OUT
OUT
OUT
OUT
OUT
OUT
OUT
OUT
OUT
OUT
BI
IN
IN
IN
IN
IN
OUT
OUT
OUT
OUT
OUT
OUT
OUT
OUT
IN
OUT
OUT
OUT
OUT
OUT
OUT
OUT
OUT
OUT
OUT
OUT
OUT
OUT
BI
BI
OUT
IN
OUT
OUT
OUT
OUT
OUT
BI
IN
IN
IN
OUT
OUT
IN
IN
IN
IN
IN
OUT
IN
IN
IN
IN
OUT
OUT
BI
OUT
BI
OUT
OUT
OUT
OUT
OUT
OUT
IN
OUT
OUT
OUT
OUT
OUT
OUT
C214C213
C



PU AT DC-SCM SIDE
TBC
TO SCM USB CONN
TO SCM BMC
TO OCP V3_2
TBC
FROM DC-SCM
TO DC-SCM
TO OCP SFF
CAD NOTE: R462 R1592 CO-LAY
CAD NOTE: R472 R1593 CO-LAY
Thu Aug 24 14:08:38 2023<NAME_2>
<NAME_1>
MB FABCGTI V02
29 OF 365
G ND
P 1V 8_A UX
P V DD18_S 5_P 0
P V DD18_S 5_P 0
P V DD18_S 5_P 0
7681150
2981150
76
77
29153
29 81 150
29 81 150
29 153
29 81 150
29 81 150
29 81 150
29 81 150
2981150
2981150
8183 29
2981150
2981150
77
77
29
180
77
150
137
137
131
131
180
180
180
180
150
180
77
77
77
2981150
8183
7677
0CLK _E S P I_CP U0_CLK 1 CLK _E S P I_CP U0_R_CLK 1
0RS T_E S P I_CP U0_RS TO UT_N
P D_E S P I_CP U0_CLK 2
33S P I_CP U0_TP M_CS _N
CP U0_E S P I0_A LE RT_N
E S P I_CP U0_R_A LE RT_N
E S P I_CP U0_R_D2
E S P I_CP U0_R_D3
33
E MP TY33E S P I_CP U0_A LE RT_P 0_N
RS T_E S P I_CP U0_RS TO UT_N
E S P I_CP U0_CS 1_N
5%
1/16W
0402LF
E S P I_CP U0_A LE RT_P 0_N
E S P I_CP U0_D3
E S P I_CP U0_D2
E S P I_CP U0_D1
E S P I_CP U0_D0
30K
30K
CHIP
CHIP
E S P I_CP U0_D3
E S P I_CP U0_D2 33
E S P I_CP U0_R_D1
S CM_US B _O C_N S CM_US B _O C_B U_R_N S CM_US B _O C_B UF_N
25V
0.1UF
10%
0402
X 7R
0
10K
1/16W
CHIP
5%
0402LF
S N74LV C1G 07DB V R
S MLF
IC
33
E S P I_CP U0_D0
33
33
E S P I_CP U0_R_D0
E S P I_CP U0_D1
30K E MP TY
CHIP30K
30K
CHIP
S P I_CP U0_CS 1_N
33E MP TY
SMLF
CPU0 SPI/USB
S P I_CP U0_D1
S CM_US B _O C_B UF_N
S O CK E T6096_13568-001
US B 2_CP U0_P 0_DP
IO
49.9
1/16W
4.7K
E MP TY
5%
0402LF
4.7K
E MP TY
RS T_E S P I_CP U0_R_RS TO UT_N
33
33 S P I_CP U0_R_CS 0_N
33
33
33
S P I_CP U0_D3
S P I_CP U0_R_TP M_CS _N
US B 2_CP U0_P 1_DP
US B 2_CP U0_P 10_DP
US B 2_CP U0_P 10_DN
US B 2_CP U0_P 11_DP
US B 2_CP U0_P 11_DN
U SB3_C PU 0_BMC _TX_D N
U SB3_C PU 0_BMC _TX_D P
U SB3_C PU 0_BMC _R X_H U B_C _D P
U SB3_C PU 0_BMC _R X_H U B_C _D N
US B 2_CP U0_P 1_DN
US B 2_CP U0_P 0_DN
S P I_CP U0_D0
S P I_CP U0_D2
S P I_CP U0_R_D3
S P I_CP U0_CS 0_N
E S P I_CP U0_CS 1_N
RS T_CP U0_K B RS T_R_N
33
S P I_CP U0_R_D0
S P I_CP U0_R_D1
S P I_CP U0_R_D2
S P I_CP U0_R_CS 1_N
NC_CP U0_S P I_CS 2_N
S P I_CP U0_R_CLKS P I_CP U0_CLK 33
CP U0_E S P I_CS 0_N
E S P I_CP U0_R_CS 1_N
R473
R472
R1593
R1592
R462
21 R475
21 R467
21 R466
21 R465
21 R464
21 R461
21 R460
21 R459
21 R458
21 R1506
21 R1505
21 R1504
21 R1503
2
1
R454
2
1
C30
21
R589
4
5
13
2
U3
21 R474
21 R471
21 R468
21 R469
21 R470
DG58
DH58
DJ62
DH62
DH40
DH60
DJ60
DH69
DJ69
DJ65
DH65
DG40
DJ67
DH67
E30
E29
C29
C28
E24
A28
A29
C25
C26
E27
E26
E23
A26
A25
DH27
DG26
DF30
DE27
DJ26
DJ23
DG28
DF27
DG23
DJ27
DG25
DF25
DE24
DH24
DF24
DG29
DJ28
DG22
DF28
DJ22
DJ25
U25
2
1
R455
2
1
R457
NC
Y
GND
A
VCC
22/40
ESPI_RSTOUT_L||AGPIO23
ESPI_CLK1||SPI_CLK1||AGPIO75
ESPI_CLK2||AGPIO74
ESPI0_ALERT_L||AGPIO108
AGPIO76||SPI_TPM_CS_L
ESPI_CLK0||SPI_CLK0||AGPIO117
ESPI1_ALERT_L||AGPIO110
ESPI_RSTIN_L||KBRST_L||AGPIO129
USB01_OC_L||AGPIO265
SPI_CS1_L||AGPIO119
SPI_CS2_L||AGPIO126
ESPI0_DAT0||SPI0_DAT0||AGPIO120
ESPI0_DAT1||SPI0_DAT1||AGPIO121
ESPI0_DAT2||SPI0_DAT2||AGPIO122
ESPI0_DAT3||SPI0_DAT3||AGPIO123
ESPI1_DAT2||SPI1_DAT2||AGPIO133
ESPI1_DAT3||SPI1_DAT3||AGPIO134
ESPI_CS1_L||AGPIO125
ESPI1_DAT0||SPI1_DAT0||AGPIO131
ESPI1_DAT1||SPI1_DAT1||AGPIO132
SPI_CS0_L||AGPIO118
USB00_OC_L||AGPIO264
ESPI_CS0_L||AGPIO124
USB11_OC_L||AGPIO17
USB10_OC_L||AGPIO16
USB11_TXP
USB11_TXN
USB11_RXP
USB11_RXN
USB11_DP
USB11_DN
USB10_TXP
USB10_TXN
USB10_RXP
USB10_RXN
USB10_DP
USB10_DN
USB01_TXP
USB01_TXN
USB01_RXP
USB01_RXN
USB01_DP
USB01_DN
USB00_TXP
USB00_TXN
USB00_RXP
USB00_RXN
USB00_DP
USB00_DN
21
21
21
21
21
1
SHEETDATE
23
7 3 2 16 5 4
E
A
B
C
E
D
C
B
A
7 6 5 4
D
DEPARTMENT
SIZE
PROJECT DOCUMENT NUMBER REV
REVIEWER
DESIGNER
OUT
BI
BI
IN
IN
OUT
OUT
OUT
OUT
OUT
OUT
OUT
OUT
OUTIN
IN
BI
BI
BI
BI
BI
BI
OUT
OUT
IN
OUT
BI
BI
BI
BI
BI
BI
BI
BI
IN
OUT
OUT
OUT
OUT
OUT
C



Thu Aug 24 14:08:38 2023<NAME_2>
<NAME_1>
MB FABCGTI V02
30 OF 365
P V DDCR_S O C_P 0 P V DDCR_S O C_P 0
P V DD_33_S 5
P V DD18_S 5_P 0
P V DD11_S 3_P 0
P V DDCR_CP U0_P 0
P V DDCR_CP U1_P 0
P V DDCR_CP U1_P 0
P V DDCR_CP U0_P 0
P 1V 5_B A T
P V DDIO _P 0
S O CK E T6096_13568-001
S O CK E T6096_13568-001
S O CK E T6096_13568-001
S O CK E T6096_13568-001
S O CK E T6096_13568-001
IO
IO
IO
IO
IO
CPU0 POWER
SMLF
SMLFSMLF
SMLFSMLF
Y19
Y12
Y5
V22
U18
U11
U4
P22
P19
P12
P5
L18
L11
L4
K22
H19
H12
H5
E11
E4
C4
BM 5
BJ48
BJ11
BJ4
BH48
BH25
BH23
BG48
BG28
BG26
BG24
BG22
BF48
BF27
BF25
BF23
BD48
BD28
BD26
BD24
BD22
BD19
BD12
BD5
BC48
BC27
BC25
BC23
BB49
BB28
BB26
BB24
BB22
BA48
BA27
BA25
BA23
BA18
BA11
BA4
B5
AY49
AY28
AY26
AY24
AY22
AW48
AW27
AW25
AW23
AV47
AV45
AV43
AV41
AV39
AV36
AV34
AV32
AV30
AV28
AV26
AV24
AV22
AV19
AV12
AV5
AU40
AU35
AU31
AU27
AU23
AT 22
AR18
AR11
AR4
AM 22
AM 19
AM 12
AM 5
AJ18
AJ11
AJ4
AH22
AF19
AF12
AF5
AD22
AC18
AC11
AC4
AA22
U25
DH57
DH56
DH54
DH53
DH51
DH50
DH48
DH47
DH45
DH44
DH42
DH41
DH35
DH34
DH32
DH31
DH29
DH28
DH26
DH25
DH23
DH22
DH20
DH19
DG57
DG19
DE54
DE51
DE48
DE45
DE42
DE41
DE35
DE34
DE31
DE28
DE25
DE22
DD54
DD51
DD48
DD45
DD42
DD34
DD31
DD28
DD25
DD22
DC41
DC40
DC36
DC35
DB53
DB52
DB50
DB49
DB47
DB46
DB44
DB43
DB33
DB32
DB30
DB29
DB27
DB26
DB24
DB23
DA41
DA40
DA36
DA35
CV53
CV52
CV50
CV49
CV47
CV46
CV44
CV43
CV33
CV32
CV30
CV29
CV27
CV26
CV24
CV23
CU41
CU40
CU36
CU35
CP53
CP52
CP50
CP49
CP47
CP46
CP44
CP43
CP33
CP32
CP30
CP29
CP27
CP26
CP24
CP23
CN41
CN40
CN36
CN35
CL47
CL46
CL44
CL43
CL33
CL32
CL30
CL29
CK41
CK40
CK36
CK35
CH53
CH52
CH50
CH49
CH47
CH46
CH44
CH43
CH33
CH32
CH30
CH29
CH27
CH26
CH24
CH23
CG41
CG40
CG36
CG35
CD53
CD52
CD50
CD49
CD47
CD46
CD44
CD43
CD33
CD32
CD30
CD29
CD27
CD26
CD24
CD23
CC41
CC40
CC36
CC35
BY53
BY52
BY50
BY49
BY47
BY46
BY44
BY43
BY33
BY32
BY30
BY29
BY27
BY26
BY24
BY23
BW41
BW40
BW36
BW35
BT 53
BT 52
BT 50
BT 49
BT 47
BT 46
BT 44
BT 43
BT 33
BT 32
BT 30
BT 29
BT 27
BT 26
BT 24
BT 23
BR52
BR50
BR48
BR46
BR44
BR42
BR40
BR35
BR33
BR31
BR29
BR27
BR25
BR23
BP49
BP47
BP45
BP43
BP41
BP39
BP36
BP34
BP32
BP30
BP28
BP26
BP24
BN50
BN46
BN42
BN35
BN31
BN27
U25
Y41
Y40
Y36
Y35
W47
W46
W44
W43
W33
W32
W30
W29
U41
U40
U36
U35
T 53
T 52
T 50
T 49
T 47
T 46
T 44
T 43
T 33
T 32
T 30
T 29
T 27
T 26
T 24
T 23
N41
N40
N36
N35
M 53
M 52
M 50
M 49
M 47
M 46
M 44
M 43
M 33
M 32
M 30
M 29
M 27
M 26
M 24
M 23
J41
J40
J36
J35
H53
H52
H50
H49
H47
H46
H44
H43
H33
H32
H30
H29
H27
H26
H24
H23
G41
G40
G36
G35
F54
F51
F48
F45
F42
F34
F31
F28
F25
F22
E54
E51
E48
E45
E42
E35
E34
E31
E28
E25
E22
D56
D55
C20
B57
B56
B54
B53
B51
B50
B48
B47
B45
B44
B42
B41
B35
B34
B32
B31
B29
B28
B26
B25
B23
B22
B20
B19
AU48
AU46
AU44
AU42
AU33
AU29
AU25
AT 49
AT 47
AT 45
AT 43
AT 41
AT 39
AT 36
AT 34
AT 32
AT 30
AT 28
AT 26
AT 24
AR50
AR48
AR46
AR44
AR42
AR40
AR35
AR33
AR31
AR29
AR27
AR25
AR23
AP53
AP52
AP50
AP49
AP47
AP46
AP44
AP43
AP33
AP32
AP30
AP29
AP27
AP26
AP24
AP23
AL41
AL40
AL36
AL35
AK53
AK52
AK50
AK49
AK47
AK46
AK44
AK43
AK33
AK32
AK30
AK29
AK27
AK26
AK24
AK23
AG41
AG40
AG36
AG35
AF53
AF52
AF50
AF49
AF47
AF46
AF44
AF43
AF33
AF32
AF30
AF29
AF27
AF26
AF24
AF23
AC41
AC40
AC36
AC35
AB53
AB52
AB50
AB49
AB47
AB46
AB44
AB43
AB33
AB32
AB30
AB29
AB27
AB26
AB24
AB23
U25
DJ57
B36
D23
DG42
DH14
C59
C23
DF41
DH13
C58
E36
E33
DJ4
DH21
DH17
DG17
D72
D65
D62
D58
D36
D34
D22
D11
D8
D4
C54
C53
C35
C34
C31
BD72
BD69
BD65
BD62
BD58
BD55
BD21
BD18
BD14
BD11
BD7
BD4
B40
A60
A59
A57
A56
A55
A54
A51
A50
A48
A45
A42
A41
A35
A31
U25
Y71
Y64
Y57
V54
U72
U65
U58
P71
P64
P57
P54
L72
L65
L58
K54
H71
H64
H57
DG71
DG64
DE72
DE65
DE58
DB71
DB64
DB57
CY54
CW72
CW65
CW58
CT 71
CT 64
CT 57
CT 54
CN72
CN65
CN58
CM 54
CK71
CK64
CK57
CJ54
CG72
CG65
CG58
CF54
CD71
CD64
CD57
CB54
CA72
CA65
CA58
BV71
BV64
BV57
BV54
BR72
BR65
BR58
BN54
BM 71
BM 64
BM 57
BM 53
BM 51
BL54
BL52
BL50
BK53
BK51
BJ72
BJ65
BJ58
BJ54
BJ52
BJ50
BH53
BH51
BG54
BG52
BG50
BF71
BF64
BF57
BF53
BF51
BD54
BD52
BD50
BA72
BA65
BA58
AV71
AV64
AV57
BH27
AR72
AR65
AR58
AM 71
AM 64
AM 57
AM 54
AJ72
AJ65
AJ58
AH54
AF71
AF64
AF57
AD54
AC72
AC65
AC58
AA54
BN23
BP51
BN52
BC54
BC52
BB53
BB51
BA54
BA52
BA50
AY53
AY51
AW54
AW52
AW50
AV53
AV51
AV49
AU54
AU52
AU50
AT 53
AT 51
AR54
AR52
DG5
DE18
DE11
DE4
DB19
DB12
DB5
CY22
CW18
CW11
CW4
CT 22
CT 19
CT 12
CT 5
CN18
CN11
CN4
CM 22
CK19
CK12
CK5
CJ22
CG18
CG11
CG4
CF22
CD19
CD12
CD5
CB22
CA18
CA11
CA4
BV22
BV19
BV12
BV5
BR18
BR11
BR4
BP22
BN48
BN44
BN40
BN33
BN29
BN25
BM 49
BM 47
BM 45
BM 43
BM 41
BM 39
BM 36
BM 34
BM 32
BM 30
BM 28
BM 26
BM 24
BM 22
BM 19
BM 12
BL48
BL27
BL25
BL23
BK49
BK28
BK26
BK24
BK22
BJ27
BJ25
BJ23
BJ18
U25
26/40
VDDCR_SOC_BG22
VDDCR_SOC_BG24
VDDCR_SOC_BG26
VDDCR_SOC_BG28
VDDCR_SOC_BG48
VDDCR_SOC_BH23
VDDCR_SOC_BH25
VDDCR_SOC_BH48
VDDCR_SOC_BJ4
VDDCR_SOC_BJ11
VDDCR_SOC_BJ48
VDDCR_SOC_BM5
VDDCR_SOC_BF48
VDDCR_SOC_BF27
VDDCR_SOC_BF25
VDDCR_SOC_BF23
VDDCR_SOC_BD48
VDDCR_SOC_BD28
VDDCR_SOC_BD26
VDDCR_SOC_BD24
VDDCR_SOC_BD22
VDDCR_SOC_BD19
VDDCR_SOC_BD12
VDDCR_SOC_BD5
VDDCR_SOC_BC48
VDDCR_SOC_BC27
VDDCR_SOC_BC25
VDDCR_SOC_BC23
VDDCR_SOC_BB49
VDDCR_SOC_BB28
VDDCR_SOC_BB26
VDDCR_SOC_BB24
VDDCR_SOC_BB22
VDDCR_SOC_BA48
VDDCR_SOC_BA27
VDDCR_SOC_BA25
VDDCR_SOC_BA23
VDDCR_SOC_BA18
VDDCR_SOC_BA11
VDDCR_SOC_BA4
VDDCR_SOC_AY49
VDDCR_SOC_AY28
VDDCR_SOC_AY26
VDDCR_SOC_AY24
VDDCR_SOC_AY22
VDDCR_SOC_AW48
VDDCR_SOC_AW27
VDDCR_SOC_AW25
VDDCR_SOC_AW23
VDDCR_SOC_AV47
VDDCR_SOC_AV45
VDDCR_SOC_AV43
VDDCR_SOC_AV41
VDDCR_SOC_AV39
VDDCR_SOC_AV36
VDDCR_SOC_AV34
VDDCR_SOC_AV32
VDDCR_SOC_AV30
VDDCR_SOC_AV28
VDDCR_SOC_AV26
VDDCR_SOC_AV24
VDDCR_SOC_AV22
VDDCR_SOC_AV19
VDDCR_SOC_AV12
VDDCR_SOC_AV5
VDDCR_SOC_AU40
VDDCR_SOC_AU35
VDDCR_SOC_AU31
VDDCR_SOC_AU27
VDDCR_SOC_AU23
VDDCR_SOC_AT22
VDDCR_SOC_AR18
VDDCR_SOC_AR11
VDDCR_SOC_AR4
VDDCR_SOC_AM22
VDDCR_SOC_AM19
VDDCR_SOC_AM12
VDDCR_SOC_AM5
VDDCR_SOC_AJ18
VDDCR_SOC_AJ11
VDDCR_SOC_AJ4
VDDCR_SOC_AH22
VDDCR_SOC_AF19
VDDCR_SOC_AF12
VDDCR_SOC_AF5
VDDCR_SOC_AD22
VDDCR_SOC_AC18
VDDCR_SOC_AC11
VDDCR_SOC_AC4
VDDCR_SOC_AA22
VDDCR_SOC_Y19
VDDCR_SOC_Y12
VDDCR_SOC_Y5
VDDCR_SOC_V22
VDDCR_SOC_U18
VDDCR_SOC_U11
VDDCR_SOC_U4
VDDCR_SOC_P22
VDDCR_SOC_P19
VDDCR_SOC_P12
VDDCR_SOC_P5
VDDCR_SOC_L18
VDDCR_SOC_L11
VDDCR_SOC_L4
VDDCR_SOC_K22
VDDCR_SOC_H19
VDDCR_SOC_H12
VDDCR_SOC_H5
VDDCR_SOC_E11
VDDCR_SOC_E4
VDDCR_SOC_C4
VDDCR_SOC_B5
25/40
VDDCR_CPU1_BN46
VDDCR_CPU1_BN35
VDDCR_CPU1_BN27
VDDCR_CPU1_BP32
VDDCR_CPU1_BP28
VDDCR_CPU1_BP24
VDDCR_CPU1_DH51
VDDCR_CPU1_DH50
VDDCR_CPU1_DH48
VDDCR_CPU1_DH47
VDDCR_CPU1_DH45
VDDCR_CPU1_DH57
VDDCR_CPU1_DH56
VDDCR_CPU1_DH54
VDDCR_CPU1_DH53
VDDCR_CPU1_DH44
VDDCR_CPU1_DH42
VDDCR_CPU1_DH41
VDDCR_CPU1_DH35
VDDCR_CPU1_DH34
VDDCR_CPU1_DH32
VDDCR_CPU1_DH31
VDDCR_CPU1_DH29
VDDCR_CPU1_DH28
VDDCR_CPU1_DH26
VDDCR_CPU1_DH25
VDDCR_CPU1_DH23
VDDCR_CPU1_DH22
VDDCR_CPU1_DH20
VDDCR_CPU1_DH19
VDDCR_CPU1_DG57
VDDCR_CPU1_DG19
VDDCR_CPU1_DE54
VDDCR_CPU1_DE51
VDDCR_CPU1_DE48
VDDCR_CPU1_DE45
VDDCR_CPU1_DE42
VDDCR_CPU1_DE41
VDDCR_CPU1_DE35
VDDCR_CPU1_DE34
VDDCR_CPU1_DE31
VDDCR_CPU1_DE28
VDDCR_CPU1_DE25
VDDCR_CPU1_DE22
VDDCR_CPU1_DD54
VDDCR_CPU1_DD51
VDDCR_CPU1_DD48
VDDCR_CPU1_DD45
VDDCR_CPU1_DD42
VDDCR_CPU1_DD34
VDDCR_CPU1_DD31
VDDCR_CPU1_DD28
VDDCR_CPU1_DD25
VDDCR_CPU1_DD22
VDDCR_CPU1_DC41
VDDCR_CPU1_DC40
VDDCR_CPU1_DC36
VDDCR_CPU1_DC35
VDDCR_CPU1_DB53
VDDCR_CPU1_DB52
VDDCR_CPU1_DB50
VDDCR_CPU1_DB49
VDDCR_CPU1_DB47
VDDCR_CPU1_DB46
VDDCR_CPU1_DB44
VDDCR_CPU1_DB43
VDDCR_CPU1_DB33
VDDCR_CPU1_DB32
VDDCR_CPU1_DB30
VDDCR_CPU1_DB29
VDDCR_CPU1_DB27
VDDCR_CPU1_DB26
VDDCR_CPU1_DB24
VDDCR_CPU1_DB23
VDDCR_CPU1_DA41
VDDCR_CPU1_DA40
VDDCR_CPU1_DA36
VDDCR_CPU1_DA35
VDDCR_CPU1_CV53
VDDCR_CPU1_CV52
VDDCR_CPU1_CV50
VDDCR_CPU1_CV49
VDDCR_CPU1_CV47
VDDCR_CPU1_CV46
VDDCR_CPU1_CV44
VDDCR_CPU1_CV43
VDDCR_CPU1_CV33
VDDCR_CPU1_CV32
VDDCR_CPU1_CV30
VDDCR_CPU1_CV29
VDDCR_CPU1_CV27
VDDCR_CPU1_CV26
VDDCR_CPU1_CV24
VDDCR_CPU1_CV23
VDDCR_CPU1_CU41
VDDCR_CPU1_CU40
VDDCR_CPU1_CU36
VDDCR_CPU1_CU35
VDDCR_CPU1_CP53
VDDCR_CPU1_CP52
VDDCR_CPU1_CP50
VDDCR_CPU1_CP49
VDDCR_CPU1_CP47
VDDCR_CPU1_CP46
VDDCR_CPU1_CP44
VDDCR_CPU1_CP43
VDDCR_CPU1_CP33
VDDCR_CPU1_CP32
VDDCR_CPU1_CP30
VDDCR_CPU1_CP29
VDDCR_CPU1_CP27
VDDCR_CPU1_CP26
VDDCR_CPU1_CP24
VDDCR_CPU1_CP23
VDDCR_CPU1_CN41
VDDCR_CPU1_CN40
VDDCR_CPU1_CN36
VDDCR_CPU1_CN35
VDDCR_CPU1_CL47
VDDCR_CPU1_CL46
VDDCR_CPU1_CL44
VDDCR_CPU1_CL43
VDDCR_CPU1_CL33
VDDCR_CPU1_CL32
VDDCR_CPU1_CL30
VDDCR_CPU1_CL29
VDDCR_CPU1_CK41
VDDCR_CPU1_CK40
VDDCR_CPU1_CK36
VDDCR_CPU1_CK35
VDDCR_CPU1_CH53
VDDCR_CPU1_CH52
VDDCR_CPU1_CH50
VDDCR_CPU1_CH49
VDDCR_CPU1_CH47
VDDCR_CPU1_CH46
VDDCR_CPU1_CH44
VDDCR_CPU1_CH43
VDDCR_CPU1_CH33
VDDCR_CPU1_CH32
VDDCR_CPU1_CH30
VDDCR_CPU1_CH29
VDDCR_CPU1_CH27
VDDCR_CPU1_CH26
VDDCR_CPU1_CH24
VDDCR_CPU1_CH23
VDDCR_CPU1_CG41
VDDCR_CPU1_CG40
VDDCR_CPU1_CG36
VDDCR_CPU1_CG35
VDDCR_CPU1_CD53
VDDCR_CPU1_CD52
VDDCR_CPU1_CD50
VDDCR_CPU1_CD49
VDDCR_CPU1_CD47
VDDCR_CPU1_CD46
VDDCR_CPU1_CD44
VDDCR_CPU1_CD43
VDDCR_CPU1_CD33
VDDCR_CPU1_CD32
VDDCR_CPU1_CD30
VDDCR_CPU1_CD29
VDDCR_CPU1_CD27
VDDCR_CPU1_CD26
VDDCR_CPU1_CD24
VDDCR_CPU1_CD23
VDDCR_CPU1_CC41
VDDCR_CPU1_CC40
VDDCR_CPU1_CC36
VDDCR_CPU1_CC35
VDDCR_CPU1_BY53
VDDCR_CPU1_BY52
VDDCR_CPU1_BY50
VDDCR_CPU1_BY49
VDDCR_CPU1_BY47
VDDCR_CPU1_BY46
VDDCR_CPU1_BY44
VDDCR_CPU1_BY43
VDDCR_CPU1_BY33
VDDCR_CPU1_BY32
VDDCR_CPU1_BY30
VDDCR_CPU1_BY29
VDDCR_CPU1_BY27
VDDCR_CPU1_BY26
VDDCR_CPU1_BY24
VDDCR_CPU1_BY23
VDDCR_CPU1_BW41
VDDCR_CPU1_BW40
VDDCR_CPU1_BW36
VDDCR_CPU1_BW35
VDDCR_CPU1_BT53
VDDCR_CPU1_BT52
VDDCR_CPU1_BT50
VDDCR_CPU1_BT49
VDDCR_CPU1_BT47
VDDCR_CPU1_BT46
VDDCR_CPU1_BT44
VDDCR_CPU1_BT43
VDDCR_CPU1_BT33
VDDCR_CPU1_BT32
VDDCR_CPU1_BT30
VDDCR_CPU1_BT29
VDDCR_CPU1_BT27
VDDCR_CPU1_BT26
VDDCR_CPU1_BT24
VDDCR_CPU1_BT23
VDDCR_CPU1_BR52
VDDCR_CPU1_BR50
VDDCR_CPU1_BR48
VDDCR_CPU1_BR46
VDDCR_CPU1_BR44
VDDCR_CPU1_BR42
VDDCR_CPU1_BR40
VDDCR_CPU1_BR35
VDDCR_CPU1_BR33
VDDCR_CPU1_BR31
VDDCR_CPU1_BR29
VDDCR_CPU1_BR27
VDDCR_CPU1_BR25
VDDCR_CPU1_BR23
VDDCR_CPU1_BP49
VDDCR_CPU1_BP47
VDDCR_CPU1_BP45
VDDCR_CPU1_BP43
VDDCR_CPU1_BP41
VDDCR_CPU1_BP39
VDDCR_CPU1_BP36
VDDCR_CPU1_BP34
VDDCR_CPU1_BP30
VDDCR_CPU1_BP26
VDDCR_CPU1_BN50
VDDCR_CPU1_BN42
VDDCR_CPU1_BN31
24/40
VDDCR_CPU0_AU33
VDDCR_CPU0_AU25
VDDCR_CPU0_AU48
VDDCR_CPU0_AU44
VDDCR_CPU0_AU29
VDDCR_CPU0_AT49
VDDCR_CPU0_AU46
VDDCR_CPU0_AU42
VDDCR_CPU0_Y35
VDDCR_CPU0_Y36
VDDCR_CPU0_Y40
VDDCR_CPU0_Y41
VDDCR_CPU0_AB23
VDDCR_CPU0_AB24
VDDCR_CPU0_AB26
VDDCR_CPU0_AB27
VDDCR_CPU0_AB29
VDDCR_CPU0_AB30
VDDCR_CPU0_AB32
VDDCR_CPU0_AB33
VDDCR_CPU0_AB43
VDDCR_CPU0_AB44
VDDCR_CPU0_AB46
VDDCR_CPU0_AB47
VDDCR_CPU0_AB49
VDDCR_CPU0_AB50
VDDCR_CPU0_AB52
VDDCR_CPU0_AB53
VDDCR_CPU0_AC35
VDDCR_CPU0_AC36
VDDCR_CPU0_AC40
VDDCR_CPU0_AC41
VDDCR_CPU0_AF23
VDDCR_CPU0_AF24
VDDCR_CPU0_AF26
VDDCR_CPU0_AF27
VDDCR_CPU0_AF29
VDDCR_CPU0_AF30
VDDCR_CPU0_AF32
VDDCR_CPU0_AF33
VDDCR_CPU0_AF43
VDDCR_CPU0_AF44
VDDCR_CPU0_AF46
VDDCR_CPU0_AF47
VDDCR_CPU0_AF49
VDDCR_CPU0_AF50
VDDCR_CPU0_AF52
VDDCR_CPU0_AF53
VDDCR_CPU0_AG35
VDDCR_CPU0_AG36
VDDCR_CPU0_AG40
VDDCR_CPU0_AG41
VDDCR_CPU0_AK23
VDDCR_CPU0_AK24
VDDCR_CPU0_AK26
VDDCR_CPU0_AK27
VDDCR_CPU0_AK29
VDDCR_CPU0_AK30
VDDCR_CPU0_AK32
VDDCR_CPU0_AK33
VDDCR_CPU0_AK43
VDDCR_CPU0_AK44
VDDCR_CPU0_AK46
VDDCR_CPU0_AK47
VDDCR_CPU0_AK49
VDDCR_CPU0_AK50
VDDCR_CPU0_AK52
VDDCR_CPU0_AK53
VDDCR_CPU0_AL35
VDDCR_CPU0_AL36
VDDCR_CPU0_AL40
VDDCR_CPU0_AL41
VDDCR_CPU0_AP23
VDDCR_CPU0_AP24
VDDCR_CPU0_AP26
VDDCR_CPU0_AP27
VDDCR_CPU0_AP29
VDDCR_CPU0_AP30
VDDCR_CPU0_AP32
VDDCR_CPU0_AP33
VDDCR_CPU0_AP43
VDDCR_CPU0_AP44
VDDCR_CPU0_AP46
VDDCR_CPU0_AP47
VDDCR_CPU0_AP49
VDDCR_CPU0_AP50
VDDCR_CPU0_AP52
VDDCR_CPU0_AP53
VDDCR_CPU0_AR23
VDDCR_CPU0_AR25
VDDCR_CPU0_AR27
VDDCR_CPU0_AR29
VDDCR_CPU0_AR31
VDDCR_CPU0_AR33
VDDCR_CPU0_AR35
VDDCR_CPU0_AR40
VDDCR_CPU0_AR42
VDDCR_CPU0_AR44
VDDCR_CPU0_AR46
VDDCR_CPU0_AR48
VDDCR_CPU0_AR50
VDDCR_CPU0_AT24
VDDCR_CPU0_AT26
VDDCR_CPU0_AT28
VDDCR_CPU0_AT30
VDDCR_CPU0_AT32
VDDCR_CPU0_AT34
VDDCR_CPU0_AT36
VDDCR_CPU0_AT39
VDDCR_CPU0_AT41
VDDCR_CPU0_AT43
VDDCR_CPU0_AT45
VDDCR_CPU0_AT47
VDDCR_CPU0_B19
VDDCR_CPU0_B20
VDDCR_CPU0_B22
VDDCR_CPU0_B23
VDDCR_CPU0_B25
VDDCR_CPU0_B26
VDDCR_CPU0_B28
VDDCR_CPU0_B29
VDDCR_CPU0_B31
VDDCR_CPU0_B32
VDDCR_CPU0_B34
VDDCR_CPU0_B35
VDDCR_CPU0_B41
VDDCR_CPU0_B42
VDDCR_CPU0_B44
VDDCR_CPU0_B45
VDDCR_CPU0_B47
VDDCR_CPU0_B48
VDDCR_CPU0_B50
VDDCR_CPU0_B51
VDDCR_CPU0_B53
VDDCR_CPU0_B54
VDDCR_CPU0_B56
VDDCR_CPU0_B57
VDDCR_CPU0_C20
VDDCR_CPU0_D55
VDDCR_CPU0_D56
VDDCR_CPU0_E22
VDDCR_CPU0_E25
VDDCR_CPU0_E28
VDDCR_CPU0_E31
VDDCR_CPU0_E34
VDDCR_CPU0_E35
VDDCR_CPU0_E42
VDDCR_CPU0_E45
VDDCR_CPU0_E48
VDDCR_CPU0_E51
VDDCR_CPU0_E54
VDDCR_CPU0_F22
VDDCR_CPU0_F25
VDDCR_CPU0_F28
VDDCR_CPU0_F31
VDDCR_CPU0_F34
VDDCR_CPU0_F42
VDDCR_CPU0_F45
VDDCR_CPU0_F48
VDDCR_CPU0_F51
VDDCR_CPU0_F54
VDDCR_CPU0_G35
VDDCR_CPU0_G36
VDDCR_CPU0_G40
VDDCR_CPU0_G41
VDDCR_CPU0_H23
VDDCR_CPU0_H24
VDDCR_CPU0_H26
VDDCR_CPU0_H27
VDDCR_CPU0_H29
VDDCR_CPU0_H30
VDDCR_CPU0_H32
VDDCR_CPU0_H33
VDDCR_CPU0_H43
VDDCR_CPU0_H44
VDDCR_CPU0_H46
VDDCR_CPU0_H47
VDDCR_CPU0_H49
VDDCR_CPU0_H50
VDDCR_CPU0_H52
VDDCR_CPU0_H53
VDDCR_CPU0_J35
VDDCR_CPU0_J36
VDDCR_CPU0_J40
VDDCR_CPU0_J41
VDDCR_CPU0_M23
VDDCR_CPU0_M24
VDDCR_CPU0_M26
VDDCR_CPU0_M27
VDDCR_CPU0_M29
VDDCR_CPU0_M30
VDDCR_CPU0_M32
VDDCR_CPU0_M33
VDDCR_CPU0_M43
VDDCR_CPU0_M44
VDDCR_CPU0_M46
VDDCR_CPU0_M47
VDDCR_CPU0_M49
VDDCR_CPU0_M50
VDDCR_CPU0_M52
VDDCR_CPU0_M53
VDDCR_CPU0_N35
VDDCR_CPU0_N36
VDDCR_CPU0_N40
VDDCR_CPU0_N41
VDDCR_CPU0_T23
VDDCR_CPU0_T24
VDDCR_CPU0_T26
VDDCR_CPU0_T27
VDDCR_CPU0_T29
VDDCR_CPU0_T30
VDDCR_CPU0_T32
VDDCR_CPU0_T33
VDDCR_CPU0_T43
VDDCR_CPU0_T44
VDDCR_CPU0_T46
VDDCR_CPU0_T47
VDDCR_CPU0_T49
VDDCR_CPU0_T50
VDDCR_CPU0_T52
VDDCR_CPU0_T53
VDDCR_CPU0_U35
VDDCR_CPU0_U36
VDDCR_CPU0_U40
VDDCR_CPU0_U41
VDDCR_CPU0_W29
VDDCR_CPU0_W30
VDDCR_CPU0_W32
VDDCR_CPU0_W33
VDDCR_CPU0_W43
VDDCR_CPU0_W44
VDDCR_CPU0_W46
VDDCR_CPU0_W47
23/40
TEST6_X3D6
TEST4_CCD15
TEST4_CCD12
TEST5_CCD12
TEST5_CCD15
TEST4_CCD14
TEST5_CCD14
TEST4_CCD13
TEST5_CCD13
TEST6_X3D7
RSVD_A60
RSVD_BD7
RSVD_D36
RSVD_BD58
RSVD_BD55
RSVD_A54
RSVD_A51
RSVD_A50
RSVD_A48
RSVD_C53
RSVD_A45
RSVD_C35
RSVD_D65
RSVD_A42
RSVD_C34
RSVD_D62
RSVD_BD21
RSVD_A41
RSVD_C31
RSVD_D58
RSVD_BD18
RSVD_DJ4
RSVD_A35
RSVD_B40
RSVD_BD14
RSVD_DH21
RSVD_A31
RSVD_D34
RSVD_BD11
RSVD_DH17
RSVD_A59
RSVD_D22
RSVD_DG17
RSVD_A57
RSVD_D11
RSVD_BD4
RSVD_BD72
RSVD_A56
RSVD_D8
RSVD_E36
RSVD_BD69
RSVD_A55
RSVD_D4
RSVD_E33
RSVD_BD65
RSVD_C54
RSVD_D72
RSVD_BD62
27/40
VDD_11_S3_CT19
VDD_11_S3_CT22
VDD_11_S3_CW4
VDD_11_S3_CW11
VDD_11_S3_CW18
VDD_11_S3_CY22
VDD_11_S3_DB5
VDD_11_S3_DB12
VDD_11_S3_DB19
VDD_11_S3_DE4
VDD_11_S3_DE11
VDD_11_S3_DE18
VDD_11_S3_DG5
VDDIO_CT64
VDDIO_CT71
VDDIO_CW58
VDDIO_CW65
VDDIO_CW72
VDDIO_CY54
VDDIO_DB57
VDDIO_DB64
VDDIO_DB71
VDDIO_DE58
VDDIO_DE65
VDDIO_DE72
VDDIO_DG64
VDDIO_DG71
VDDBT_RTC_G
VDDIO_AUDIO
VDD_33_S5_BP51
VDD_33_S5_BN52
VDD_11_S3_CT12
VDD_18_S5_BB53
VDD_18_S5_BB51
VDD_18_S5_BA54
VDD_18_S5_BA52
VDD_18_S5_BA50
VDD_18_S5_AY53
VDD_18_S5_AY51
VDD_18_S5_AW54
VDD_18_S5_AW52
VDD_18_S5_BC54
VDD_18_S5_BC52
VDD_18_S5_AW50
VDD_18_S5_AV53
VDD_18_S5_AV51
VDD_18_S5_AV49
VDD_18_S5_AU52
VDD_18_S5_AU50
VDD_18_S5_AT53
VDD_18_S5_AT51
VDD_18_S5_AR54
VDD_18_S5_AR52
VDD_18_S5_AU54
VDD_11_S3_CT5
VDD_11_S3_CN18
VDD_11_S3_CN11
VDD_11_S3_CN4
VDD_11_S3_CM22
VDD_11_S3_CK19
VDD_11_S3_CK12
VDD_11_S3_CK5
VDD_11_S3_CJ22
VDD_11_S3_CG18
VDD_11_S3_CG11
VDD_11_S3_CG4
VDD_11_S3_CF22
VDD_11_S3_CD19
VDD_11_S3_CD12
VDD_11_S3_CD5
VDD_11_S3_CB22
VDD_11_S3_CA18
VDD_11_S3_CA11
VDD_11_S3_CA4
VDD_11_S3_BV22
VDD_11_S3_BV19
VDD_11_S3_BV12
VDD_11_S3_BV5
VDD_11_S3_BR18
VDD_11_S3_BR11
VDD_11_S3_BR4
VDD_11_S3_BP22
VDD_11_S3_BN48
VDD_11_S3_BN44
VDD_11_S3_BN40
VDD_11_S3_BN33
VDD_11_S3_BN29
VDD_11_S3_BN25
VDD_11_S3_BM49
VDD_11_S3_BM47
VDD_11_S3_BM45
VDD_11_S3_BM43
VDD_11_S3_BM41
VDD_11_S3_BM39
VDD_11_S3_BM36
VDD_11_S3_BM34
VDD_11_S3_BM32
VDD_11_S3_BM30
VDD_11_S3_BM28
VDD_11_S3_BM26
VDD_11_S3_BM24
VDD_11_S3_BM22
VDD_11_S3_BM19
VDD_11_S3_BM12
VDD_11_S3_BL48
VDD_11_S3_BL27
VDD_11_S3_BL25
VDD_11_S3_BL23
VDD_11_S3_BK49
VDD_11_S3_BK28
VDD_11_S3_BK26
VDD_11_S3_BK24
VDD_11_S3_BK22
VDD_11_S3_BJ27
VDD_11_S3_BJ25
VDD_11_S3_BJ23
VDD_11_S3_BJ18
VDDIO_CT57
VDDIO_CT54
VDDIO_CN72
VDDIO_CN65
VDDIO_CN58
VDDIO_CM54
VDDIO_CK71
VDDIO_CK64
VDDIO_CK57
VDDIO_CJ54
VDDIO_CG72
VDDIO_CG65
VDDIO_CG58
VDDIO_CF54
VDDIO_CD71
VDDIO_CD64
VDDIO_CD57
VDDIO_CB54
VDDIO_CA72
VDDIO_CA65
VDDIO_CA58
VDDIO_BV71
VDDIO_BV64
VDDIO_BV57
VDDIO_BV54
VDDIO_BR72
VDDIO_BR65
VDDIO_BR58
VDDIO_BN54
VDDIO_BM71
VDDIO_BM64
VDDIO_BM57
VDDIO_BM53
VDDIO_BM51
VDDIO_BL54
VDDIO_BL52
VDDIO_BL50
VDDIO_BK53
VDDIO_BK51
VDDIO_BJ72
VDDIO_BJ65
VDDIO_BJ58
VDDIO_BJ54
VDDIO_BJ52
VDDIO_BJ50
VDDIO_BH53
VDDIO_BH51
VDDIO_BG54
VDDIO_BG52
VDDIO_BG50
VDDIO_BF71
VDDIO_BF64
VDDIO_BF57
VDDIO_BF53
VDDIO_BF51
VDDIO_BD54
VDDIO_BD52
VDDIO_BD50
VDDIO_BA72
VDDIO_BA65
VDDIO_BA58
VDDIO_AV71
VDDIO_AV64
VDDIO_AV57
VDDIO_AR72
VDDIO_AR65
VDDIO_AR58
VDDIO_AM71
VDDIO_AM64
VDDIO_AM57
VDDIO_AM54
VDDIO_AJ72
VDDIO_AJ65
VDDIO_AJ58
VDDIO_AH54
VDDIO_AF71
VDDIO_AF64
VDDIO_AF57
VDDIO_AD54
VDDIO_AC72
VDDIO_AC65
VDDIO_AC58
VDDIO_AA54
VDDIO_Y71
VDDIO_Y64
VDDIO_Y57
VDDIO_V54
VDDIO_U72
VDDIO_U65
VDDIO_U58
VDDIO_P71
VDDIO_P64
VDDIO_P57
VDDIO_P54
VDDIO_L72
VDDIO_L65
VDDIO_L58
VDDIO_K54
VDDIO_H71
VDDIO_H64
VDDIO_H57
1
SHEETDATE
23
7 3 2 16 5 4
E
A
B
C
E
D
C
B
A
7 6 5 4
D
DEPARTMENT
SIZE
PROJECT DOCUMENT NUMBER REV
REVIEWER
DESIGNER
C



Thu Aug 24 14:08:39 2023<NAME_2>
<NAME_1>
MB FABCGTI V02
31 OF 365
S O CK E T6096_13568-001S O CK E T6096_13568-001S O CK E T6096_13568-001
S O CK E T6096_13568-001S O CK E T6096_13568-001S O CK E T6096_13568-001 IOIOIO
IO
IO
IO
CPU0 VSS 1/3
SMLFSMLFSMLFSMLFSMLFSMLF
BL24
BL22
BL20
BL18
BL15
BL13
BL11
BL8
BL6
BL4
BL1
BK73
BK71
BK68
BK66
BK64
BK61
BK59
BK57
BK54
BK52
BK50
BK48
BK27
BK25
BK23
BK19
BK17
BK15
BK12
BK10
BK8
BK5
BK3
BJ75
BJ70
BJ68
BJ63
BJ61
BJ56
BJ53
BJ51
BJ49
BJ28
BJ26
BJ24
BJ22
BJ20
BJ15
BJ13
BJ8
BJ6
BJ1
BH73
BH71
BH68
BH66
BH64
BH61
BH59
BH57
BH54
BH52
BH50
BH49
BH28
BH26
BH24
BH22
BH19
BH17
BH15
BH12
BH10
BH8
BH5
BH3
BG75
BG72
BG70
BG68
BG65
BG63
BG61
BG58
BG56
BG53
BG51
BG49
BG27
BG25
BG23
BG20
BG18
BG15
BG13
BG11
BG8
BG6
BG4
BG1
BF73
BF68
BF66
BF61
BF59
BF54
BF52
BF50
BF49
BF28
BF26
BF24
BF22
BF19
BF17
BF15
BF12
BF10
BF8
BF5
BF3
BD73
BD71
BD68
BD66
BD64
BD61
BD59
BD57
BD53
BD51
BD49
BD27
BD25
BD23
BD17
BD15
BD10
BD8
BD3
BC75
BC72
BC70
BC68
BC65
BC63
BC61
BC58
BC56
BC53
BC51
BC50
BC49
BC28
BC26
BC24
BC22
BC20
BC18
BC15
BC13
BC11
BC8
BC6
BC4
BC1
BB73
BB71
BB68
BB66
BB64
BB61
BB59
BB57
BB54
BB52
BB50
BB48
BB27
BB25
BB23
BB19
BB17
BB15
BB12
BB10
BB8
BB5
BB3
BA75
BA70
BA68
BA63
BA61
BA56
BA53
BA51
BA49
BA28
BA26
BA24
BA22
BA20
BA15
BA13
BA8
BA6
BA1
AY73
AY71
AY68
AY66
AY64
AY61
AY59
AY57
AY54
AY52
AY50
AY48
AY27
AY25
AY23
AY19
AY17
AY15
AY12
AY10
AY8
AY5
AY3
AW75
AW72
AW70
AW68
AW65
AW63
U25
AW61
AW58
AW56
AW53
AW51
AW49
AW28
AW26
AW24
AW22
AW20
AW18
AW15
AW13
AW11
AW8
AW6
AW4
AW1
AV73
AV68
AV66
AV61
AV59
AV54
AV52
AV50
AV48
AV46
AV44
AV42
AV40
AV37
AV35
AV33
AV31
AV29
AV27
AV25
AV23
AV17
AV15
AV10
AV8
AV3
AU75
AU73
AU72
AU70
AU68
AU65
AU63
AU61
AU58
AU56
AU53
AU51
AU49
AU47
AU45
AU43
AU41
AU36
AU34
AU32
AU30
AU28
AU26
AU24
AU22
AU20
AU18
AU15
AU13
AU11
AU8
AU6
AU4
AU3
AU1
AT 73
AT 72
AT 71
AT 70
AT 68
AT 67
AT 66
AT 64
AT 63
AT 61
AT 60
AT 59
AT 57
AT 56
AT 54
AT 52
AT 50
AT 48
AT 46
AT 44
AT 42
AT 40
AT 37
AT 35
AT 33
AT 31
AT 29
AT 27
AT 25
AT 23
AT 20
AT 19
AT 17
AT 16
AT 15
AT 13
AT 12
AT 10
AT 9
AT 8
AT 6
AT 5
AT 4
AT 3
AR75
AR71
AR70
AR68
AR67
AR64
AR63
AR61
AR60
AR57
AR56
AR53
AR51
AR49
AR47
AR45
AR43
AR41
AR36
AR34
AR32
AR30
AR28
AR26
AR24
AR22
AR20
AR19
AR16
AR15
AR13
AR12
AR9
AR8
AR6
AR5
AR1
AP73
AP71
AP68
AP66
AP64
AP61
AP59
AP57
AP54
AP51
AP48
AP45
AP42
AP39
AP37
AP34
AP31
AP28
AP25
AP22
AP19
AP17
AP15
AP12
AP10
AP8
AP5
AP3
AN75
AN72
AN70
AN68
AN65
AN63
AN61
AN58
AN56
AN54
AN51
AN48
AN45
AN42
AN41
AN40
AN36
AN35
AN34
AN31
AN28
AN25
AN22
AN18
AN15
AN13
AN11
AN8
AN6
AN4
AN1
AM 73
AM 68
AM 66
AM 61
AM 59
AM 53
AM 52
AM 51
AM 50
AM 49
AM 48
AM 47
AM 46
AM 45
AM 44
AM 43
AM 42
U25
AM 39
AM 34
AM 33
AM 32
AM 31
AM 30
AM 29
AM 28
AM 27
AM 26
AM 25
AM 24
AM 23
AM 17
AM 15
AM 10
AM 8
AM 3
AL75
AL72
AL70
AL68
AL65
AL63
AL61
AL58
AL56
AL54
AL51
AL48
AL45
AL42
AL34
AL31
AL28
AL25
AL22
AL20
AL18
AL15
AL13
AL11
AL8
AL6
AL4
AL1
AK73
AK71
AK68
AK66
AK64
AK61
AK59
AK57
AK54
AK51
AK48
AK45
AK42
AK39
AK37
AK34
AK31
AK28
AK25
AK22
AK19
AK17
AK15
AK12
AK10
AK8
AK5
AK3
AJ75
AJ70
AJ68
AJ63
AJ61
AJ56
AJ54
AJ51
AJ48
AJ45
AJ42
AJ41
AJ40
AJ36
AJ35
AJ34
AJ31
AJ28
AJ25
AJ22
AJ20
AJ15
AJ8
AJ6
AJ1
AH73
AH71
AH68
AH66
AH64
AH61
AH59
AH57
AH53
AH52
AH51
AH50
AH49
AH48
AH47
AH46
AH45
AH44
AH43
AH42
AH39
AH37
AH34
AH32
AH31
AH30
AH29
AH28
AH27
AH26
AH25
AH24
AH23
AH19
AH17
AH15
AH12
AH10
AH8
AH5
AH3
AG75
AG72
AG70
AG68
AG65
AG63
AG61
AG58
AG56
AG54
AG51
AG48
AG45
AG42
AG34
AG31
AG28
AG25
AG22
AG20
AG18
AG15
AG13
AG11
AG8
AG6
AG4
AG1
AF73
AF68
AF66
AF61
AF59
AF54
AF51
AF48
AF45
AF42
AF39
AF37
AF34
AF31
AF28
AF25
AF22
AF17
AF15
AF10
AF8
AF3
AE75
AE72
AE70
AE68
AE65
AE63
AE61
AE58
AE56
AE54
AE51
AE48
AE45
AE42
AE41
AE40
AE36
AE35
AE34
AE31
AE28
AE25
AE22
AE20
AE18
AE15
AE13
AE11
AE8
AE6
AE1
AD73
AD71
AD68
AD66
AD64
AD61
AD59
AD57
AD53
AD52
AD51
AD50
AD49
U25
Y73
Y68
Y66
Y61
Y59
Y54
Y53
Y52
Y51
Y50
Y49
Y48
Y45
Y44
Y43
Y42
Y39
Y37
Y34
Y33
Y32
Y31
Y28
Y27
Y26
Y25
Y24
Y23
Y22
Y17
Y15
Y10
Y8
Y3
W75
W72
W70
W68
W65
W63
W61
W58
W56
W54
W51
W48
W45
W42
W41
W40
W36
W35
W34
W28
W25
W22
W20
W18
W15
W13
W11
W8
W6
W4
W1
V73
V71
V66
V64
V61
V59
V57
V53
V52
V51
V50
V49
V48
V47
V46
V45
V44
V43
V42
V39
V37
V34
V33
V32
V31
V30
V29
V28
V26
V25
V24
V23
V19
V17
V15
V12
V10
V8
V5
V3
U75
U70
U68
U63
U61
U56
U54
U51
U48
U45
U42
U34
U31
U28
U25
U22
U20
U15
U13
U8
U6
U1
T 73
T 71
T 68
T 66
AD48
AD47
AD46
AD45
AD44
AD43
AD42
AD39
AD37
AD34
AD33
AD32
AD30
AD29
AD28
AD27
AD26
AD25
AD24
AD23
AD19
AD17
AD15
AD12
AD10
AD8
AD5
AD3
AC75
AC70
AC68
AC63
AC61
AC56
AC54
AC51
AC48
AC45
AC42
AC34
AC31
AC28
AC25
AC22
AC20
AC15
AC13
AC8
AC6
AC1
AB73
AB71
AB68
AB66
AB64
AB61
AB59
AB57
AB54
AB51
AB48
AB45
AB42
AB39
AB37
AB34
AB31
AB28
AB25
AB22
AB19
AB17
AB15
AB12
AB10
AB8
AB5
AB3
AA75
AA70
AA68
AA65
AA63
AA61
AA58
AA56
AA45
AA41
AA40
AA36
AA35
AA34
AA31
AA20
AA18
AA15
AA13
AA11
AA8
AA6
AA4
AA1
U25
T 64
T 61
T 59
T 57
T 54
T 51
T 48
T 45
T 42
T 39
T 37
T 34
T 31
T 28
T 25
T 22
T 19
T 17
T 15
T 12
T 10
T 8
T 5
T 3
R75
R72
R70
R68
R65
R63
R61
R58
R56
R54
R51
R48
R45
R42
R41
R40
R36
R35
R34
R31
R28
R25
R22
R20
R18
R15
R13
R11
R8
R6
R4
R1
P73
P66
P61
P59
P53
P52
P51
P50
P49
P48
P47
P46
P45
P44
P43
P42
P39
P37
P34
P33
P32
P31
P30
P29
P28
P27
P26
P24
P23
P17
P15
P10
P8
P3
N75
N72
N70
N68
N65
N63
N61
N58
N56
N54
N51
N48
N45
N42
N34
N31
N28
N25
N22
N20
N18
N15
N13
N11
N8
N6
N4
N1
M 73
M 71
M 68
M 66
M 64
M 61
M 59
M 57
M 54
M 51
M 48
M 45
M 42
M 39
M 37
M 34
M 31
M 28
M 25
M 22
M 19
M 17
M 15
M 12
M 10
M 8
M 5
M 3
L75
L70
L68
L63
L61
L56
L54
L51
L48
L45
L42
L41
L40
L36
L35
L34
L31
L28
L25
L22
L20
L15
L13
L8
L6
L1
K73
K71
K68
K66
K64
K61
K57
K53
K52
K51
K50
K49
K48
K47
K46
K45
K44
K43
K42
K39
K37
K34
K33
K32
K31
K30
K29
K28
K27
K26
K25
K24
K19
K17
K15
K12
K10
K8
K5
K3
J75
J72
J70
J68
J65
J63
J61
J58
J56
J54
J51
J48
J45
J42
J34
J31
J28
J25
J22
J20
J18
J15
U25
J13
J11
J8
J6
J4
J1
H73
H68
H66
H61
H59
H54
H51
H48
H45
H42
H39
H37
H34
H31
H28
H25
H22
H17
H15
H10
H8
H3
G75
G72
G70
G68
G65
G63
G61
G58
G56
G54
G51
G48
G45
G42
G34
G31
G28
G25
G22
G20
G18
G15
G13
G11
G8
G6
G4
G1
F73
F71
F68
F66
F64
F61
F59
F57
F53
F52
F50
F49
F47
F46
F44
F43
F41
F40
F39
F37
F36
F35
F33
F32
F30
F29
F27
F26
F24
F23
F19
F17
F15
F12
F10
F8
F5
F3
E75
E73
E72
E70
E69
E68
E66
E65
E63
E62
E61
E59
E58
E56
E55
E53
E52
E21
E20
E18
E17
E15
E14
E13
E10
E8
E7
E6
E3
E1
D74
D73
D71
D70
D67
D66
D64
D63
D61
D60
D59
D57
D54
D53
D52
D51
D50
D49
D48
D47
D46
D45
D44
D43
D42
D41
D40
D39
D37
D35
D31
D30
D29
D28
D27
D26
D25
D24
D21
D20
D19
D17
D16
D13
D12
D10
D9
D6
D5
D3
D2
C75
C73
C71
C69
C67
C64
C61
C57
C56
C55
C52
C49
C46
C43
C40
C36
C30
C27
C24
C21
C15
C13
C11
C10
C8
C5
C1
B70
B68
B65
B62
B59
B55
B52
B49
B46
B43
B39
B37
B33
B30
B27
B24
B18
B13
B11
B10
B8
B7
A73
A72
A67
A61
A53
A49
A47
A44
A43
A27
A21
A15
A9
A3
U25
33/40
VSS_BL24
VSS_BL22
VSS_BL20
VSS_BL18
VSS_BL15
VSS_BL13
VSS_BL11
VSS_BL8
VSS_BL6
VSS_BL4
VSS_BL1
VSS_BK73
VSS_BK71
VSS_BK68
VSS_BK66
VSS_BK64
VSS_BK61
VSS_BK59
VSS_BK57
VSS_BK54
VSS_BK52
VSS_BK50
VSS_BK48
VSS_BK27
VSS_BK25
VSS_BK23
VSS_BK19
VSS_BK17
VSS_BK15
VSS_BK12
VSS_BK10
VSS_BK8
VSS_BK5
VSS_BK3
VSS_BJ75
VSS_BJ70
VSS_BJ68
VSS_BJ63
VSS_BJ61
VSS_BJ56
VSS_BJ53
VSS_BJ51
VSS_BJ49
VSS_BJ28
VSS_BJ26
VSS_BJ24
VSS_BJ22
VSS_BJ20
VSS_BJ15
VSS_BJ13
VSS_BJ8
VSS_BJ6
VSS_BJ1
VSS_BH73
VSS_BH71
VSS_BH68
VSS_BH66
VSS_BH64
VSS_BH61
VSS_BH59
VSS_BH57
VSS_BH54
VSS_BH52
VSS_BH50
VSS_BH49
VSS_BH28
VSS_BH26
VSS_BH24
VSS_BH22
VSS_BH19
VSS_BH17
VSS_BH15
VSS_BH12
VSS_BH10
VSS_BH8
VSS_BH5
VSS_BH3
VSS_BG75
VSS_BG72
VSS_BG70
VSS_BG68
VSS_BG65
VSS_BG63
VSS_BG61
VSS_BG58
VSS_BG56
VSS_BG53
VSS_BG51
VSS_BG49
VSS_BG27
VSS_BG25
VSS_BG23
VSS_BG20
VSS_BG18
VSS_BG15
VSS_BG13
VSS_BG11
VSS_BG8
VSS_BG6
VSS_BG4
VSS_BG1
VSS_BF73
VSS_BF68
VSS_BF66
VSS_BF61
VSS_BF59
VSS_BF54
VSS_BF52
VSS_BF50
VSS_BF49
VSS_BF28
VSS_BF26
VSS_BF24
VSS_BF22
VSS_BF19
VSS_BF17
VSS_BF15
VSS_BF12
VSS_BF10
VSS_BF8
VSS_BF5
VSS_BF3
VSS_BD73
VSS_BD71
VSS_BD68
VSS_BD66
VSS_BD64
VSS_BD61
VSS_BD59
VSS_BD57
VSS_BD53
VSS_BD51
VSS_BD49
VSS_BD27
VSS_BD25
VSS_BD23
VSS_BD17
VSS_BD15
VSS_BD10
VSS_BD8
VSS_BD3
VSS_BC75
VSS_BC72
VSS_BC70
VSS_BC68
VSS_BC65
VSS_BC63
VSS_BC61
VSS_BC58
VSS_BC56
VSS_BC53
VSS_BC51
VSS_BC50
VSS_BC49
VSS_BC28
VSS_BC26
VSS_BC24
VSS_BC22
VSS_BC20
VSS_BC18
VSS_BC15
VSS_BC13
VSS_BC11
VSS_BC8
VSS_BC6
VSS_BC4
VSS_BC1
VSS_BB73
VSS_BB71
VSS_BB68
VSS_BB66
VSS_BB64
VSS_BB61
VSS_BB59
VSS_BB57
VSS_BB54
VSS_BB52
VSS_BB50
VSS_BB48
VSS_BB27
VSS_BB25
VSS_BB23
VSS_BB19
VSS_BB17
VSS_BB15
VSS_BB12
VSS_BB10
VSS_BB8
VSS_BB5
VSS_BB3
VSS_BA75
VSS_BA70
VSS_BA68
VSS_BA63
VSS_BA61
VSS_BA56
VSS_BA53
VSS_BA51
VSS_BA49
VSS_BA28
VSS_BA26
VSS_BA24
VSS_BA22
VSS_BA20
VSS_BA15
VSS_BA13
VSS_BA8
VSS_BA6
VSS_BA1
VSS_AY73
VSS_AY71
VSS_AY68
VSS_AY66
VSS_AY64
VSS_AY61
VSS_AY59
VSS_AY57
VSS_AY54
VSS_AY52
VSS_AY50
VSS_AY48
VSS_AY27
VSS_AY25
VSS_AY23
VSS_AY19
VSS_AY17
VSS_AY15
VSS_AY12
VSS_AY10
VSS_AY8
VSS_AY5
VSS_AY3
VSS_AW75
VSS_AW72
VSS_AW70
VSS_AW68
VSS_AW65
VSS_AW63
32/40
VSS_AW61
VSS_AW58
VSS_AW56
VSS_AW53
VSS_AW51
VSS_AW49
VSS_AW28
VSS_AW26
VSS_AW24
VSS_AW22
VSS_AW20
VSS_AW18
VSS_AW15
VSS_AW13
VSS_AW11
VSS_AW8
VSS_AW6
VSS_AW4
VSS_AW1
VSS_AV73
VSS_AV68
VSS_AV66
VSS_AV61
VSS_AV59
VSS_AV54
VSS_AV52
VSS_AV50
VSS_AV48
VSS_AV46
VSS_AV44
VSS_AV42
VSS_AV40
VSS_AV37
VSS_AV35
VSS_AV33
VSS_AV31
VSS_AV29
VSS_AV27
VSS_AV25
VSS_AV23
VSS_AV17
VSS_AV15
VSS_AV10
VSS_AV8
VSS_AV3
VSS_AU75
VSS_AU73
VSS_AU72
VSS_AU70
VSS_AU68
VSS_AU65
VSS_AU63
VSS_AU61
VSS_AU58
VSS_AU56
VSS_AU53
VSS_AU51
VSS_AU49
VSS_AU47
VSS_AU45
VSS_AU43
VSS_AU41
VSS_AU36
VSS_AU34
VSS_AU32
VSS_AU30
VSS_AU28
VSS_AU26
VSS_AU24
VSS_AU22
VSS_AU20
VSS_AU18
VSS_AU15
VSS_AU13
VSS_AU11
VSS_AU8
VSS_AU6
VSS_AU4
VSS_AU3
VSS_AU1
VSS_AT73
VSS_AT72
VSS_AT71
VSS_AT70
VSS_AT68
VSS_AT67
VSS_AT66
VSS_AT64
VSS_AT63
VSS_AT61
VSS_AT60
VSS_AT59
VSS_AT57
VSS_AT56
VSS_AT54
VSS_AT52
VSS_AT50
VSS_AT48
VSS_AT46
VSS_AT44
VSS_AT42
VSS_AT40
VSS_AT37
VSS_AT35
VSS_AT33
VSS_AT31
VSS_AT29
VSS_AT27
VSS_AT25
VSS_AT23
VSS_AT20
VSS_AT19
VSS_AT17
VSS_AT16
VSS_AT15
VSS_AT13
VSS_AT12
VSS_AT10
VSS_AT9
VSS_AT8
VSS_AT6
VSS_AT5
VSS_AT4
VSS_AT3
VSS_AR75
VSS_AR71
VSS_AR70
VSS_AR68
VSS_AR67
VSS_AR64
VSS_AR63
VSS_AR61
VSS_AR60
VSS_AR57
VSS_AR56
VSS_AR53
VSS_AR51
VSS_AR49
VSS_AR47
VSS_AR45
VSS_AR43
VSS_AR41
VSS_AR36
VSS_AR34
VSS_AR32
VSS_AR30
VSS_AR28
VSS_AR26
VSS_AR24
VSS_AR22
VSS_AR20
VSS_AR19
VSS_AR16
VSS_AR15
VSS_AR13
VSS_AR12
VSS_AR9
VSS_AR8
VSS_AR6
VSS_AR5
VSS_AR1
VSS_AP73
VSS_AP71
VSS_AP68
VSS_AP66
VSS_AP64
VSS_AP61
VSS_AP59
VSS_AP57
VSS_AP54
VSS_AP51
VSS_AP48
VSS_AP45
VSS_AP42
VSS_AP39
VSS_AP37
VSS_AP34
VSS_AP31
VSS_AP28
VSS_AP25
VSS_AP22
VSS_AP19
VSS_AP17
VSS_AP15
VSS_AP12
VSS_AP10
VSS_AP8
VSS_AP5
VSS_AP3
VSS_AN75
VSS_AN72
VSS_AN70
VSS_AN68
VSS_AN65
VSS_AN63
VSS_AN61
VSS_AN58
VSS_AN56
VSS_AN54
VSS_AN51
VSS_AN48
VSS_AN45
VSS_AN42
VSS_AN41
VSS_AN40
VSS_AN36
VSS_AN35
VSS_AN34
VSS_AN31
VSS_AN28
VSS_AN25
VSS_AN22
VSS_AN18
VSS_AN15
VSS_AN13
VSS_AN11
VSS_AN8
VSS_AN6
VSS_AN4
VSS_AN1
VSS_AM73
VSS_AM68
VSS_AM66
VSS_AM61
VSS_AM59
VSS_AM53
VSS_AM52
VSS_AM51
VSS_AM50
VSS_AM49
VSS_AM48
VSS_AM47
VSS_AM46
VSS_AM45
VSS_AM44
VSS_AM43
VSS_AM42
31/40
VSS_AK8
VSS_AK5
VSS_AK3
VSS_AJ75
VSS_AJ70
VSS_AJ68
VSS_AJ63
VSS_AJ61
VSS_AJ56
VSS_AJ54
VSS_AJ51
VSS_AJ48
VSS_AJ45
VSS_AJ42
VSS_AJ41
VSS_AJ40
VSS_AJ36
VSS_AJ35
VSS_AJ34
VSS_AJ31
VSS_AJ28
VSS_AJ25
VSS_AJ22
VSS_AJ20
VSS_AJ15
VSS_AJ8
VSS_AJ6
VSS_AJ1
VSS_AH73
VSS_AH71
VSS_AH68
VSS_AH66
VSS_AH64
VSS_AH61
VSS_AH59
VSS_AH57
VSS_AH53
VSS_AH52
VSS_AH51
VSS_AH50
VSS_AH49
VSS_AH48
VSS_AH47
VSS_AH46
VSS_AH45
VSS_AH44
VSS_AH43
VSS_AH42
VSS_AH39
VSS_AH37
VSS_AH34
VSS_AH32
VSS_AH31
VSS_AH30
VSS_AH29
VSS_AH28
VSS_AH27
VSS_AH26
VSS_AH25
VSS_AH24
VSS_AH23
VSS_AH19
VSS_AH17
VSS_AH15
VSS_AH12
VSS_AH10
VSS_AH8
VSS_AH5
VSS_AH3
VSS_AG75
VSS_AG72
VSS_AG70
VSS_AG68
VSS_AG65
VSS_AG63
VSS_AG61
VSS_AG58
VSS_AG56
VSS_AG54
VSS_AG51
VSS_AG48
VSS_AG45
VSS_AG42
VSS_AG34
VSS_AG31
VSS_AG28
VSS_AG25
VSS_AG22
VSS_AG20
VSS_AG18
VSS_AG15
VSS_AG13
VSS_AG11
VSS_AG8
VSS_AG6
VSS_AG4
VSS_AG1
VSS_AF73
VSS_AF68
VSS_AF66
VSS_AF61
VSS_AF59
VSS_AF54
VSS_AF51
VSS_AF48
VSS_AF45
VSS_AF42
VSS_AF39
VSS_AF37
VSS_AF34
VSS_AF31
VSS_AF28
VSS_AF25
VSS_AF22
VSS_AF17
VSS_AF15
VSS_AF10
VSS_AF8
VSS_AF3
VSS_AE75
VSS_AE72
VSS_AE70
VSS_AE68
VSS_AE65
VSS_AE63
VSS_AE61
VSS_AE58
VSS_AE56
VSS_AE54
VSS_AE51
VSS_AE48
VSS_AE45
VSS_AE42
VSS_AE41
VSS_AE40
VSS_AE36
VSS_AE35
VSS_AE34
VSS_AE31
VSS_AE28
VSS_AE25
VSS_AE22
VSS_AE20
VSS_AE18
VSS_AE15
VSS_AE13
VSS_AE11
VSS_AE8
VSS_AE6
VSS_AE1
VSS_AD73
VSS_AD71
VSS_AD68
VSS_AD66
VSS_AD64
VSS_AD61
VSS_AD59
VSS_AD57
VSS_AD53
VSS_AD52
VSS_AD51
VSS_AD50
VSS_AD49
VSS_AM39
VSS_AM34
VSS_AM33
VSS_AM32
VSS_AM31
VSS_AM30
VSS_AM29
VSS_AM28
VSS_AM27
VSS_AM26
VSS_AM25
VSS_AM24
VSS_AM23
VSS_AM17
VSS_AM15
VSS_AM10
VSS_AM8
VSS_AM3
VSS_AL75
VSS_AL72
VSS_AL70
VSS_AL68
VSS_AL65
VSS_AL63
VSS_AL61
VSS_AL58
VSS_AL56
VSS_AL54
VSS_AL51
VSS_AL48
VSS_AL45
VSS_AL42
VSS_AL34
VSS_AL31
VSS_AL28
VSS_AL25
VSS_AL22
VSS_AL20
VSS_AL18
VSS_AL15
VSS_AL13
VSS_AL11
VSS_AL8
VSS_AL6
VSS_AL4
VSS_AL1
VSS_AK73
VSS_AK71
VSS_AK68
VSS_AK66
VSS_AK64
VSS_AK61
VSS_AK59
VSS_AK57
VSS_AK54
VSS_AK51
VSS_AK48
VSS_AK45
VSS_AK42
VSS_AK39
VSS_AK37
VSS_AK34
VSS_AK31
VSS_AK28
VSS_AK25
VSS_AK22
VSS_AK19
VSS_AK17
VSS_AK15
VSS_AK12
VSS_AK10
30/40
VSS_AB66
VSS_AB64
VSS_AB61
VSS_AB59
VSS_AB57
VSS_AB54
VSS_AB51
VSS_AB48
VSS_AB45
VSS_AB42
VSS_AB39
VSS_AB37
VSS_AB34
VSS_AB31
VSS_AB28
VSS_AB25
VSS_AB22
VSS_AB19
VSS_AB17
VSS_AB15
VSS_AB12
VSS_AB10
VSS_AB8
VSS_AB5
VSS_AB3
VSS_AA75
VSS_AA70
VSS_AA68
VSS_AA65
VSS_AA63
VSS_AA61
VSS_AA58
VSS_AA56
VSS_AA45
VSS_AA41
VSS_AA40
VSS_AA36
VSS_AA35
VSS_AA34
VSS_AA31
VSS_AA20
VSS_AA18
VSS_AA15
VSS_AA13
VSS_AA11
VSS_AA8
VSS_AA6
VSS_AA4
VSS_AA1
VSS_Y73
VSS_Y68
VSS_Y66
VSS_Y61
VSS_Y59
VSS_Y54
VSS_Y53
VSS_Y52
VSS_Y51
VSS_Y50
VSS_Y49
VSS_Y48
VSS_Y45
VSS_Y44
VSS_Y43
VSS_Y42
VSS_Y39
VSS_Y37
VSS_Y34
VSS_Y33
VSS_Y32
VSS_Y31
VSS_Y28
VSS_Y27
VSS_Y26
VSS_Y25
VSS_Y24
VSS_Y23
VSS_Y22
VSS_Y17
VSS_Y15
VSS_Y10
VSS_Y8
VSS_Y3
VSS_W75
VSS_W72
VSS_W70
VSS_W68
VSS_W65
VSS_W63
VSS_W61
VSS_W58
VSS_W56
VSS_W54
VSS_W51
VSS_W48
VSS_W45
VSS_W42
VSS_W41
VSS_W40
VSS_W36
VSS_W35
VSS_W34
VSS_W28
VSS_W25
VSS_W22
VSS_W20
VSS_W18
VSS_W15
VSS_W13
VSS_W11
VSS_W8
VSS_W6
VSS_W4
VSS_W1
VSS_V73
VSS_V71
VSS_V66
VSS_V64
VSS_V61
VSS_V59
VSS_V57
VSS_V53
VSS_V52
VSS_V51
VSS_V50
VSS_V49
VSS_V48
VSS_V47
VSS_V46
VSS_V45
VSS_V44
VSS_V43
VSS_V42
VSS_V39
VSS_V37
VSS_V34
VSS_V33
VSS_V32
VSS_V31
VSS_V30
VSS_V29
VSS_V28
VSS_V26
VSS_V25
VSS_V24
VSS_V23
VSS_V19
VSS_V17
VSS_V15
VSS_V12
VSS_V10
VSS_V8
VSS_V5
VSS_V3
VSS_U75
VSS_U70
VSS_U68
VSS_U63
VSS_U61
VSS_U56
VSS_U54
VSS_U51
VSS_U48
VSS_U45
VSS_U42
VSS_U34
VSS_U31
VSS_U28
VSS_U25
VSS_U22
VSS_U20
VSS_U15
VSS_U13
VSS_U8
VSS_U6
VSS_U1
VSS_T73
VSS_T71
VSS_T68
VSS_T66
VSS_AD48
VSS_AD47
VSS_AD46
VSS_AD45
VSS_AD44
VSS_AD43
VSS_AD42
VSS_AD39
VSS_AD37
VSS_AD34
VSS_AD33
VSS_AD32
VSS_AD30
VSS_AD29
VSS_AD28
VSS_AD27
VSS_AD26
VSS_AD25
VSS_AD24
VSS_AD23
VSS_AD19
VSS_AD17
VSS_AD15
VSS_AD12
VSS_AD10
VSS_AD8
VSS_AD5
VSS_AD3
VSS_AC75
VSS_AC70
VSS_AC68
VSS_AC63
VSS_AC61
VSS_AC56
VSS_AC54
VSS_AC51
VSS_AC48
VSS_AC45
VSS_AC42
VSS_AC34
VSS_AC31
VSS_AC28
VSS_AC25
VSS_AC22
VSS_AC20
VSS_AC15
VSS_AC13
VSS_AC8
VSS_AC6
VSS_AC1
VSS_AB73
VSS_AB71
VSS_AB68
29/40
VSS_R45
VSS_R42
VSS_R41
VSS_R40
VSS_R36
VSS_R35
VSS_R34
VSS_R31
VSS_R28
VSS_R25
VSS_R22
VSS_R20
VSS_R18
VSS_R15
VSS_R13
VSS_R11
VSS_R8
VSS_R6
VSS_R4
VSS_R1
VSS_P73
VSS_P66
VSS_P61
VSS_P59
VSS_P53
VSS_P52
VSS_P51
VSS_P50
VSS_P49
VSS_P48
VSS_P47
VSS_P46
VSS_P45
VSS_P44
VSS_P43
VSS_P42
VSS_P39
VSS_P37
VSS_P34
VSS_P33
VSS_P32
VSS_P31
VSS_P30
VSS_P29
VSS_P28
VSS_P27
VSS_P26
VSS_P24
VSS_P23
VSS_P17
VSS_P15
VSS_P10
VSS_P8
VSS_P3
VSS_N75
VSS_N72
VSS_N70
VSS_N68
VSS_N65
VSS_N63
VSS_N61
VSS_N58
VSS_N56
VSS_N54
VSS_N51
VSS_N48
VSS_N45
VSS_N42
VSS_N34
VSS_N31
VSS_N28
VSS_N25
VSS_N22
VSS_N20
VSS_N18
VSS_N15
VSS_N13
VSS_N11
VSS_N8
VSS_N6
VSS_N4
VSS_N1
VSS_M73
VSS_M71
VSS_M68
VSS_M66
VSS_M64
VSS_M61
VSS_M59
VSS_M57
VSS_M54
VSS_M51
VSS_M48
VSS_M45
VSS_M42
VSS_M39
VSS_M37
VSS_M34
VSS_M31
VSS_M28
VSS_M25
VSS_M22
VSS_M19
VSS_M17
VSS_M15
VSS_M12
VSS_M10
VSS_M8
VSS_M5
VSS_M3
VSS_L75
VSS_L70
VSS_L68
VSS_L63
VSS_L61
VSS_L56
VSS_L54
VSS_L51
VSS_L48
VSS_L45
VSS_L42
VSS_L41
VSS_L40
VSS_L36
VSS_L35
VSS_L34
VSS_L31
VSS_L28
VSS_L25
VSS_L22
VSS_L20
VSS_L15
VSS_L13
VSS_L8
VSS_L6
VSS_L1
VSS_K73
VSS_K71
VSS_K68
VSS_K66
VSS_K64
VSS_K61
VSS_K57
VSS_K53
VSS_K52
VSS_K51
VSS_K50
VSS_K49
VSS_K48
VSS_K47
VSS_K46
VSS_K45
VSS_K44
VSS_K43
VSS_K42
VSS_K39
VSS_K37
VSS_K34
VSS_K33
VSS_K32
VSS_K31
VSS_K30
VSS_K29
VSS_K28
VSS_K27
VSS_K26
VSS_K25
VSS_K24
VSS_K19
VSS_K17
VSS_K15
VSS_K12
VSS_K10
VSS_K8
VSS_K5
VSS_K3
VSS_J75
VSS_J72
VSS_J70
VSS_J68
VSS_J65
VSS_J63
VSS_J61
VSS_J58
VSS_J56
VSS_J54
VSS_J51
VSS_J48
VSS_J45
VSS_J42
VSS_J34
VSS_J31
VSS_J28
VSS_J25
VSS_J22
VSS_J20
VSS_J18
VSS_J15
VSS_T64
VSS_T61
VSS_T59
VSS_T57
VSS_T54
VSS_T51
VSS_T48
VSS_T45
VSS_T42
VSS_T39
VSS_T37
VSS_T34
VSS_T31
VSS_T28
VSS_T25
VSS_T22
VSS_T19
VSS_T17
VSS_T15
VSS_T12
VSS_T10
VSS_T8
VSS_T5
VSS_T3
VSS_R75
VSS_R72
VSS_R70
VSS_R68
VSS_R65
VSS_R63
VSS_R61
VSS_R58
VSS_R56
VSS_R54
VSS_R51
VSS_R48
28/40
VSS_H34
VSS_H31
VSS_H28
VSS_H25
VSS_H22
VSS_H17
VSS_H15
VSS_H10
VSS_H8
VSS_H3
VSS_G75
VSS_G72
VSS_G70
VSS_G68
VSS_G65
VSS_G63
VSS_G61
VSS_G58
VSS_G56
VSS_G54
VSS_G51
VSS_G48
VSS_G45
VSS_G42
VSS_G34
VSS_G31
VSS_G28
VSS_G25
VSS_G22
VSS_G20
VSS_G18
VSS_G15
VSS_G13
VSS_G11
VSS_G8
VSS_G6
VSS_G4
VSS_G1
VSS_F73
VSS_F71
VSS_F68
VSS_F66
VSS_F64
VSS_F61
VSS_F59
VSS_F57
VSS_F53
VSS_F52
VSS_F50
VSS_F49
VSS_F47
VSS_F46
VSS_F44
VSS_F43
VSS_F41
VSS_F40
VSS_F39
VSS_F37
VSS_F36
VSS_F35
VSS_F33
VSS_F32
VSS_F30
VSS_F29
VSS_F27
VSS_F26
VSS_F24
VSS_F23
VSS_F19
VSS_F17
VSS_F15
VSS_F12
VSS_F10
VSS_F8
VSS_F5
VSS_F3
VSS_E75
VSS_E73
VSS_E72
VSS_E70
VSS_E69
VSS_E68
VSS_E66
VSS_E65
VSS_E63
VSS_E62
VSS_E61
VSS_E59
VSS_E58
VSS_E56
VSS_E55
VSS_E53
VSS_E52
VSS_E21
VSS_E20
VSS_E18
VSS_E17
VSS_E15
VSS_E14
VSS_E13
VSS_E10
VSS_E8
VSS_E7
VSS_E6
VSS_E3
VSS_E1
VSS_D74
VSS_D73
VSS_D71
VSS_D70
VSS_D67
VSS_D66
VSS_D64
VSS_D63
VSS_D61
VSS_D60
VSS_D59
VSS_D57
VSS_D54
VSS_D53
VSS_D52
VSS_D51
VSS_D50
VSS_D49
VSS_D48
VSS_D47
VSS_D46
VSS_D45
VSS_D44
VSS_D43
VSS_D42
VSS_D41
VSS_D40
VSS_D39
VSS_D37
VSS_D35
VSS_D31
VSS_D30
VSS_D29
VSS_D28
VSS_D27
VSS_D26
VSS_D25
VSS_D24
VSS_D21
VSS_D20
VSS_D19
VSS_D17
VSS_D16
VSS_D13
VSS_D12
VSS_D10
VSS_D9
VSS_D6
VSS_D5
VSS_D3
VSS_D2
VSS_C75
VSS_C73
VSS_C71
VSS_C69
VSS_C67
VSS_C64
VSS_C61
VSS_C57
VSS_C56
VSS_C55
VSS_C52
VSS_C49
VSS_C46
VSS_C43
VSS_C40
VSS_C36
VSS_C30
VSS_C27
VSS_C24
VSS_C21
VSS_C15
VSS_C13
VSS_C11
VSS_C10
VSS_C8
VSS_C5
VSS_C1
VSS_B70
VSS_B68
VSS_B65
VSS_B62
VSS_B59
VSS_B55
VSS_B52
VSS_B49
VSS_B46
VSS_B43
VSS_B39
VSS_B37
VSS_B33
VSS_B30
VSS_B27
VSS_B24
VSS_B18
VSS_B13
VSS_B11
VSS_B10
VSS_B8
VSS_B7
VSS_A73
VSS_A72
VSS_A67
VSS_A61
VSS_A53
VSS_A49
VSS_A47
VSS_A44
VSS_A43
VSS_A27
VSS_A21
VSS_A15
VSS_A9
VSS_A3
VSS_J13
VSS_J11
VSS_J8
VSS_J6
VSS_J4
VSS_J1
VSS_H73
VSS_H68
VSS_H66
VSS_H61
VSS_H59
VSS_H54
VSS_H51
VSS_H48
VSS_H45
VSS_H42
VSS_H39
VSS_H37
1
SHEETDATE
23
7 3 2 16 5 4
E
A
B
C
E
D
C
B
A
7 6 5 4
D
DEPARTMENT
SIZE
PROJECT DOCUMENT NUMBER REV
REVIEWER
DESIGNER
C



Thu Aug 24 14:08:40 2023<NAME_2>
<NAME_1>
MB FABCGTI V02
32 OF 365
S O CK E T6096_13568-001
S O CK E T6096_13568-001
S O CK E T6096_13568-001S O CK E T6096_13568-001
IO
IO
IOIO
CPU0 VSS 2/3
SMLFSMLFSMLFSMLF
DA70
DA68
DA65
DA63
DA61
DA58
DA54
DA51
DA48
DA45
DA42
DA34
DA31
DA28
DA25
DA22
DA20
DA18
DA15
DA13
DA11
DA8
DA6
DA4
DA1
CY73
CY71
CY68
CY66
CY64
CY61
CY59
CY53
CY52
CY51
CY50
CY49
CY48
CY47
CY46
CY45
CY44
CY43
CY42
CY39
CY37
CY34
CY33
CY32
CY31
CY30
CY29
CY28
CY27
CY26
CY25
CY24
CY23
CY19
CY17
CY15
CY12
CY10
CY8
CY5
CY3
CW75
CW70
CW68
CW63
CW61
CW56
CW54
CW51
CW48
CW45
CW42
CW41
CW40
CW36
CW35
CW34
CW31
CW28
CW25
CW22
CW20
CW15
CW13
CW8
CW6
CW1
CV73
CV71
CV68
CV66
CV64
CV61
CV59
CV57
CV54
CV51
CV48
CV45
CV42
CV39
CV37
CV34
CV31
CV28
CV25
CV22
CV19
CV17
CV15
CV12
CV10
CV8
CV5
CV3
CU75
CU72
CU70
CU68
CU65
CU63
CU61
CU56
CU54
CU51
CU48
CU45
CU42
CU34
CU31
CU28
CU25
CU22
CU20
CU18
CU15
CU13
CU11
CU8
CU6
CU4
CU1
CT 73
CT 68
CT 66
CT 61
CT 59
CT 53
CT 51
CT 50
CT 49
CT 48
CT 47
CT 46
CT 45
CT 44
CT 43
CT 42
CT 39
CT 37
CT 34
CT 33
CT 32
CT 31
CT 30
CT 29
CT 28
CT 27
CT 26
CT 25
CT 24
CT 23
CT 17
CT 15
CT 10
CT 8
CT 3
CR75
CR72
CR70
CR68
CR65
CR63
CR61
CR58
CR56
CR54
CR51
CR48
CR45
CR42
CR41
CR40
CR36
CR35
CR34
CR31
CR28
CR25
CR22
CR20
CR18
CR15
CR13
CR11
CR8
CR6
CR4
CR1
CP73
CP71
CP68
CP66
CP64
CP61
CP59
CP57
CP54
CP51
CP48
CP45
CP42
CP39
CP37
CP34
CP31
CP28
CP25
CP22
U25
CP19
CP17
CP15
CP12
CP10
CP8
CP5
CP3
CN75
CN70
CN68
CN63
CN61
CN56
CN51
CN48
CN45
CN42
CN34
CN31
CN28
CN25
CN22
CN20
CN15
CN13
CN8
CN6
CN1
CM 73
CM 71
CM 68
CM 66
CM 64
CM 61
CM 59
CM 57
CM 53
CM 52
CM 51
CM 49
CM 48
CM 47
CM 46
CM 45
CM 44
CM 43
CM 42
CM 39
CM 37
CM 34
CM 33
CM 32
CM 31
CM 30
CM 29
CM 28
CM 27
CM 26
CM 25
CM 24
CM 23
CM 19
CM 17
CM 15
CM 12
CM 10
CM 8
CM 5
CM 3
CL75
CL72
CL70
CL68
CL65
CL63
CL61
CL58
CL56
CL54
CL51
CL48
CL45
CL42
CL41
CL40
CL36
CL35
CL34
CL31
CL28
CL25
CL22
CL20
CL18
CL15
CL13
CL11
CL8
CL6
CL4
CL1
CK73
CK68
CK66
CK61
CK59
CK54
CK53
CK52
CK51
CK50
CK49
CK48
CK45
CK44
CK43
CK42
CK39
CK37
CK34
CK33
CK32
CK28
CK27
CK26
CK25
CK24
CK23
CK22
CK17
CK15
CK8
CK3
CJ75
CJ72
CJ70
CJ68
CJ65
CJ63
CJ61
CJ58
CJ56
CJ45
CJ42
CJ41
CJ40
CJ36
CJ35
CJ34
CJ31
CJ23
CJ20
CJ18
CJ15
CJ13
CJ11
CJ8
CJ6
CJ4
CJ1
CH73
CH71
CH68
CH66
CH64
CH61
CH59
CH57
CH54
CH51
CH48
CH45
CH42
CH39
CH37
CH34
CH31
CH28
CH25
CH22
CH19
CH17
CH15
CH12
CH10
CH8
CH5
CH3
CG75
CG70
CG68
CG63
CG61
CG56
CG54
CG51
CG48
CG45
CG34
CG31
CG28
CG25
CG22
CG20
CG15
CG13
CG8
CG6
CG1
CF73
CF71
CF68
CF66
CF64
CF61
CF59
CF57
CF53
CF52
CF51
CF50
CF49
CF48
CF47
CF45
CF44
CF43
CF42
CF39
CF37
CF34
U25
CF33
CF32
CF31
CF30
CF29
CF28
CF27
CF26
CF25
CF24
CF23
CF19
CF17
CF15
CF12
CF10
CF8
CF5
CF3
CE75
CE72
CE70
CE68
CE65
CE63
CE61
CE58
CE56
CE54
CE51
CE48
CE45
CE42
CE41
CE40
CE36
CE35
CE34
CE31
CE28
CE25
CE22
CE20
CE18
CE15
CE13
CE11
CE8
CE6
CE4
CE1
CD73
CD68
CD66
CD61
CD59
CD54
CD51
CD48
CD45
CD42
CD39
CD37
CD34
CD31
CD28
CD25
CD22
CD17
CD15
CD10
CD8
CD3
CC75
CC72
CC70
CC68
CC65
CC63
CC61
CC58
CC56
CC54
CC51
CC48
CC45
CC42
CC34
CC31
CC28
CC25
CC20
CC18
CC15
CC13
CC11
CC8
CC6
CC4
CC1
CB73
CB71
CB68
CB66
CB64
CB61
CB59
CB57
CB53
CB52
CB51
CB50
CB49
CB48
CB47
CB46
CB45
CB43
CB42
CB39
CB37
CB34
CB33
CB32
CB31
CB30
CB29
CB28
CB27
CB26
CB25
CB24
CB23
CB19
CB17
CB15
CB12
CB10
CB8
CB5
CB3
CA75
CA70
CA68
CA63
CA61
CA56
CA54
CA51
CA48
CA45
CA42
CA41
CA40
CA36
CA35
CA34
CA31
CA28
CA25
CA22
CA20
CA15
CA13
CA8
CA6
CA1
BY73
BY71
BY68
BY66
BY64
BY61
BY59
BY57
BY54
BY51
BY48
BY45
BY42
BY39
BY37
BY34
BY31
BY28
BY25
BY22
BY19
BY17
BY15
BY12
BY10
BY8
BY5
BY3
BW75
BW72
BW70
BW68
BW65
BW63
BW61
BW58
BW56
BW54
BW51
BW48
BW45
BW42
BW34
BW31
BW28
BW22
BW20
BW18
BW15
BW13
BW11
BW8
BW6
BW4
BW1
BV73
BV68
BV66
BV61
BV59
BV53
BV52
BV51
BV50
BV49
BV48
BV47
BV46
U25
BV45
BV44
BV43
BV39
BV37
BV34
BV33
BV32
BV31
BV30
BV29
BV28
BV27
BV26
BV25
BV24
BV23
BV17
BV15
BV10
BV8
BV3
BU75
BU72
BU70
BU68
BU65
BU63
BU61
BU58
BU56
BU54
BU51
BU48
BU45
BU42
BU41
BU40
BU36
BU35
BU34
BU31
BU28
BU25
BU22
BU20
BU18
BU15
BU13
BU11
BU8
BU6
BU4
BU1
BT 73
BT 72
BT 71
BT 69
BT 68
BT 66
BT 65
BT 64
BT 62
BT 61
BT 59
BT 58
BT 57
BT 55
BT 54
BT 51
BT 48
BT 45
BT 42
BT 39
BT 37
BT 34
BT 31
BT 28
BT 25
BT 22
BT 21
BT 19
BT 18
BT 17
BT 15
BT 14
BT 12
BT 11
BT 10
BT 8
BT 7
BT 5
BT 4
BT 3
BR75
BR73
BR70
BR69
BR68
BR66
BR63
BR62
BR61
BR59
BR56
BR55
BR51
BR49
BR47
BR45
BR43
BR41
BR36
BR34
BR32
BR30
BR28
BR26
BR24
BR22
BR21
BR20
BR17
BR15
BR14
BR13
BR10
BR8
BR7
BR6
BR3
BR1
BP73
BP71
BP68
BP66
BP64
BP61
BP59
BP57
BP54
BP52
BP50
BP48
BP46
BP44
BP42
BP40
BP37
BP35
BP33
BP31
BP29
BP27
BP25
BP23
BP19
BP17
BP15
BP12
BP10
BP8
BP5
BP3
BN75
BN72
BN70
BN68
BN65
BN63
BN61
BN58
BN56
BN53
BN51
BN49
BN47
BN45
BN43
BN41
BN36
BN34
BN32
BN30
BN28
BN26
BN24
BN22
BN20
BN18
BN15
BN13
BN11
BN8
BN6
BN4
BN1
BM 73
BM 68
BM 66
BM 61
BM 59
BM 54
BM 52
BM 50
BM 48
BM 46
BM 44
BM 42
BM 40
BM 37
BM 35
BM 33
BM 31
BM 29
BM 27
BM 25
BM 23
BM 17
BM 15
BM 10
BM 8
BM 3
BL75
BL72
BL70
BL68
BL65
BL63
BL61
BL58
BL56
BL53
BL51
BL49
BL28
BL26
U25
39/40
VSS_DA70
VSS_DA68
VSS_DA65
VSS_DA63
VSS_DA61
VSS_DA58
VSS_DA42
VSS_DA34
VSS_DA31
VSS_DA28
VSS_DA25
VSS_DA22
VSS_DA11
VSS_DA8
VSS_DA6
VSS_DA4
VSS_DA1
VSS_CY73
VSS_CY71
VSS_CY61
VSS_CY59
VSS_CY53
VSS_CY52
VSS_CY51
VSS_CY50
VSS_CY49
VSS_CY46
VSS_CY45
VSS_CY44
VSS_CY43
VSS_CY42
VSS_CY39
VSS_CY37
VSS_CY34
VSS_CY33
VSS_CY31
VSS_CY30
VSS_CY29
VSS_CY28
VSS_CY27
VSS_CY26
VSS_CY25
VSS_CY24
VSS_CY23
VSS_CY19
VSS_CY17
VSS_CY15
VSS_CY12
VSS_CY10
VSS_CY8
VSS_CY5
VSS_CY3
VSS_CW75
VSS_CW70
VSS_CW68
VSS_CW63
VSS_CW61
VSS_CW56
VSS_CW54
VSS_CW51
VSS_CW48
VSS_CW45
VSS_CW42
VSS_CW41
VSS_CW40
VSS_CW36
VSS_CW35
VSS_CW20
VSS_CW15
VSS_CW13
VSS_CW8
VSS_CW6
VSS_CW1
VSS_CV61
VSS_CV59
VSS_CV57
VSS_CV54
VSS_CV51
VSS_CV48
VSS_CV31
VSS_CV28
VSS_CV25
VSS_CV22
VSS_CV19
VSS_CV17
VSS_CV3
VSS_CU75
VSS_CU72
VSS_CU70
VSS_CU68
VSS_CU65
VSS_CU54
VSS_CU51
VSS_CU48
VSS_CU45
VSS_CU42
VSS_CU34
VSS_CU31
VSS_CU20
VSS_CU18
VSS_CU15
VSS_CU13
VSS_CU11
VSS_CU8
VSS_CU6
VSS_CU4
VSS_CT68
VSS_CT66
VSS_CT61
VSS_CT59
VSS_CT53
VSS_CT51
VSS_CT50
VSS_CT49
VSS_CT47
VSS_CT46
VSS_CT45
VSS_CT44
VSS_CT43
VSS_CT42
VSS_CT39
VSS_CT37
VSS_CT34
VSS_CT33
VSS_CT32
VSS_CT31
VSS_CT30
VSS_CT29
VSS_CT28
VSS_CT27
VSS_CT26
VSS_CT25
VSS_CT24
VSS_CT23
VSS_CT17
VSS_CR72
VSS_CR70
VSS_CR68
VSS_CR65
VSS_CR63
VSS_CR61
VSS_CR45
VSS_CR42
VSS_CR41
VSS_CR40
VSS_CR36
VSS_CR35
VSS_CR20
VSS_CR18
VSS_CR15
VSS_CR13
VSS_CR11
VSS_CR8
VSS_CP68
VSS_CP66
VSS_CP64
VSS_CP61
VSS_CP59
VSS_CP57
VSS_CP39
VSS_CP37
VSS_CP34
VSS_CP31
VSS_CP28
VSS_CP25
VSS_DA54
VSS_DA51
VSS_DA48
VSS_DA45
VSS_DA20
VSS_DA18
VSS_DA15
VSS_DA13
VSS_CY68
VSS_CY66
VSS_CY64
VSS_CY48
VSS_CY47
VSS_CY32
VSS_CW34
VSS_CW31
VSS_CW28
VSS_CW25
VSS_CW22
VSS_CV73
VSS_CV71
VSS_CV68
VSS_CV66
VSS_CV64
VSS_CV45
VSS_CV42
VSS_CV39
VSS_CV37
VSS_CV34
VSS_CV15
VSS_CV12
VSS_CV10
VSS_CV8
VSS_CV5
VSS_CU63
VSS_CU61
VSS_CU56
VSS_CU28
VSS_CU25
VSS_CU22
VSS_CU1
VSS_CT73
VSS_CT48
VSS_CT15
VSS_CT10
VSS_CT8
VSS_CT3
VSS_CR75
VSS_CR58
VSS_CR56
VSS_CR54
VSS_CR51
VSS_CR48
VSS_CR34
VSS_CR31
VSS_CR28
VSS_CR25
VSS_CR22
VSS_CR6
VSS_CR4
VSS_CR1
VSS_CP73
VSS_CP71
VSS_CP54
VSS_CP51
VSS_CP48
VSS_CP45
VSS_CP42
VSS_CP22
38/40
VSS_CP19
VSS_CP17
VSS_CP15
VSS_CP12
VSS_CP10
VSS_CP8
VSS_CP5
VSS_CP3
VSS_CN75
VSS_CN70
VSS_CN68
VSS_CN63
VSS_CN61
VSS_CN51
VSS_CN48
VSS_CN45
VSS_CN42
VSS_CN34
VSS_CN31
VSS_CN28
VSS_CN25
VSS_CN15
VSS_CN13
VSS_CN8
VSS_CN6
VSS_CN1
VSS_CM73
VSS_CM71
VSS_CM68
VSS_CM59
VSS_CM57
VSS_CM53
VSS_CM52
VSS_CM51
VSS_CM49
VSS_CM48
VSS_CM47
VSS_CM46
VSS_CM45
VSS_CM44
VSS_CM33
VSS_CM32
VSS_CM31
VSS_CM30
VSS_CM29
VSS_CM28
VSS_CM23
VSS_CM19
VSS_CM17
VSS_CM15
VSS_CM12
VSS_CM10
VSS_CM8
VSS_CL72
VSS_CL70
VSS_CL68
VSS_CL65
VSS_CL63
VSS_CL61
VSS_CL58
VSS_CL56
VSS_CL48
VSS_CL45
VSS_CL42
VSS_CL41
VSS_CL40
VSS_CL36
VSS_CL35
VSS_CL34
VSS_CL31
VSS_CL25
VSS_CL22
VSS_CL20
VSS_CL18
VSS_CL15
VSS_CL13
VSS_CL11
VSS_CL8
VSS_CL6
VSS_CL4
VSS_CL1
VSS_CK73
VSS_CK68
VSS_CK66
VSS_CK61
VSS_CK59
VSS_CK54
VSS_CK53
VSS_CK52
VSS_CK51
VSS_CK50
VSS_CK49
VSS_CK48
VSS_CK45
VSS_CK44
VSS_CK43
VSS_CK42
VSS_CK39
VSS_CK37
VSS_CK34
VSS_CK32
VSS_CK28
VSS_CK27
VSS_CK26
VSS_CK25
VSS_CK24
VSS_CK23
VSS_CK22
VSS_CK8
VSS_CK3
VSS_CJ75
VSS_CJ72
VSS_CJ70
VSS_CJ68
VSS_CJ65
VSS_CJ56
VSS_CJ45
VSS_CJ42
VSS_CJ41
VSS_CJ40
VSS_CJ36
VSS_CJ35
VSS_CJ18
VSS_CJ15
VSS_CJ13
VSS_CJ11
VSS_CJ8
VSS_CJ6
VSS_CH66
VSS_CH64
VSS_CH61
VSS_CH59
VSS_CH57
VSS_CH54
VSS_CH37
VSS_CH34
VSS_CH31
VSS_CH28
VSS_CH25
VSS_CH22
VSS_CH8
VSS_CH5
VSS_CH3
VSS_CG75
VSS_CG70
VSS_CG68
VSS_CG63
VSS_CG61
VSS_CG56
VSS_CG54
VSS_CG51
VSS_CG48
VSS_CG45
VSS_CG34
VSS_CG31
VSS_CG28
VSS_CG25
VSS_CG22
VSS_CG20
VSS_CG15
VSS_CG13
VSS_CG8
VSS_CG6
VSS_CG1
VSS_CF73
VSS_CF71
VSS_CF68
VSS_CF66
VSS_CF64
VSS_CF61
VSS_CF59
VSS_CF57
VSS_CF53
VSS_CF52
VSS_CF51
VSS_CF50
VSS_CF49
VSS_CF48
VSS_CF47
VSS_CF45
VSS_CF44
VSS_CF43
VSS_CF42
VSS_CF39
VSS_CF37
VSS_CF34
VSS_CH19
VSS_CH51
VSS_CJ4
VSS_CL28
VSS_CL54
VSS_CM5
VSS_CM27
VSS_CM43
VSS_CH17
VSS_CH48
VSS_CJ1
VSS_CJ34
VSS_CL51
VSS_CM3
VSS_CM26
VSS_CM42
VSS_CH15
VSS_CH45
VSS_CH73
VSS_CJ31
VSS_CJ63
VSS_CL75
VSS_CM25
VSS_CM39
VSS_CM66
VSS_CH12
VSS_CH42
VSS_CH71
VSS_CJ23
VSS_CJ61
VSS_CK17
VSS_CM24
VSS_CM37
VSS_CM64
VSS_CN22
VSS_CH10
VSS_CH39
VSS_CH68
VSS_CJ20
VSS_CJ58
VSS_CK15
VSS_CK33
VSS_CM34
VSS_CM61
VSS_CN20
VSS_CN56
37/40
VSS_CF33
VSS_CF32
VSS_CF31
VSS_CF30
VSS_CF29
VSS_CF28
VSS_CF27
VSS_CF26
VSS_CF25
VSS_CF24
VSS_CF23
VSS_CF19
VSS_CF17
VSS_CF15
VSS_CF12
VSS_CF10
VSS_CF8
VSS_CF5
VSS_CF3
VSS_CE75
VSS_CE72
VSS_CE70
VSS_CE68
VSS_CE65
VSS_CE63
VSS_CE61
VSS_CE58
VSS_CE56
VSS_CE54
VSS_CE51
VSS_CE48
VSS_CE45
VSS_CE42
VSS_CE41
VSS_CE40
VSS_CE36
VSS_CE35
VSS_CE34
VSS_CE31
VSS_CE28
VSS_CE25
VSS_CE22
VSS_CE20
VSS_CE18
VSS_CE15
VSS_CE13
VSS_CE11
VSS_CE8
VSS_CE6
VSS_CE4
VSS_CE1
VSS_CD73
VSS_CD68
VSS_CD66
VSS_CD61
VSS_CD59
VSS_CD54
VSS_CD51
VSS_CD48
VSS_CD45
VSS_CD42
VSS_CD39
VSS_CD37
VSS_CD34
VSS_CD31
VSS_CD28
VSS_CD25
VSS_CD22
VSS_CD17
VSS_CD15
VSS_CD10
VSS_CD8
VSS_CD3
VSS_CC75
VSS_CC72
VSS_CC70
VSS_CC68
VSS_CC65
VSS_CC63
VSS_CC61
VSS_CC58
VSS_CC56
VSS_CC54
VSS_CC51
VSS_CC48
VSS_CC45
VSS_CC42
VSS_CC34
VSS_CC31
VSS_CC28
VSS_CC25
VSS_CC20
VSS_CC18
VSS_CC15
VSS_CC13
VSS_CC11
VSS_CC8
VSS_CC6
VSS_CC4
VSS_CC1
VSS_CB73
VSS_CB71
VSS_CB68
VSS_CB66
VSS_CB64
VSS_CB61
VSS_CB59
VSS_CB57
VSS_CB53
VSS_CB52
VSS_CB51
VSS_CB50
VSS_CB49
VSS_CB48
VSS_CB47
VSS_CB46
VSS_CB45
VSS_CB43
VSS_CB42
VSS_CB39
VSS_CB37
VSS_CB34
VSS_CB33
VSS_CB32
VSS_CB31
VSS_CB30
VSS_CB29
VSS_CB28
VSS_CB27
VSS_CB26
VSS_CB25
VSS_CB24
VSS_CB23
VSS_CB19
VSS_CB17
VSS_CB15
VSS_CB12
VSS_CB10
VSS_CB8
VSS_CB5
VSS_CB3
VSS_CA75
VSS_CA70
VSS_CA68
VSS_CA63
VSS_CA61
VSS_CA56
VSS_CA54
VSS_CA51
VSS_CA48
VSS_CA45
VSS_CA42
VSS_CA41
VSS_CA40
VSS_CA36
VSS_CA35
VSS_CA34
VSS_CA31
VSS_CA28
VSS_CA25
VSS_CA22
VSS_CA20
VSS_CA15
VSS_CA13
VSS_CA8
VSS_CA6
VSS_CA1
VSS_BY73
VSS_BY71
VSS_BY68
VSS_BY66
VSS_BY64
VSS_BY61
VSS_BY59
VSS_BY57
VSS_BY54
VSS_BY51
VSS_BY48
VSS_BY45
VSS_BY42
VSS_BY39
VSS_BY37
VSS_BY34
VSS_BY31
VSS_BY28
VSS_BY25
VSS_BY22
VSS_BY19
VSS_BY17
VSS_BY15
VSS_BY12
VSS_BY10
VSS_BY8
VSS_BY5
VSS_BY3
VSS_BW75
VSS_BW72
VSS_BW70
VSS_BW68
VSS_BW65
VSS_BW63
VSS_BW61
VSS_BW58
VSS_BW56
VSS_BW54
VSS_BW51
VSS_BW48
VSS_BW45
VSS_BW42
VSS_BW34
VSS_BW31
VSS_BW28
VSS_BW22
VSS_BW20
VSS_BW18
VSS_BW15
VSS_BW13
VSS_BW11
VSS_BW8
VSS_BW6
VSS_BW4
VSS_BW1
VSS_BV73
VSS_BV68
VSS_BV66
VSS_BV61
VSS_BV59
VSS_BV53
VSS_BV52
VSS_BV51
VSS_BV50
VSS_BV49
VSS_BV48
VSS_BV47
VSS_BV46
34/40
VSS_BV45
VSS_BV44
VSS_BV43
VSS_BV39
VSS_BV34
VSS_BV33
VSS_BV32
VSS_BV31
VSS_BV30
VSS_BV29
VSS_BV28
VSS_BV27
VSS_BV26
VSS_BV25
VSS_BV24
VSS_BV23
VSS_BV17
VSS_BV15
VSS_BV10
VSS_BV8
VSS_BV3
VSS_BU75
VSS_BU72
VSS_BU70
VSS_BU68
VSS_BU65
VSS_BU63
VSS_BU61
VSS_BU58
VSS_BU56
VSS_BU54
VSS_BU51
VSS_BU48
VSS_BU45
VSS_BU42
VSS_BU41
VSS_BU40
VSS_BU36
VSS_BU35
VSS_BU34
VSS_BU31
VSS_BU28
VSS_BU25
VSS_BU22
VSS_BU20
VSS_BU18
VSS_BU15
VSS_BU13
VSS_BU11
VSS_BU8
VSS_BU6
VSS_BU4
VSS_BU1
VSS_BT73
VSS_BT72
VSS_BT71
VSS_BT69
VSS_BT68
VSS_BT66
VSS_BT65
VSS_BT64
VSS_BT62
VSS_BT61
VSS_BT59
VSS_BT58
VSS_BT57
VSS_BT55
VSS_BT54
VSS_BT51
VSS_BT48
VSS_BT45
VSS_BT42
VSS_BT39
VSS_BT37
VSS_BT34
VSS_BT31
VSS_BT28
VSS_BT25
VSS_BT22
VSS_BT21
VSS_BT19
VSS_BT18
VSS_BT17
VSS_BT15
VSS_BT14
VSS_BT12
VSS_BT11
VSS_BT10
VSS_BT8
VSS_BT7
VSS_BT5
VSS_BT4
VSS_BT3
VSS_BR75
VSS_BR73
VSS_BR70
VSS_BR69
VSS_BR68
VSS_BR66
VSS_BR63
VSS_BR62
VSS_BR61
VSS_BR59
VSS_BR56
VSS_BR55
VSS_BR51
VSS_BR49
VSS_BR47
VSS_BR45
VSS_BR43
VSS_BR41
VSS_BR36
VSS_BR34
VSS_BR32
VSS_BR30
VSS_BR28
VSS_BR26
VSS_BR24
VSS_BR22
VSS_BR21
VSS_BR20
VSS_BR17
VSS_BR15
VSS_BR14
VSS_BR13
VSS_BR10
VSS_BR8
VSS_BR7
VSS_BR6
VSS_BR3
VSS_BR1
VSS_BP73
VSS_BP71
VSS_BP68
VSS_BP66
VSS_BP64
VSS_BP61
VSS_BP59
VSS_BP57
VSS_BP54
VSS_BP52
VSS_BP50
VSS_BP48
VSS_BP46
VSS_BP44
VSS_BP42
VSS_BP40
VSS_BP37
VSS_BP35
VSS_BP33
VSS_BP31
VSS_BP29
VSS_BP27
VSS_BP25
VSS_BP23
VSS_BP19
VSS_BP17
VSS_BP15
VSS_BP12
VSS_BP10
VSS_BP8
VSS_BP5
VSS_BP3
VSS_BN75
VSS_BN72
VSS_BN70
VSS_BN68
VSS_BN65
VSS_BN63
VSS_BN61
VSS_BN58
VSS_BN56
VSS_BN53
VSS_BN51
VSS_BN49
VSS_BN47
VSS_BN45
VSS_BN43
VSS_BN41
VSS_BN36
VSS_BN34
VSS_BN32
VSS_BN30
VSS_BN28
VSS_BN26
VSS_BN24
VSS_BN22
VSS_BN20
VSS_BN18
VSS_BN15
VSS_BN13
VSS_BN11
VSS_BN8
VSS_BN6
VSS_BN4
VSS_BN1
VSS_BM73
VSS_BM68
VSS_BM66
VSS_BM61
VSS_BM59
VSS_BM54
VSS_BM52
VSS_BM50
VSS_BM48
VSS_BM46
VSS_BM44
VSS_BM42
VSS_BM40
VSS_BM37
VSS_BM35
VSS_BM33
VSS_BM31
VSS_BM29
VSS_BM27
VSS_BM25
VSS_BM23
VSS_BM17
VSS_BM15
VSS_BM10
VSS_BM8
VSS_BM3
VSS_BL75
VSS_BL72
VSS_BL70
VSS_BL68
VSS_BL65
VSS_BL63
VSS_BL61
VSS_BL58
VSS_BL56
VSS_BL53
VSS_BL51
VSS_BL49
VSS_BL28
VSS_BL26
VSS_BV37
1
SHEETDATE
23
7 3 2 16 5 4
E
A
B
C
E
D
C
B
A
7 6 5 4
D
DEPARTMENT
SIZE
PROJECT DOCUMENT NUMBER REV
REVIEWER
DESIGNER
C



Thu Aug 24 14:08:40 2023<NAME_2>
<NAME_1>
MB FABCGTI V02
33 OF 365
SOCKET6096_13568-001
IO
SMLF
CPU0 VSS 3/3
V68
V27
P68
P25
K59
K23
DJ73
DJ68
DJ66
DJ63
DJ61
DJ59
DJ49
DJ43
DJ19
DJ15
DJ7
DH70
DH68
DH66
DH64
DH63
DH61
DH59
DH55
DH52
DH49
DH46
DH43
DH39
DH37
DH18
DH11
DH5
DG75
DG74
DG70
DG69
DG68
DG67
DG66
DG65
DG63
DG62
DG61
DG60
DG59
DG56
DG55
DG52
DG49
DG46
DG43
DG41
DG33
DG30
DG27
DG24
DG21
DG20
DG18
DG16
DG15
DG14
DG13
DG9
DG8
DG7
DG6
DG2
DG1
DF73
DF72
DF71
DF70
DF68
DF66
DF65
DF64
DF63
DF61
DF59
DF58
DF57
DF56
DF54
DF53
DF52
DF51
DF50
DF49
DF48
DF47
DF46
DF45
DF44
DF43
DF42
DF39
DF37
DF35
DF32
DF29
DF26
DF23
DF22
DF20
DF19
DF18
DF17
DF15
DF13
DF12
DF11
DF10
DF8
DF6
DF5
DF4
DF3
DE75
DE70
DE68
DE63
DE61
DE56
DE33
DE29
DE26
DE23
DE20
DE15
DE13
DE8
DE6
DE1
DD73
DD71
DD68
DD66
DD64
DD61
DD59
DD57
DD53
DD52
DD50
DD49
DD47
DD46
DD44
DD43
DD41
DD40
DD39
DD37
DD36
DD35
DD33
DD32
DD30
DD29
DD27
DD26
DD24
DD23
DD19
DD17
DD15
DD12
DD10
DD8
DD5
DD3
DC75
DC72
DC70
DC68
DC65
DC63
DC61
DC58
DC56
DC54
DC51
DC48
DC45
DC42
DC34
DC31
DC28
DC25
DC22
DC20
DC18
DC15
DC13
DC11
DC8
DC6
DC4
DC1
DB73
DB68
DB66
DB61
DB59
DB54
DB51
DB48
DB45
DB42
DB39
DB37
DB34
DB31
DB28
DB25
DB22
DB17
DB15
DB10
DB8
DB3
DA75
DA72
DA56
CY57
CU58
CT52
CN54
CM50
CK31
CK10
CG42
CF46
CC22
CB44
BW25
BV42
AN20
AM37
AJ13
AH33
AE4
AD31
AA72
AA42
U25
40/40
VSS_V68
VSS_BV42
VSS_CT52
VSS_CM50
VSS_K59
VSS_DA56
VSS_CG42
VSS_AE4
VSS_AH33
VSS_BW25
VSS_CU58
VSS_P25
VSS_P68
VSS_AN20
VSS_CC22
VSS_CF46
VSS_V27
VSS_AA42
VSS_AD31
VSS_AJ13
VSS_AA72
VSS_CK10
VSS_CN54
VSS_K23
VSS_AM37
VSS_CB44
VSS_CK31
VSS_CY57
VSS_DJ73
VSS_DJ68
VSS_DJ66
VSS_DJ63
VSS_DJ61
VSS_DJ59
VSS_DJ49
VSS_DJ43
VSS_DJ19
VSS_DJ15
VSS_DJ7
VSS_DH70
VSS_DH68
VSS_DH59
VSS_DH55
VSS_DH52
VSS_DH49
VSS_DH46
VSS_DH43
VSS_DH39
VSS_DG75
VSS_DG74
VSS_DG70
VSS_DG69
VSS_DG68
VSS_DG67
VSS_DG66
VSS_DG60
VSS_DG59
VSS_DG56
VSS_DG55
VSS_DG52
VSS_DG49
VSS_DG46
VSS_DG27
VSS_DG24
VSS_DG21
VSS_DG20
VSS_DG18
VSS_DG16
VSS_DG15
VSS_DG7
VSS_DG6
VSS_DG2
VSS_DG1
VSS_DF73
VSS_DF72
VSS_DF71
VSS_DF65
VSS_DF64
VSS_DF63
VSS_DF61
VSS_DF59
VSS_DF58
VSS_DF57
VSS_DF56
VSS_DF52
VSS_DF51
VSS_DF50
VSS_DF49
VSS_DF48
VSS_DF47
VSS_DF46
VSS_DF45
VSS_DF44
VSS_DF42
VSS_DF39
VSS_DF37
VSS_DF35
VSS_DF32
VSS_DF29
VSS_DF26
VSS_DF23
VSS_DF22
VSS_DF20
VSS_DF13
VSS_DF12
VSS_DF11
VSS_DF10
VSS_DF8
VSS_DF6
VSS_DF5
VSS_DE68
VSS_DE63
VSS_DE61
VSS_DE56
VSS_DE33
VSS_DE29
VSS_DE26
VSS_DE8
VSS_DE6
VSS_DE1
VSS_DD73
VSS_DD71
VSS_DD68
VSS_DD66
VSS_DD53
VSS_DD52
VSS_DD50
VSS_DD49
VSS_DD47
VSS_DD46
VSS_DD44
VSS_DD37
VSS_DD36
VSS_DD35
VSS_DD33
VSS_DD32
VSS_DD30
VSS_DD29
VSS_DD19
VSS_DD17
VSS_DD15
VSS_DD12
VSS_DD10
VSS_DD8
VSS_DD5
VSS_DC68
VSS_DC65
VSS_DC63
VSS_DC61
VSS_DC58
VSS_DC56
VSS_DC54
VSS_DC42
VSS_DC34
VSS_DC31
VSS_DC28
VSS_DC25
VSS_DC22
VSS_DC20
VSS_DC18
VSS_DC11
VSS_DC8
VSS_DC6
VSS_DC4
VSS_DC1
VSS_DB73
VSS_DB68
VSS_DB66
VSS_DB61
VSS_DB45
VSS_DB42
VSS_DB39
VSS_DB37
VSS_DB34
VSS_DB31
VSS_DB28
VSS_DB10
VSS_DB8
VSS_DB3
VSS_DA75
VSS_DA72
VSS_DH66
VSS_DH64
VSS_DH63
VSS_DH61
VSS_DH37
VSS_DH18
VSS_DH11
VSS_DH5
VSS_DG65
VSS_DG63
VSS_DG62
VSS_DG61
VSS_DG43
VSS_DG41
VSS_DG33
VSS_DG30
VSS_DG14
VSS_DG13
VSS_DG9
VSS_DG8
VSS_DF70
VSS_DF68
VSS_DF66
VSS_DF54
VSS_DF53
VSS_DF43
VSS_DF19
VSS_DF18
VSS_DF17
VSS_DF15
VSS_DF4
VSS_DF3
VSS_DE75
VSS_DE70
VSS_DE23
VSS_DE20
VSS_DE15
VSS_DE13
VSS_DD64
VSS_DD61
VSS_DD59
VSS_DD57
VSS_DD43
VSS_DD41
VSS_DD40
VSS_DD39
VSS_DD27
VSS_DD26
VSS_DD24
VSS_DD23
VSS_DD3
VSS_DC75
VSS_DC72
VSS_DC70
VSS_DC51
VSS_DC48
VSS_DC45
VSS_DC15
VSS_DC13
VSS_DB59
VSS_DB54
VSS_DB51
VSS_DB48
VSS_DB25
VSS_DB22
VSS_DB17
VSS_DB15
1
SHEETDATE
23
7 3 2 16 5 4
E
A
B
C
E
D
C
B
A
7 6 5 4
D
DEPARTMENT
SIZE
PROJECT DOCUMENT NUMBER REV
REVIEWER
DESIGNER
C



INTERNAL PU
Thu Aug 24 14:08:40 2023<NAME_2>
<NAME_1>
MB FABCGTI V02
34 OF 365
P 1V 8_A UX
P 3V 3_A UX
P 3V 3_A UX
P V DD18_S 5_P 0
P V DD18_S 5_P 0
P V DD18_S 5_P 0
2834
2834
28166
34 80
34 80
81
34 80
34 80
28 34
28 34
CHIP
CHIP 2.2K
4.7K
S N74LV C1G 07DB V R
S MLF
0402
0.1UF
TP _U27_E N
X 7R
0402
25V
25V25V
0.1UF
0.1UF
P CA 9617A DP
10%
10%10%
X 7R
X 7R
IC
S MB _CP U0_4_S CL
S MB _CP U0_4_S DA
FM_B IO S _P O S T_CMP LT_N
S MB _CP U0_4_X LTR_S CL
S MB _CP U0_4_X LTR_S DA
CPU0 GLUE LOGIC
SMLF
0402
0402
1000PF
5%
50V
X7R
IC
FM_B IO S _P O S T_CMP LT_B UF_NFM_B IO S _P O S T_CMP LT_B UF_R1_N 49.9
4.7K S MB _CP U0_4_X LTR_S DA
0402LF
1/16W
CHIP
5%
4.7K
4.7K S MB _CP U0_4_X LTR_S CL
1/16W
CHIP
5%
4.7K
0402LF
S MB _CP U0_4_S CL
S MB _CP U0_4_S DA
21 R6100
21R498
21R495
2
1
R942
2
1 C226
4
5
13
2
U101
2
1
R943
2
1
C43
2
1 C42
81
63
72
4 5
U27
21R590
21R499
C5000
NC
Y
GND
A
VCC
GND
SCLB
SDABSDAA
SCLA
VCCBVCCA
EN
2
1
1
SHEETDATE
23
7 3 2 16 5 4
E
A
B
C
E
D
C
B
A
7 6 5 4
D
DEPARTMENT
SIZE
PROJECT DOCUMENT NUMBER REV
REVIEWER
DESIGNER
IN OUT
BI
OUT
BI
IN
OUT
OUT
OUT
OUT
C



Thu Aug 24 10:13:43 2023<NAME_2>
<NAME_1>
MB FABCGTI V02
35 OF 365
Blank
1
SHEETDATE
23
7 3 2 16 5 4
E
A
B
C
E
D
C
B
A
7 6 5 4
D
DEPARTMENT
SIZE
PROJECT DOCUMENT NUMBER REV
REVIEWER
DESIGNER
C



Thu Aug 24 10:13:43 2023<NAME_2>
<NAME_1>
MB FABCGTI V02
36 OF 365Blank
1
SHEETDATE
23
7 3 2 16 5 4
E
A
B
C
E
D
C
B
A
7 6 5 4
D
DEPARTMENT
SIZE
PROJECT DOCUMENT NUMBER REV
REVIEWER
DESIGNER
C



Thu Aug 24 14:08:41 2023<NAME_2>
<NAME_1>
MB FABCGTI V02
37 OF 365
98
98
98
98
98
98
98
98
98
98
98
98
98
98
98
98
98
98
98
98
98
98
15 M_A _CP U1_A LE RT_R_NM_A _CP U1_A LE RT_N 1%
0402LF
S O CK E T6096_13568-001
IO
TP _M_A _CP U1_S A _TE S T40
TP _M_A _CP U1_S A _TE S T39A
M_A _CP U1_S A _CA <6:0>
M_A _CP U1_S B _CA <6:0>
M_A _CP U1_CLK _DP <0>
M_A _CP U1_CLK _DN<0>
M_A _CP U1_S A _CS _N<0>
M_A _CP U1_S A _CS _N<1>
M_A _CP U1_S A _RS P <0>
M_A _CP U1_S A _P A R
M_A _CP U1_S B _CS _N<0>
M_A _CP U1_S B _CS _N<1>
M_A _CP U1_S B _RS P <0>
M_A _CP U1_S B _P A R
M_A _CP U1_RE S E T_N
M_A _CP U1_S A _DQ S _DP <9:0>
M_A _CP U1_S B _DQ S _DP <9:0>
M_A _CP U1_S B _DQ S _DN<9:0>
M_A _CP U1_S A _DQ S _DN<9:0>
M_A _CP U1_S A _CB <7:0>
M_A _CP U1_S B _CB <7:0>
M_A _CP U1_S A _DQ <31:0>
M_A _CP U1_S B _DQ <31:0>
CPU1 DDR CHA
R1958 PLACE CLOSE TO CPU < 25MM
SMLF
21R500
C60
BF72
BL74
BW74
DC73
CU73
CL73
CE73
BW73
DC74
CU74
CL74
CE74
BV74
DD72
CV72
CM 72
CF72
BY72
DB74
CT 74
CK74
CD74
DF74
DE74
DE73
DD74
DB72
DA74
DA73
CY74
CY72
CW74
CW73
CV74
CT 72
CR74
CR73
CP74
CP72
CN74
CN73
CM 74
CK72
CJ74
CJ73
CH74
CH72
CG74
CG73
CF74
CD72
CC74
CC73
CB74
BV72
BU74
BU73
BT 74
CB72
CA74
CA73
BY74
BK74
BK72
BJ73
BJ74
BH74
BH72
BG73
BR74
BM 74
BL73
BP74
BN74
BM 72
BC73
AM 72
AF72
Y72
P72
H72
AM 74
AF74
Y74
P74
H74
AN73
AG73
AA73
R73
J73
AL74
AE74
W74
N74
G74
AJ73
AH74
AH72
AG74
AE73
AD74
AD72
AC74
AC73
AB74
AB72
AA74
W73
V74
V72
U74
U73
T 74
T 72
R74
N73
M 74
M 72
L74
L73
K74
K72
J74
G73
F74
F72
E74
AR73
AP74
AP72
AN74
AL73
AK74
AK72
AJ74
BB72
BB74
BA74
BA73
AY72
AY74
AW74
BP72
AV72
AU74
BN73
AW73
AV74
AT 74
AR74
BG74
BF74
BD74
BC74
U26
5
6
4
3
2
0
1
6
5
4
3
2
1
0
9
8
7
9
8
7
6
5
4
6
5
3
2
4
3
2
1
0
1
0
9
8
7
9
8
6
5
4
6
7
5
3
2
4
3
1
0
2
1
0
6
7
5
3
4
2
1
0
7
6
5
4
3
1
2
0
31
30
29
28
27
26
25
24
23
22
21
20
19
17
18
16
15
13
14
12
11
9
10
8
7
5
6
4
2
3
0
1
31
30
29
28
27
26
24
25
23
21
22
20
19
18
16
17
15
13
14
11
12
10
8
9
7
6
4
5
3
2
0
1
CAD NOTE:
1/40
TEST40
TEST39A
MA1_CLK_L
MA0_CLK_L
MA1_CLK_H
MAB_DQS_H9
MA0_CLK_H
MAB_PAR
MAA_PAR
MAA0_CS_L0
MAA_DATA3
MAA_DQS_H6
MAB_CA6
MAB_DATA2
MAB_DATA17
MAB_DATA28
MAB_DQS_H0
MAB_DQS_L4
MAA_CA6
MAA_DATA2
MAA_DQS_H5
MAA_DQS_L9
MAB1_RSP_L
MAB_CA5
MAB_CHECK7
MAB_DATA1
MAB_DATA16
MAB_DATA27
MAB_DQS_L3
MAA_CA5
MAA_DATA1
MAA_DQS_H4
MAA_DQS_L8
MAB0_RSP_L
MAB_CA4
MAB_CHECK6
MAB_DATA0
MAB_DATA15
MAB_DATA26
MAB_DQS_L2
MAA_CA4
MAA_DATA0
MAA_DQS_H3
MAA_DQS_L7
MAB_CA3
MAB_CHECK5
MAB_DATA14
MAB_DATA25
MAB_DQS_L1
MAA_CA3
MAA_DATA19
MAA_DQS_H2
MAA_DQS_L6
MAB_CA2
MAB_CHECK4
MAB_DATA13
MAB_DATA24
MAB_DQS_L0
MAA_CA2
MAA_DATA18
MAA_DATA29
MAA_DQS_H1
MAA_DQS_L5
MAB_CA1
MAB_CHECK3
MAB_DATA12
MAB_DATA23
MAA_CA1
MAA_DATA17
MAA_DATA28
MAA_DQS_H0
MAA_DQS_L4
MAB_CA0
MAB_CHECK2
MAB_DATA11
MAB_DATA22
MAA1_RSP_L
MAA_CA0
MAA_CHECK7
MAA_DATA16
MAA_DATA27
MAA_DQS_L3
MAB_CHECK1
MAB_DATA10
MAB_DATA21
MAA0_RSP_L
MAA_CHECK6
MAA_DATA15
MAA_DATA26
MAA_DQS_L2
MAB_CHECK0
MAB_DATA20
MAB_DATA31
MAA_CHECK5
MAA_DATA14
MAA_DATA25
MAA_DQS_L1
MAB1_CS_L1
MAB_DATA30
MAB_DQS_H8
MAA_CHECK4
MAA_DATA13
MAA_DATA24
MAA_DQS_L0
MAB0_CS_L1
MAB1_CS_L0
MAB_DATA9
MAB_DQS_H7
MAA_CHECK3
MAA_DATA9
MAA_DATA12
MAA_DATA23
MAB0_CS_L0
MAB_DATA8
MAB_DQS_H6
MAA_CHECK2
MAA_DATA8
MAA_DATA11
MAA_DATA22
MAB_DATA7
MAB_DQS_H5
MAB_DQS_L9
MAA_CHECK1
MAA_DATA7
MAA_DATA10
MAA_DATA21
MAB_DATA6
MAB_DQS_H4
MAB_DQS_L8
MAA_CHECK0
MAA_DATA6
MAA_DATA20
MAA_DATA31
MAA_DQS_H9
MAB_DATA5
MAB_DQS_H3
MAB_DQS_L7
MAA1_CS_L1
MAA_DATA5
MAA_DATA30
MAA_DQS_H8
MAB_DATA4
MAB_DATA19
MAB_DQS_H2
MAB_DQS_L6
MAA0_CS_L1
MAA1_CS_L0
MAA_DATA4
MAA_DQS_H7
MAB_DATA3
MAB_DATA18
MAB_DATA29
MAB_DQS_H1
MAB_DQS_L5
MA_RESET_L
MA_ALERT_L
1
SHEETDATE
23
7 3 2 16 5 4
E
A
B
C
E
D
C
B
A
7 6 5 4
D
DEPARTMENT
SIZE
PROJECT DOCUMENT NUMBER REV
REVIEWER
DESIGNER
IN
OUT
OUT
IN
OUT
OUT
OUT
IN
OUT
OUT
OUT
OUT
OUT
OUT
BI
BI
BI
BI
BI
BI
BI
BI
C



Thu Aug 24 14:08:41 2023<NAME_2>
<NAME_1>
MB FABCGTI V02
38 OF 365
99
99
99
99
99
99
99
99
99
99
99
99
99
99
99
99
99
99
99
99
99
99
15 M_B _CP U1_A LE RT_R_NM_B _CP U1_A LE RT_N 1%
0402LF
S O CK E T6096_13568-001
IO
TP _M_B _CP U1_S A _TE S T39B
M_B _CP U1_S A _CA <6:0>
M_B _CP U1_S B _CA <6:0>
M_B _CP U1_CLK _DP <0>
M_B _CP U1_CLK _DN<0>
M_B _CP U1_S A _CS _N<0>
M_B _CP U1_S A _CS _N<1>
M_B _CP U1_S A _RS P <0>
M_B _CP U1_S A _P A R
M_B _CP U1_S B _CS _N<1>
M_B _CP U1_S B _CS _N<0>
M_B _CP U1_S B _RS P <0>
M_B _CP U1_S B _P A R
M_B _CP U1_RE S E T_N
M_B _CP U1_S A _DQ S _DP <9:0>
M_B _CP U1_S B _DQ S _DP <9:0>
M_B _CP U1_S B _DQ S _DN<9:0>
M_B _CP U1_S A _DQ S _DN<9:0>
M_B _CP U1_S B _CB <7:0>
M_B _CP U1_S A _CB <7:0>
M_B _CP U1_S A _DQ <31:0>
M_B _CP U1_S B _DQ <31:0>
CPU1 DDR CHB
R1959 PLACE CLOSE TO CPU < 25MM
SMLF
21R501
BF62
BL64
BW64
DC62
CU62
CL62
CE62
BW62
DC64
CU64
CL64
CE64
BV63
DD62
CV62
CM 62
CF62
BY62
DB63
CT 63
CK63
CD63
DF62
DE64
DE62
DD63
DB62
DA64
DA62
CY63
CY62
CW64
CW62
CV63
CT 62
CR64
CR62
CP63
CP62
CN64
CN62
CM 63
CK62
CJ64
CJ62
CH63
CH62
CG64
CG62
CF63
CD62
CC64
CC62
CB63
BV62
BU64
BU62
BT 63
CB62
CA64
CA62
BY63
BK63
BK62
BJ62
BJ64
BH63
BH62
BG62
BR64
BM 63
BL62
BP63
BN64
BM 62
BC62
AM 62
AF62
Y62
P62
H62
AM 63
AF63
Y63
P63
H63
AN62
AG62
AA62
R62
J62
AL64
AE64
W64
N64
G64
AJ62
AH63
AH62
AG64
AE62
AD63
AD62
AC64
AC62
AB63
AB62
AA64
W62
V63
V62
U64
U62
T 63
T 62
R64
N62
M 63
M 62
L64
L62
K63
K62
J64
G62
F63
F62
E64
AR62
AP63
AP62
AN64
AL62
AK63
AK62
AJ64
BB62
BB63
BA64
BA62
AY62
AY63
AW64
BP62
AV62
AU64
BN62
AW62
AV63
AU62
AT 62
BG64
BF63
BD63
BC64
U26
5
4
6
3
2
0
1
6
5
4
2
3
1
9
0
9
8
7
6
4
5
8
7
5
6
4
3
2
1
9
0
3
2
1
0
8
7
6
4
5
8
9
7
6
5
4
2
3
1
0
3
2
1
0
6
7
5
4
3
2
1
0
6
7
5
4
3
31
0
1
2
26
27
28
29
30
23
22
24
25
19
20
21
18
17
16
14
15
13
12
10
9
11
8
6
7
5
4
3
0
1
2
31
28
30
29
27
26
25
24
23
22
21
19
20
18
17
16
15
14
13
12
9
10
11
8
7
6
5
3
4
0
1
2
CAD NOTE:
2/40
TEST39B
MBB_DATA20
MBA_DATA24
MBB_DATA19
MB1_CLK_L
MB1_CLK_H
MB0_CLK_L
MB0_CLK_H
MBB_PAR
MBA_PAR
MBB_DQS_H9
MBA_CHECK1
MBA_DATA10
MBA_DATA21
MBB_DQS_H4
MBB_DQS_L8
MBA1_CS_L1
MBA_CHECK0
MBA_DATA20
MBA_DATA31
MBA_DQS_H9
MBB_CA6
MBB_DQS_H3
MBB_DQS_L7
MBA0_CS_L1
MBA1_CS_L0
MBA_CA6
MBA_DATA30
MBA_DQS_H8
MBB_CA5
MBB_DQS_H2
MBB_DQS_L6
MBA0_CS_L0
MBA_CA5
MBA_DQS_H7
MBB_CA4
MBB_DATA18
MBB_DATA29
MBB_DQS_H1
MBB_DQS_L5
MBA_CA4
MBA_DQS_H6
MBB1_RSP_L
MBB_CA3
MBB_DATA9
MBB_DATA17
MBB_DATA28
MBB_DQS_H0
MBB_DQS_L4
MBA_CA3
MBA_DATA9MBA_DQS_H5
MBA_DQS_L9
MBB0_RSP_L
MBB_CA2
MBB_CHECK7
MBB_DATA8
MBB_DATA16
MBB_DATA27
MBB_DQS_L3
MBA_CA2
MBA_DATA8
MBA_DQS_H4
MBA_DQS_L8
MBB_CA1
MBB_CHECK6
MBB_DATA7
MBB_DATA15
MBB_DATA26
MBB_DQS_L2
MBA_CA1
MBA_DATA7
MBA_DQS_H3
MBA_DQS_L7
MBB_CA0
MBB_CHECK5
MBB_DATA6
MBB_DATA14
MBB_DATA25
MBB_DQS_L1
MBA_CA0
MBA_DATA6
MBA_DATA19
MBA_DQS_H2
MBA_DQS_L6
MBB_CHECK4
MBB_DATA5
MBB_DATA13
MBB_DATA24
MBB_DQS_L0
MBA_DATA5
MBA_DATA18
MBA_DATA29
MBA_DQS_H1
MBA_DQS_L5
MBB_CHECK3
MBB_DATA4
MBB_DATA12
MBB_DATA23
MBA1_RSP_L
MBA_DATA4
MBA_DATA17
MBA_DATA28
MBA_DQS_H0
MBA_DQS_L4
MBB_CHECK2
MBB_DATA3
MBB_DATA11
MBB_DATA22
MBA0_RSP_L
MBA_CHECK7
MBA_DATA3
MBA_DATA16
MBA_DATA27
MBA_DQS_L3
MBB_CHECK1
MBB_DATA2
MBB_DATA10
MBB_DATA21
MBA_CHECK6
MBA_DATA2
MBA_DATA15
MBA_DATA26
MBA_DQS_L2
MBB1_CS_L1
MBB_CHECK0
MBB_DATA1
MBB_DATA31
MBA_CHECK5
MBA_DATA1
MBA_DATA14
MBA_DATA25
MBA_DQS_L1
MBB0_CS_L1
MBB1_CS_L0
MBB_DATA0
MBB_DATA30
MBB_DQS_H8
MBA_CHECK4
MBA_DATA0
MBA_DATA13
MBA_DQS_L0
MBB0_CS_L0
MBB_DQS_H7
MBA_CHECK3
MBA_DATA12
MBA_DATA23
MBB_DQS_H6
MBA_CHECK2
MBA_DATA11
MBA_DATA22
MBB_DQS_H5
MBB_DQS_L9
MB_RESET_L
MB_ALERT_L
1
SHEETDATE
23
7 3 2 16 5 4
E
A
B
C
E
D
C
B
A
7 6 5 4
D
DEPARTMENT
SIZE
PROJECT DOCUMENT NUMBER REV
REVIEWER
DESIGNER
OUT
IN
OUT
IN
OUT
OUT
OUT
IN
OUT
OUT
OUT
OUT
OUT
OUT
BI
BI
BI
BI
BI
BI
BI
BI
C



Thu Aug 24 14:08:41 2023<NAME_2>
<NAME_1>
MB FABCGTI V02
39 OF 365
100
100
100
100
100
100
100
100
100
100
100
100
100
100
100
100
100
100
100
100
100
100
15 M_C_CP U1_A LE RT_R_NM_C_CP U1_A LE RT_N 1%
0402LF
S O CK E T6096_13568-001
IO
M_C_CP U1_S B _CA <6:0>
M_C_CP U1_S A _CA <6:0>
TP _M_C_CP U1_S A _TE S T39C
M_C_CP U1_CLK _DN<0>
M_C_CP U1_CLK _DP <0>
M_C_CP U1_S A _CS _N<1>
M_C_CP U1_S A _CS _N<0>
M_C_CP U1_S A _RS P <0>
M_C_CP U1_S A _P A R
M_C_CP U1_S B _CS _N<0>
M_C_CP U1_S B _CS _N<1>
M_C_CP U1_S B _RS P <0>
M_C_CP U1_S B _P A R
M_C_CP U1_RE S E T_N
M_C_CP U1_S B _DQ S _DN<9:0>
M_C_CP U1_S A _DQ S _DN<9:0>
M_C_CP U1_S A _DQ S _DP <9:0>
M_C_CP U1_S B _DQ S _DP <9:0>
M_C_CP U1_S A _CB <7:0>
M_C_CP U1_S B _CB <7:0>
M_C_CP U1_S A _DQ <31:0>
M_C_CP U1_S B _DQ <31:0>
CPU1 DDR CHC
R1960 PLACE CLOSE TO CPU < 25MM
SMLF
21R502
BF55
BL57
BW57
DC55
CU55
CL55
CE55
BW55
DC57
CU57
CL57
CE57
BV56
DD55
CV55
CM 55
CF55
BY55
DB56
CT 56
CK56
CD56
DF55
DE57
DE55
DD56
DB55
DA57
DA55
CY56
CY55
CW57
CW55
CV56
CT 55
CR57
CR55
CP56
CP55
CN57
CN55
CM 56
CK55
CJ57
CJ55
CH56
CH55
CG57
CG55
CF56
CD55
CC57
CC55
CB56
BV55
BU57
BU55
BT 56
CB55
CA57
CA55
BY56
BK56
BK55
BJ55
BJ57
BH56
BH55
BG55
BR57
BM 56
BL55
BP56
BN57
BM 55
BC55
AM 55
AF55
Y55
P55
H55
AM 56
AF56
Y56
P56
H56
AN55
AG55
AA55
R55
J55
AL57
AE57
W57
N57
G57
AJ55
AH56
AH55
AG57
AE55
AD56
AD55
AC57
AC55
AB56
AB55
AA57
W55
V56
V55
U57
U55
T 56
T 55
R57
N55
M 56
M 55
L57
L55
K56
K55
J57
G55
F56
F55
E57
AR55
AP56
AP55
AN57
AL55
AK56
AK55
AJ57
BB55
BB56
BA57
BA55
AY55
AY56
AW57
BP55
AV55
AU57
BN55
AW55
AV56
AU55
AT 55
BG57
BF56
BD56
BC57
U26
6
5
4
3
0
1
2
6
5
4
2
3
0
1
9
8
7
6
4
5
8
9
7
6
4
5
3
2
1
0
9
3
2
1
0
8
7
6
4
5
9
7
8
6
5
3
2
0
1
3
4
2
1
0
6
7
5
4
3
2
1
0
7
6
3
4
5
0
31
2
1
30
29
26
28
27
23
25
24
22
20
21
19
17
18
16
14
15
13
11
12
10
8
9
7
4
5
6
2
3
1
0
31
29
30
27
28
26
24
25
22
23
20
21
17
18
19
16
15
14
13
11
12
10
8
9
7
4
5
6
2
3
1
0
CAD NOTE:
3/40
TEST39C
MC1_CLK_L
MC1_CLK_H
MC0_CLK_L
MC0_CLK_H
MCB_PAR
MCA_PAR
MCB_DQS_H9
MCA_CHECK4
MCA_DATA8
MCA_DATA13
MCA_DATA24
MCA_DQS_L0
MCB0_CS_L0
MCB1_CS_L0
MCB_DATA7
MCB_DQS_H7
MCA_CHECK3
MCA_DATA7
MCA_DATA12
MCA_DATA23
MCB_DATA6
MCB_DQS_H6
MCA_CHECK2
MCA_DATA6
MCA_DATA11
MCA_DATA22
MCB_CA6
MCB_DATA5
MCB_DQS_H5
MCB_DQS_L9
MCA_CA6
MCA_CHECK1
MCA_DATA5
MCA_DATA10
MCA_DATA21
MCB_CA5
MCB_DATA4
MCB_DQS_H4
MCB_DQS_L8
MCA_CA5
MCA_CHECK0
MCA_DATA4
MCA_DATA20
MCA_DATA31
MCA_DQS_H9
MCB_CA4
MCB_DATA3
MCB_DQS_H3
MCB_DQS_L7
MCA1_CS_L1
MCA_CA4
MCA_DATA3
MCA_DATA30
MCA_DQS_H8
MCB_CA3
MCB_DATA2
MCB_DATA19
MCB_DQS_H2
MCB_DQS_L6
MCA0_CS_L1
MCA1_CS_L0
MCA_CA3
MCA_DATA2
MCA_DQS_H7
MCB_CA2
MCB_DATA1
MCB_DATA18
MCB_DATA29
MCB_DQS_H1
MCB_DQS_L5
MCA0_CS_L0
MCA_CA2
MCA_DATA1
MCA_DQS_H6
MCB_CA1
MCB_DATA0
MCB_DATA17
MCB_DATA28
MCB_DQS_H0
MCB_DQS_L4
MCA_CA1
MCA_DATA0
MCA_DQS_H5
MCA_DQS_L9
MCB0_RSP_L
MCB1_RSP_L
MCB_CA0
MCB_CHECK7
MCB_DATA16
MCB_DATA27
MCB_DQS_L3
MCA_CA0
MCA_DQS_H4
MCA_DQS_L8
MCB_CHECK6
MCB_DATA15
MCB_DATA26
MCB_DQS_L2
MCA_DQS_H3
MCA_DQS_L7
MCB_CHECK5
MCB_DATA14
MCB_DATA25
MCB_DQS_L1
MCA_DATA19
MCA_DQS_H2
MCA_DQS_L6
MCB_CHECK4
MCB_DATA13
MCB_DATA24
MCB_DQS_L0
MCA_DATA18
MCA_DATA29
MCA_DQS_H1
MCA_DQS_L5
MCB_CHECK3
MCB_DATA12
MCB_DATA23
MCA_DATA17
MCA_DATA28
MCA_DQS_H0
MCA_DQS_L4
MCB_CHECK2
MCB_DATA11
MCB_DATA22
MCA1_RSP_L
MCA_CHECK7
MCA_DATA16
MCA_DATA27
MCA_DQS_L3
MCB_CHECK1
MCB_DATA10
MCB_DATA21
MCA0_RSP_L
MCA_CHECK6
MCA_DATA15
MCA_DATA26
MCA_DQS_L2
MCB_CHECK0
MCB_DATA9
MCB_DATA20
MCB_DATA31
MCA_CHECK5
MCA_DATA9
MCA_DATA14
MCA_DATA25
MCA_DQS_L1
MCB0_CS_L1
MCB1_CS_L1
MCB_DATA8
MCB_DATA30
MCB_DQS_H8
MC_RESET_L
MC_ALERT_L
1
SHEETDATE
23
7 3 2 16 5 4
E
A
B
C
E
D
C
B
A
7 6 5 4
D
DEPARTMENT
SIZE
PROJECT DOCUMENT NUMBER REV
REVIEWER
DESIGNER
IN
OUT
OUT
IN
OUT
OUT
OUT
IN
OUT
OUT
OUT
OUT
OUT
OUT
BI
BI
BI
BI
BI
BI
BI
BI
C



Thu Aug 24 14:08:41 2023<NAME_2>
<NAME_1>
MB FABCGTI V02
40 OF 365
101
101
101
101
101
101
101
101
101
101
101
101
101
101
101
101
101
101
101
101
101
101
15 M_D_CP U1_A LE RT_R_NM_D_CP U1_A LE RT_N 1%
0402LF
S O CK E T6096_13568-001
IO
TP _M_D_CP U1_S A _TE S T39D
M_D_CP U1_S A _CA <6:0>
M_D_CP U1_S B _CA <6:0>
M_D_CP U1_CLK _DP <0>
M_D_CP U1_CLK _DN<0>
M_D_CP U1_S A _CS _N<0>
M_D_CP U1_S A _CS _N<1>
M_D_CP U1_S A _RS P <0>
M_D_CP U1_S A _P A R
M_D_CP U1_S B _CS _N<0>
M_D_CP U1_S B _CS _N<1>
M_D_CP U1_S B _RS P <0>
M_D_CP U1_S B _P A R
M_D_CP U1_RE S E T_N
M_D_CP U1_S A _DQ S _DP <9:0>
M_D_CP U1_S B _DQ S _DP <9:0>
M_D_CP U1_S B _DQ S _DN<9:0>
M_D_CP U1_S A _DQ S _DN<9:0>
M_D_CP U1_S B _CB <7:0>
M_D_CP U1_S A _CB <7:0>
M_D_CP U1_S A _DQ <31:0>
M_D_CP U1_S B _DQ <31:0>
CPU1 DDR CHD
R1961 PLACE CLOSE TO CPU < 25MM
SMLF
21R503
BF58
BL60
BW60
DC59
CU59
CL59
CE59
BW59
DC60
CU60
CL60
CE60
BV60
DD58
CV58
CM 58
CF58
BY58
DB60
CT 60
CK60
CD60
DF60
DE60
DE59
DD60
DB58
DA60
DA59
CY60
CY58
CW60
CW59
CV60
CT 58
CR60
CR59
CP60
CP58
CN60
CN59
CM 60
CK58
CJ60
CJ59
CH60
CH58
CG60
CG59
CF60
CD58
CC60
CC59
CB60
BV58
BU60
BU59
BT 60
CB58
CA60
CA59
BY60
BK60
BK58
BJ59
BJ60
BH60
BH58
BG59
BR60
BM 60
BL59
BP60
BN60
BM 58
BC59
AM 58
AF58
Y58
P58
H58
AM 60
AF60
Y60
P60
H60
AN59
AG59
AA59
R59
J59
AL60
AE60
W60
N60
G60
AJ59
AH60
AH58
AG60
AE59
AD60
AD58
AC60
AC59
AB60
AB58
AA60
W59
V60
V58
U60
U59
T 60
T 58
R60
N59
M 60
M 58
L60
L59
K60
K58
J60
G59
F60
F58
E60
AR59
AP60
AP58
AN60
AL59
AK60
AK58
AJ60
BB58
BB60
BA60
BA59
AY58
AY60
AW60
BP58
AV58
AU60
BN59
AW59
AV60
AU59
AT 58
BG60
BF60
BD60
BC60
U26
6
5
4
2
3
0
1
6
5
4
3
2
0
1
9
9
8
7
6
5
4
8
7
6
5
4
3
2
1
0
9
3
2
1
0
8
7
6
5
4
9
8
7
6
5
4
3
2
1
0
3
2
1
0
5
4
6
7
2
3
0
1
7
6
5
4
3
1
2
0
31
27
26
28
30
29
25
22
23
24
20
19
21
18
17
16
13
12
14
15
9
8
10
11
7
6
5
3
4
0
2
31
1
27
26
28
30
29
25
24
23
22
17
18
19
21
20
13
12
14
15
16
8
9
10
11
7
6
5
3
4
0
2
1
CAD NOTE:
4/40
TEST39D
MD1_CLK_L
MD1_CLK_H
MD0_CLK_L
MD0_CLK_H
MDB_DQS_H9
MDB_CA3
MDB_PAR
MDA_PAR
MDA1_RSP_L
MDA_DATA2
MDA_DATA17
MDA_DATA28
MDA_DQS_H0
MDA_DQS_L4
MDB_CHECK2
MDB_DATA1
MDB_DATA11
MDB_DATA22
MDA0_RSP_L
MDA_CHECK7
MDA_DATA1
MDA_DATA16
MDA_DATA27
MDA_DQS_L3
MDB_CHECK1
MDB_DATA0
MDB_DATA10
MDB_DATA21
MDA_CHECK6
MDA_DATA0
MDA_DATA15
MDA_DATA26
MDA_DQS_L2
MDB1_CS_L1
MDB_CHECK0
MDB_DATA20
MDB_DATA31
MDA_CHECK5
MDA_DATA14
MDA_DATA25
MDA_DQS_L1
MDB0_CS_L1
MDB1_CS_L0
MDB_CA6
MDB_DATA30
MDB_DQS_H8
MDA_CA6
MDA_CHECK4
MDA_DATA13
MDA_DATA24
MDA_DQS_L0
MDB0_CS_L0
MDB_CA5
MDB_DQS_H7
MDA_CA5
MDA_CHECK3
MDA_DATA12
MDA_DATA23
MDB_CA4
MDB_DQS_H6
MDA_CA4
MDA_CHECK2
MDA_DATA11
MDA_DATA22
MDB_DQS_H5
MDB_DQS_L9
MDA_CA3
MDA_CHECK1
MDA_DATA10
MDA_DATA21
MDB_CA2
MDB_DQS_H4
MDB_DQS_L8
MDA1_CS_L1
MDA_CA2
MDA_CHECK0
MDA_DATA20
MDA_DATA31
MDA_DQS_H9
MDB_CA1
MDB_DQS_H3
MDB_DQS_L7
MDA0_CS_L1
MDA1_CS_L0
MDA_CA1
MDA_DATA30
MDA_DQS_H8
MDB_CA0
MDB_DATA9
MDB_DATA19
MDB_DQS_H2
MDB_DQS_L6
MDA0_CS_L0
MDA_CA0
MDA_DATA9
MDA_DQS_H7
MDB_DATA8
MDB_DATA18
MDB_DATA29
MDB_DQS_H1
MDB_DQS_L5
MDA_DATA8
MDA_DQS_H6
MDB1_RSP_L
MDB_DATA7
MDB_DATA17
MDB_DATA28
MDB_DQS_H0
MDB_DQS_L4
MDA_DATA7
MDA_DQS_H5
MDA_DQS_L9
MDB0_RSP_L
MDB_CHECK7
MDB_DATA6
MDB_DATA16
MDB_DATA27
MDB_DQS_L3
MDA_DATA6
MDA_DQS_H4
MDA_DQS_L8
MDB_CHECK6
MDB_DATA5
MDB_DATA15
MDB_DATA26
MDB_DQS_L2
MDA_DATA5
MDA_DQS_H3
MDA_DQS_L7
MDB_CHECK5
MDB_DATA4
MDB_DATA14
MDB_DATA25
MDB_DQS_L1
MDA_DATA4
MDA_DATA19
MDA_DQS_H2
MDA_DQS_L6
MDB_CHECK4
MDB_DATA3
MDB_DATA13
MDB_DATA24
MDB_DQS_L0
MDA_DATA3
MDA_DATA18
MDA_DATA29
MDA_DQS_H1
MDA_DQS_L5
MDB_CHECK3
MDB_DATA2
MDB_DATA12
MDB_DATA23
MD_RESET_L
MD_ALERT_L
1
SHEETDATE
23
7 3 2 16 5 4
E
A
B
C
E
D
C
B
A
7 6 5 4
D
DEPARTMENT
SIZE
PROJECT DOCUMENT NUMBER REV
REVIEWER
DESIGNER
OUT
IN
OUT
IN
OUT
OUT
OUT
IN
OUT
OUT
OUT
OUT
OUT
OUT
BI
BI
BI
BI
BI
BI
BI
BI
C



Thu Aug 24 14:08:42 2023<NAME_2>
<NAME_1>
MB FABCGTI V02
41 OF 365
102
102
102
102
102
102
102
102
102
102
102
102
102
102
102
102
102
102
102
102
102
102
15 M_E _CP U1_A LE RT_R_NM_E _CP U1_A LE RT_N 1%
0402LF
S O CK E T6096_13568-001
IO
TP _M_E _CP U1_S A _TE S T39E
M_E _CP U1_S A _CA <6:0>
M_E _CP U1_S B _CA <6:0>
M_E _CP U1_CLK _DP <0>
M_E _CP U1_CLK _DN<0>
M_E _CP U1_S A _CS _N<0>
M_E _CP U1_S A _RS P <0>
M_E _CP U1_S A _CS _N<1>
M_E _CP U1_S A _P A R
M_E _CP U1_S B _CS _N<1>
M_E _CP U1_S B _CS _N<0>
M_E _CP U1_S B _RS P <0>
M_E _CP U1_S B _P A R
M_E _CP U1_RE S E T_N
M_E _CP U1_S A _DQ S _DP <9:0>
M_E _CP U1_S B _DQ S _DP <9:0>
M_E _CP U1_S B _DQ S _DN<9:0>
M_E _CP U1_S A _DQ S _DN<9:0>
M_E _CP U1_S B _CB <7:0>
M_E _CP U1_S A _CB <7:0>
M_E _CP U1_S A _DQ <31:0>
M_E _CP U1_S B _DQ <31:0>
CPU1 DDR CHE
R1962 PLACE CLOSE TO CPU < 25MM
SMLF
21R504
BF69
BL71
BW71
DC69
CU69
CL69
CE69
BW69
DC71
CU71
CL71
CE71
BV70
DD69
CV69
CM 69
CF69
BY69
DB70
CT 70
CK70
CD70
DF69
DE71
DE69
DD70
DB69
DA71
DA69
CY70
CY69
CW71
CW69
CV70
CT 69
CR71
CR69
CP70
CP69
CN71
CN69
CM 70
CK69
CJ71
CJ69
CH70
CH69
CG71
CG69
CF70
CD69
CC71
CC69
CB70
BV69
BU71
BU69
BT 70
CB69
CA71
CA69
BY70
BK70
BK69
BJ69
BJ71
BH70
BH69
BG69
BR71
BM 70
BL69
BP70
BN71
BM 69
BC69
AM 69
AF69
Y69
P69
H69
AM 70
AF70
Y70
P70
H70
AN69
AG69
AA69
R69
J69
AL71
AE71
W71
N71
G71
AJ69
AH70
AH69
AG71
AE69
AD70
AD69
AC71
AC69
AB70
AB69
AA71
W69
V70
V69
U71
U69
T 70
T 69
R71
N69
M 70
M 69
L71
L69
K70
K69
J71
G69
F70
F69
E71
AR69
AP70
AP69
AN71
AL69
AK70
AK69
AJ71
BB69
BB70
BA71
BA69
AY69
AY70
AW71
BP69
AV69
AU71
BN69
AW69
AV70
AU69
AT 69
BG71
BF70
BD70
BC71
U26
5
6
4
3
2
1
0
6
5
4
3
2
1
0
9
8
9
7
6
5
4
3
7
8
6
4
5
2
1
0
9
3
2
1
9
0
7
8
6
5
4
3
7
8
6
4
5
2
1
0
2
3
1
0
7
6
4
5
3
2
1
0
7
6
4
5
2
3
1
0
31
30
29
27
28
26
25
23
24
21
22
19
20
18
17
16
15
14
13
12
11
10
9
8
7
6
5
3
4
2
1
0
31
30
29
27
28
26
25
24
23
22
21
19
20
18
17
16
15
14
13
12
11
10
9
8
7
6
5
4
3
2
1
0
CAD NOTE:
5/40
TEST39E
ME1_CLK_L
ME1_CLK_H
ME0_CLK_L
ME0_CLK_H
MEB_DQS_H9
MEB_PAR
MEA_PAR
MEA_DQS_H3
MEA_DQS_L7
MEB_CHECK5
MEB_DATA14
MEB_DATA25
MEB_DQS_L1
MEA_DATA19
MEA_DQS_H2
MEA_DQS_L6
MEB_CHECK4
MEB_DATA13
MEB_DATA24
MEB_DQS_L0
MEA_DATA18
MEA_DATA29
MEA_DQS_H1
MEA_DQS_L5
MEB_CHECK3
MEB_DATA12
MEB_DATA23
MEA_DATA17
MEA_DATA28
MEA_DQS_H0
MEA_DQS_L4
MEB_CHECK2
MEB_DATA9
MEB_DATA11
MEB_DATA22
MEA0_RSP_L
MEA1_RSP_L
MEA_CHECK7
MEA_DATA9
MEA_DATA16
MEA_DATA27
MEA_DQS_L3
MEB_CA6
MEB_CHECK1
MEB_DATA8
MEB_DATA10
MEB_DATA21
MEA_CA6
MEA_CHECK6
MEA_DATA8
MEA_DATA15
MEA_DATA26
MEA_DQS_L2
MEB_CA5
MEB_CHECK0
MEB_DATA7
MEB_DATA20
MEB_DATA31
MEA_CA5
MEA_CHECK5
MEA_DATA7
MEA_DATA14
MEA_DATA25
MEA_DQS_L1
MEB0_CS_L1
MEB1_CS_L1
MEB_CA4
MEB_DATA6
MEB_DATA30
MEB_DQS_H8
MEA_CA4
MEA_CHECK4
MEA_DATA6
MEA_DATA13
MEA_DATA24
MEA_DQS_L0
MEB0_CS_L0
MEB1_CS_L0
MEB_CA3
MEB_DATA5
MEB_DQS_H7
MEA_CA3
MEA_CHECK3
MEA_DATA5
MEA_DATA12
MEA_DATA23
MEB_CA2
MEB_DATA4
MEB_DQS_H6
MEA_CA2
MEA_CHECK2
MEA_DATA4
MEA_DATA11
MEA_DATA22
MEB_CA1
MEB_DATA3
MEB_DQS_H5
MEB_DQS_L9
MEA_CA1
MEA_CHECK1
MEA_DATA3
MEA_DATA10
MEA_DATA21
MEB_CA0
MEB_DATA2
MEB_DQS_H4
MEB_DQS_L8
MEA_CA0
MEA_CHECK0
MEA_DATA2
MEA_DATA20
MEA_DATA31
MEA_DQS_H9
MEB_DATA1
MEB_DQS_H3
MEB_DQS_L7
MEA0_CS_L1
MEA1_CS_L1
MEA_DATA1
MEA_DATA30
MEA_DQS_H8
MEB_DATA0
MEB_DATA19
MEB_DQS_H2
MEB_DQS_L6
MEA0_CS_L0
MEA1_CS_L0
MEA_DATA0
MEA_DQS_H7
MEB_DATA18
MEB_DATA29
MEB_DQS_H1
MEB_DQS_L5
MEA_DQS_H6
MEB_DATA17
MEB_DATA28
MEB_DQS_H0
MEB_DQS_L4
MEA_DQS_H5
MEA_DQS_L9
MEB0_RSP_L
MEB1_RSP_L
MEB_CHECK7
MEB_DATA16
MEB_DATA27
MEB_DQS_L3
MEA_DQS_H4
MEA_DQS_L8
MEB_CHECK6
MEB_DATA15
MEB_DATA26
MEB_DQS_L2
ME_RESET_L
ME_ALERT_L
1
SHEETDATE
23
7 3 2 16 5 4
E
A
B
C
E
D
C
B
A
7 6 5 4
D
DEPARTMENT
SIZE
PROJECT DOCUMENT NUMBER REV
REVIEWER
DESIGNER
OUT
IN
OUT
IN
OUT
OUT
OUT
OUT
IN
OUT
OUT
OUT
OUT
OUT
BI
BI
BI
BI
BI
BI
BI
BI
C



Thu Aug 24 14:08:42 2023<NAME_2>
<NAME_1>
MB FABCGTI V02
42 OF 365
103
103
103
103
103
103
103
103
103
103
103
103
103
103
103
103
103
103
103
103
103
103
15 M_F_CP U1_A LE RT_R_NM_F_CP U1_A LE RT_N 1%
0402LF
S O CK E T6096_13568-001
IO
TP _M_F_CP U1_S A _TE S T39F
M_F_CP U1_S A _CA <6:0>
M_F_CP U1_S B _CA <6:0>
M_F_CP U1_CLK _DP <0>
M_F_CP U1_CLK _DN<0>
M_F_CP U1_S A _CS _N<0>
M_F_CP U1_S A _CS _N<1>
M_F_CP U1_S A _RS P <0>
M_F_CP U1_S A _P A R
M_F_CP U1_S B _CS _N<0>
M_F_CP U1_S B _CS _N<1>
M_F_CP U1_S B _RS P <0>
M_F_CP U1_S B _P A R
M_F_CP U1_RE S E T_N
M_F_CP U1_S A _DQ S _DP <9:0>
M_F_CP U1_S B _DQ S _DP <9:0>
M_F_CP U1_S B _DQ S _DN<9:0>
M_F_CP U1_S A _DQ S _DN<9:0>
M_F_CP U1_S A _CB <7:0>
M_F_CP U1_S B _CB <7:0>
M_F_CP U1_S B _DQ <31:0>
M_F_CP U1_S A _DQ <31:0>
CPU1 DDR CHF
R1963 PLACE CLOSE TO CPU < 25MM
SMLF
21R505
BF65
BL67
BW67
DC66
CU66
CL66
CE66
BW66
DC67
CU67
CL67
CE67
BV67
DD65
CV65
CM 65
CF65
BY65
DB67
CT 67
CK67
CD67
DF67
DE67
DE66
DD67
DB65
DA67
DA66
CY67
CY65
CW67
CW66
CV67
CT 65
CR67
CR66
CP67
CP65
CN67
CN66
CM 67
CK65
CJ67
CJ66
CH67
CH65
CG67
CG66
CF67
CD65
CC67
CC66
CB67
BV65
BU67
BU66
BT 67
CB65
CA67
CA66
BY67
BK67
BK65
BJ66
BJ67
BH67
BH65
BG66
BR67
BM 67
BL66
BP67
BN67
BM 65
BC66
AM 65
AF65
Y65
P65
H65
AM 67
AF67
Y67
P67
H67
AN66
AG66
AA66
R66
J66
AL67
AE67
W67
N67
G67
AJ66
AH67
AH65
AG67
AE66
AD67
AD65
AC67
AC66
AB67
AB65
AA67
W66
V67
V65
U67
U66
T 67
T 65
R67
N66
M 67
M 65
L67
L66
K67
K65
J67
G66
F67
F65
E67
AR66
AP67
AP65
AN67
AL66
AK67
AK65
AJ67
BB65
BB67
BA67
BA66
AY65
AY67
AW67
BP65
AV65
AU67
BN66
AW66
AV67
AU66
AT 65
BG67
BF67
BD67
BC67
U26
6
5
4
3
1
2
0
6
5
4
3
2
0
1
8
9
7
6
5
9
8
7
5
6
4
3
2
1
0
4
3
2
0
1
9
8
7
6
5
8
9
7
6
4
3
2
1
0
4
5
3
2
1
0
7
5
4
6
3
2
0
1
6
5
7
4
3
0
2
1
31
30
28
29
26
27
25
24
22
23
21
19
20
18
17
16
15
13
12
14
11
10
8
9
6
7
5
3
4
2
1
0
31
29
30
28
27
26
24
25
22
23
21
20
19
18
17
16
15
14
12
13
10
11
9
8
7
6
4
3
5
2
1
0
CAD NOTE:
6/40
TEST39F
MF1_CLK_L
MF1_CLK_H
MF0_CLK_L
MF0_CLK_H
MFB_DQS_H9
MFB_PAR
MFA_PAR
MFA0_CS_L0
MFA_DATA7
MFA_DQS_H7
MFB_DATA6
MFB_DATA18
MFB_DATA29
MFB_DQS_H1
MFB_DQS_L5
MFA_DATA6
MFA_DQS_H6
MFB1_RSP_L
MFB_DATA5
MFB_DATA17
MFB_DATA28
MFB_DQS_H0
MFB_DQS_L4
MFA_DATA5
MFA_DQS_H5
MFA_DQS_L9
MFB0_RSP_L
MFB_CHECK7
MFB_DATA4
MFB_DATA16
MFB_DATA27
MFB_DQS_L3
MFA_DATA4
MFA_DQS_H4
MFA_DQS_L8
MFB_CHECK6
MFB_DATA3
MFB_DATA15
MFB_DATA26
MFB_DQS_L2
MFA_DATA3
MFA_DQS_H3
MFA_DQS_L7
MFB_CHECK5
MFB_DATA2
MFB_DATA14
MFB_DATA25
MFB_DQS_L1
MFA_DATA2
MFA_DATA19
MFA_DQS_H2
MFA_DQS_L6
MFB_CA6
MFB_CHECK4
MFB_DATA1
MFB_DATA13
MFB_DATA24
MFB_DQS_L0
MFA_CA6
MFA_DATA1
MFA_DATA18
MFA_DATA29
MFA_DQS_H1
MFA_DQS_L5
MFB_CA5
MFB_CHECK3
MFB_DATA0
MFB_DATA12
MFB_DATA23
MFA1_RSP_L
MFA_CA5
MFA_DATA0
MFA_DATA17
MFA_DATA28
MFA_DQS_H0
MFA_DQS_L4
MFB_CA4
MFB_CHECK2
MFB_DATA11
MFB_DATA22
MFA0_RSP_L
MFA_CA4
MFA_CHECK7
MFA_DATA16
MFA_DATA27
MFA_DQS_L3
MFB_CA3
MFB_CHECK1
MFB_DATA10
MFB_DATA21
MFA_CA3
MFA_CHECK6
MFA_DATA15
MFA_DATA26
MFA_DQS_L2
MFB1_CS_L1
MFB_CA2
MFB_CHECK0
MFB_DATA20
MFB_DATA31
MFA_CA2
MFA_CHECK5
MFA_DATA14
MFA_DATA25
MFA_DQS_L1
MFB0_CS_L1
MFB1_CS_L0
MFB_CA1
MFB_DATA30
MFB_DQS_H8
MFA_CA1
MFA_CHECK4
MFA_DATA13
MFA_DATA24
MFA_DQS_L0
MFB0_CS_L0
MFB_CA0
MFB_DQS_H7
MFA_CA0
MFA_CHECK3
MFA_DATA12
MFA_DATA23
MFB_DQS_H6
MFA_CHECK2
MFA_DATA11
MFA_DATA22
MFB_DQS_H5
MFB_DQS_L9
MFA_CHECK1
MFA_DATA10
MFA_DATA21
MFB_DATA9
MFB_DQS_H4
MFB_DQS_L8
MFA1_CS_L1
MFA_CHECK0
MFA_DATA9
MFA_DATA20
MFA_DATA31
MFA_DQS_H9
MFB_DATA8
MFB_DQS_H3
MFB_DQS_L7
MFA0_CS_L1
MFA1_CS_L0
MFA_DATA8
MFA_DATA30
MFA_DQS_H8
MFB_DATA7
MFB_DATA19
MFB_DQS_H2
MFB_DQS_L6
MF_RESET_L
MF_ALERT_L
1
SHEETDATE
23
7 3 2 16 5 4
E
A
B
C
E
D
C
B
A
7 6 5 4
D
DEPARTMENT
SIZE
PROJECT DOCUMENT NUMBER REV
REVIEWER
DESIGNER
IN
OUT
OUT
IN
OUT
OUT
OUT
IN
OUT
OUT
OUT
OUT
OUT
OUT
BI
BI
BI
BI
BI
BI
BI
BI
C



Thu Aug 24 14:08:42 2023<NAME_2>
<NAME_1>
MB FABCGTI V02
43 OF 365
104
104
104
104
104
104
104
104
104
104
104
104
104
104
104
104
104
104
104
104
104
104
15 M_G _CP U1_A LE RT_R_NM_G _CP U1_A LE RT_N 1%
0402LF
S O CK E T6096_13568-001
IO
TP _M_G _CP U1_S A _TE S T39G
M_G _CP U1_S A _CA <6:0>
M_G _CP U1_S B _CA <6:0>
M_G _CP U1_CLK _DN<0>
M_G _CP U1_CLK _DP <0>
M_G _CP U1_S A _CS _N<0>
M_G _CP U1_S A _CS _N<1>
M_G _CP U1_S A _P A R
M_G _CP U1_S A _RS P <0>
M_G _CP U1_S B _CS _N<0>
M_G _CP U1_S B _CS _N<1>
M_G _CP U1_S B _RS P <0>
M_G _CP U1_S B _P A R
M_G _CP U1_RE S E T_N
M_G _CP U1_S A _DQ S _DP <9:0>
M_G _CP U1_S B _DQ S _DP <9:0>
M_G _CP U1_S B _DQ S _DN<9:0>
M_G _CP U1_S A _DQ S _DN<9:0>
M_G _CP U1_S A _CB <7:0>
M_G _CP U1_S B _CB <7:0>
M_G _CP U1_S A _DQ <31:0>
M_G _CP U1_S B _DQ <31:0>
CPU1 DDR CHG
R1964 PLACE CLOSE TO CPU < 25MM
SMLF
21R506
BF4
BL3
BW2
DC3
CU3
CL3
CE3
BW3
DC2
CU2
CL2
CE2
BV2
DD4
CV4
CM 4
CF4
BY4
DB2
CT 2
CK2
CD2
DF2
DE2
DE3
DD2
DB4
DA2
DA3
CY2
CY4
CW2
CW3
CV2
CT 4
CR2
CR3
CP2
CP4
CN2
CN3
CM 2
CK4
CJ2
CJ3
CH2
CH4
CG2
CG3
CF2
CD4
CC2
CC3
CB2
BV4
BU2
BU3
BT 2
CB4
CA2
CA3
BY2
BK2
BK4
BJ3
BJ2
BH2
BH4
BG3
BR2
BM 2
BL2
BP2
BN2
BM 4
BC3
AM 4
AF4
Y4
P4
H4
AM 2
AF2
Y2
P2
H2
AN3
AG3
AA3
R3
J3
AL2
AE2
W2
N2
G2
AJ3
AH2
AH4
AG2
AE3
AD2
AD4
AC2
AC3
AB2
AB4
AA2
W3
V2
V4
U2
U3
T 2
T 4
R2
N3
M 2
M 4
L2
L3
K2
K4
J2
G3
F2
F4
E2
AR3
AP2
AP4
AN2
AL3
AK2
AK4
AJ2
BB4
BB2
BA2
BA3
AY4
AY2
AW2
BP4
AW3
AV2
BN3
AV4
AU2
AT 2
AR2
BG2
BF2
BD2
BC2
U26
6
5
4
3
2
1
0
6
5
4
3
2
1
0
9
8
7
6
5
4
9
8
7
6
5
4
3
2
1
0
9
3
2
1
0
8
7
6
5
4
9
8
7
6
5
3
2
1
0
4
3
2
1
0
7
5
6
3
4
2
0
1
7
6
5
4
3
2
1
0
31
30
29
27
28
26
25
24
22
23
21
20
19
18
17
16
15
14
13
12
11
10
9
8
7
6
5
4
2
3
1
0
31
30
29
28
27
26
25
24
23
22
21
20
18
19
17
16
14
15
13
12
11
10
9
8
7
6
5
4
2
3
1
0
CAD NOTE:
7/40
TEST39G
MG1_CLK_L
MG1_CLK_H
MG0_CLK_L
MG0_CLK_H
MGA_PAR
MGB_DQS_H9
MGB_PAR
MGA_CHECK1
MGA_DATA0
MGA_DATA10
MGA_DATA21
MGB_DATA0
MGB_DQS_H4
MGB_DQS_L8
MGA_CHECK0
MGA_DATA20
MGA_DATA31
MGA_DQS_H9
MGB_DQS_H3
MGB_DQS_L7
MGA0_CS_L1
MGA1_CS_L1
MGA_DATA30
MGA_DQS_H8
MGB_DATA19
MGB_DQS_H2
MGB_DQS_L6
MGA0_CS_L0
MGA1_CS_L0
MGA_DQS_H7
MGB_DATA18
MGB_DATA29
MGB_DQS_H1
MGB_DQS_L5
MGA_DQS_H6
MGB_DATA17
MGB_DATA28
MGB_DQS_H0
MGB_DQS_L4
MGA_DQS_H5
MGA_DQS_L9
MGB0_RSP_L
MGB1_RSP_L
MGB_CHECK7
MGB_DATA16
MGB_DATA27
MGB_DQS_L3
MGA_DQS_H4
MGA_DQS_L8
MGB_CA6
MGB_CHECK6
MGB_DATA15
MGB_DATA26
MGB_DQS_L2
MGA_CA6
MGA_DQS_H3
MGA_DQS_L7
MGB_CA5
MGB_CHECK5
MGB_DATA14
MGB_DATA25
MGB_DQS_L1
MGA_CA5
MGA_DATA9
MGA_DATA19
MGA_DQS_H2
MGA_DQS_L6
MGB_CA4
MGB_CHECK4
MGB_DATA9
MGB_DATA13
MGB_DATA24
MGB_DQS_L0
MGA_CA4
MGA_DATA8
MGA_DATA18
MGA_DATA29
MGA_DQS_H1
MGA_DQS_L5
MGB_CA3
MGB_CHECK3
MGB_DATA8
MGB_DATA12
MGB_DATA23
MGA_CA3
MGA_DATA7
MGA_DATA17
MGA_DATA28
MGA_DQS_H0
MGA_DQS_L4
MGB_CA2
MGB_CHECK2
MGB_DATA7
MGB_DATA11
MGB_DATA22
MGA0_RSP_L
MGA1_RSP_L
MGA_CA2
MGA_CHECK7
MGA_DATA6
MGA_DATA16
MGA_DATA27
MGA_DQS_L3
MGB_CA1
MGB_CHECK1
MGB_DATA6
MGB_DATA10
MGB_DATA21
MGA_CA1
MGA_CHECK6
MGA_DATA5
MGA_DATA15
MGA_DATA26
MGA_DQS_L2
MGB_CA0
MGB_CHECK0
MGB_DATA5
MGB_DATA20
MGB_DATA31
MGA_CA0
MGA_CHECK5
MGA_DATA4
MGA_DATA14
MGA_DATA25
MGA_DQS_L1
MGB0_CS_L1
MGB1_CS_L1
MGB_DATA4
MGB_DATA30
MGB_DQS_H8
MGA_CHECK4
MGA_DATA3
MGA_DATA13
MGA_DATA24
MGA_DQS_L0
MGB0_CS_L0
MGB1_CS_L0
MGB_DATA3
MGB_DQS_H7
MGA_CHECK3
MGA_DATA2
MGA_DATA12
MGA_DATA23
MGB_DATA2
MGB_DQS_H6
MGA_CHECK2
MGA_DATA1
MGA_DATA11
MGA_DATA22
MGB_DATA1
MGB_DQS_H5
MGB_DQS_L9
MG_RESET_L
MG_ALERT_L
1
SHEETDATE
23
7 3 2 16 5 4
E
A
B
C
E
D
C
B
A
7 6 5 4
D
DEPARTMENT
SIZE
PROJECT DOCUMENT NUMBER REV
REVIEWER
DESIGNER
IN
OUT
OUT
IN
OUT
OUT
IN
OUT
OUT
OUT
OUT
OUT
OUT
OUT
BI
BI
BI
BI
BI
BI
BI
BI
C



Thu Aug 24 14:08:43 2023<NAME_2>
<NAME_1>
MB FABCGTI V02
44 OF 365
105
105
105
105
105
105
105
105
105
105
105
105
105
105
105
105
105
105
105
105
105
105
15 M_H_CP U1_A LE RT_R_NM_H_CP U1_A LE RT_N 1%
0402LF
S O CK E T6096_13568-001
IO
TP _M_H_CP U1_S A _TE S T39H
M_H_CP U1_S A _CA <6:0>
M_H_CP U1_S B _CA <6:0>
M_H_CP U1_CLK _DN<0>
M_H_CP U1_CLK _DP <0>
M_H_CP U1_S A _CS _N<0>
M_H_CP U1_S A _CS _N<1>
M_H_CP U1_S A _RS P <0>
M_H_CP U1_S A _P A R
M_H_CP U1_S B _CS _N<1>
M_H_CP U1_S B _CS _N<0>
M_H_CP U1_S B _RS P <0>
M_H_CP U1_S B _P A R
M_H_CP U1_RE S E T_N
M_H_CP U1_S A _DQ S _DP <9:0>
M_H_CP U1_S B _DQ S _DP <9:0>
M_H_CP U1_S B _DQ S _DN<9:0>
M_H_CP U1_S A _DQ S _DN<9:0>
M_H_CP U1_S B _CB <7:0>
M_H_CP U1_S A _CB <7:0>
M_H_CP U1_S A _DQ <31:0>
M_H_CP U1_S B _DQ <31:0>
CPU1 DDR CHH
R1985 PLACE CLOSE TO CPU < 25MM
SMLF
21R507
BF14
BL14
BW12
DC14
CU14
CL14
CE14
BW14
DC12
CU12
CL12
CE12
BV13
DD14
CV14
CM 14
CF14
BY14
DB13
CT 13
CK13
CD13
DF14
DE12
DE14
DD13
DB14
DA12
DA14
CY13
CY14
CW12
CW14
CV13
CT 14
CR12
CR14
CP13
CP14
CN12
CN14
CM 13
CK14
CJ12
CJ14
CH13
CH14
CG12
CG14
CF13
CD14
CC12
CC14
CB13
BV14
BU12
BU14
BT 13
CB14
CA12
CA14
BY13
BK13
BK14
BJ14
BJ12
BH13
BH14
BG14
BR12
BM 13
BL12
BP13
BN12
BM 14
BC14
AM 14
AF14
Y14
P14
H14
AM 13
AF13
Y13
P13
H13
AN14
AG14
AA14
R14
J14
AL12
AE12
W12
N12
G12
AJ14
AH13
AH14
AG12
AE14
AD13
AD14
AC12
AC14
AB13
AB14
AA12
W14
V13
V14
U12
U14
T 13
T 14
R12
N14
M 13
M 14
L12
L14
K13
K14
J12
G14
F13
F14
E12
AR14
AP13
AP14
AN12
AL14
AK13
AK14
AJ12
BB14
BB13
BA12
BA14
AY14
AY13
AW12
BP14
AW14
AV13
BN14
AV14
AU12
AU14
AT 14
BG12
BF13
BD13
BC12
U26
6
4
5
3
1
2
0
6
4
5
3
2
1
0
9
8
9
8
7
6
5
4
3
7
6
5
2
4
3
1
0
9
8
2
1
0
9
8
7
6
5
4
3
7
6
5
4
3
0
1
2
2
1
0
7
4
6
5
3
2
1
6
0
7
4
5
3
2
0
1
30
29
28
31
27
24
25
26
22
23
20
19
21
18
15
16
17
12
13
14
11
10
9
6
8
7
5
4
3
1
2
31
0
30
28
29
26
27
25
24
22
23
21
19
20
17
18
15
16
13
14
11
12
10
8
6
7
9
5
4
3
1
2
0
CAD NOTE:
8/40
TEST39H
MH1_CLK_L
MH1_CLK_H
MH0_CLK_L
MH0_CLK_H
MHB_PAR
MHA_PAR
MHB_DQS_H9
MHA_CHECK5
MHA_DATA14
MHA_DATA25
MHA_DQS_L1
MHB0_CS_L1
MHB1_CS_L0
MHB_DATA30
MHB_DQS_H8
MHA_CHECK4
MHA_DATA13
MHA_DATA24
MHA_DQS_L0
MHB0_CS_L0
MHB_DQS_H7
MHA_CHECK3
MHA_DATA9
MHA_DATA12
MHA_DATA23
MHB_DATA9
MHB_DQS_H6
MHA_CHECK2
MHA_DATA8
MHA_DATA11
MHA_DATA22
MHB_DATA8
MHB_DQS_H5
MHB_DQS_L9
MHA_CHECK1
MHA_DATA7
MHA_DATA10
MHA_DATA21
MHB_DATA7
MHB_DQS_H4
MHB_DQS_L8
MHA1_CS_L1
MHA_CHECK0
MHA_DATA6
MHA_DATA20
MHA_DATA31
MHA_DQS_H9
MHB_DATA6
MHB_DQS_H3
MHB_DQS_L7
MHA0_CS_L1
MHA1_CS_L0
MHA_DATA5
MHA_DATA30
MHA_DQS_H8
MHB_DATA5
MHB_DATA19
MHB_DQS_H2
MHB_DQS_L6
MHA0_CS_L0
MHA_DATA4
MHA_DQS_H7
MHB_CA6
MHB_DATA4
MHB_DATA18
MHB_DATA29
MHB_DQS_H1
MHB_DQS_L5
MHA_CA6
MHA_DATA3
MHA_DQS_H6
MHB1_RSP_L
MHB_CA5
MHB_DATA3
MHB_DATA17
MHB_DATA28
MHB_DQS_H0
MHB_DQS_L4
MHA_CA5
MHA_DATA2
MHA_DQS_H5
MHA_DQS_L9
MHB0_RSP_L
MHB_CA4
MHB_CHECK7
MHB_DATA2
MHB_DATA16
MHB_DATA27
MHB_DQS_L3
MHA_CA4
MHA_DATA1
MHA_DQS_H4
MHA_DQS_L8
MHB_CA3
MHB_CHECK6
MHB_DATA1
MHB_DATA15
MHB_DATA26
MHB_DQS_L2
MHA_CA3
MHA_DATA0
MHA_DQS_H3
MHA_DQS_L7
MHB_CA2
MHB_CHECK5
MHB_DATA0
MHB_DATA14
MHB_DATA25
MHB_DQS_L1
MHA_CA2
MHA_DATA19
MHA_DQS_H2
MHA_DQS_L6
MHB_CA1
MHB_CHECK4
MHB_DATA13
MHB_DATA24
MHB_DQS_L0
MHA_CA1
MHA_DATA18
MHA_DATA29
MHA_DQS_H1
MHA_DQS_L5
MHB_CA0
MHB_CHECK3
MHB_DATA12
MHB_DATA23
MHA1_RSP_L
MHA_CA0
MHA_DATA17
MHA_DATA28
MHA_DQS_H0
MHA_DQS_L4
MHB_CHECK2
MHB_DATA11
MHB_DATA22
MHA0_RSP_L
MHA_CHECK7
MHA_DATA16
MHA_DATA27
MHA_DQS_L3
MHB_CHECK1
MHB_DATA10
MHB_DATA21
MHA_CHECK6
MHA_DATA15
MHA_DATA26
MHA_DQS_L2
MHB1_CS_L1
MHB_CHECK0
MHB_DATA20
MHB_DATA31
MH_RESET_L
MH_ALERT_L
1
SHEETDATE
23
7 3 2 16 5 4
E
A
B
C
E
D
C
B
A
7 6 5 4
D
DEPARTMENT
SIZE
PROJECT DOCUMENT NUMBER REV
REVIEWER
DESIGNER
IN
OUT
OUT
IN
OUT
OUT
OUT
IN
OUT
OUT
OUT
OUT
OUT
OUT
BI
BI
BI
BI
BI
BI
BI
BI
C



Thu Aug 24 14:08:43 2023<NAME_2>
<NAME_1>
MB FABCGTI V02
45 OF 365
106
106
106
106
106
106
106
106
106
106
106
106
106
106
106
106
106
106
106
106
106
106
15 M_I_CP U1_A LE RT_R_NM_I_CP U1_A LE RT_N 1%
0402LF
S O CK E T6096_13568-001
IO
TP _M_I_CP U1_S A _TE S T39I
M_I_CP U1_S A _CA <6:0>
M_I_CP U1_S B _CA <6:0>
M_I_CP U1_CLK _DP <0>
M_I_CP U1_CLK _DN<0>
M_I_CP U1_S A _CS _N<1>
M_I_CP U1_S A _RS P <0>
M_I_CP U1_S A _CS _N<0>
M_I_CP U1_S A _P A R
M_I_CP U1_S B _CS _N<0>
M_I_CP U1_S B _CS _N<1>
M_I_CP U1_S B _RS P <0>
M_I_CP U1_S B _P A R
M_I_CP U1_RE S E T_N
M_I_CP U1_S A _DQ S _DP <9:0>
M_I_CP U1_S B _DQ S _DP <9:0>
M_I_CP U1_S B _DQ S _DN<9:0>
M_I_CP U1_S A _DQ S _DN<9:0>
M_I_CP U1_S B _CB <7:0>
M_I_CP U1_S A _CB <7:0>
M_I_CP U1_S A _DQ <31:0>
M_I_CP U1_S B _DQ <31:0>
CPU1 DDR CHI
R1984 PLACE CLOSE TO CPU < 25MM
SMLF
21R508
BF21
BL21
BW19
DC21
CU21
CL21
CE21
BW21
DC19
CU19
CL19
CE19
BV20
DD21
CV21
CM 21
CF21
BY21
DB20
CT 20
CK20
CD20
DF21
DE19
DE21
DD20
DB21
DA19
DA21
CY20
CY21
CW19
CW21
CV20
CT 21
CR19
CR21
CP20
CP21
CN19
CN21
CM 20
CK21
CJ19
CJ21
CH20
CH21
CG19
CG21
CF20
CD21
CC19
CC21
CB20
BV21
BU19
BU21
BT 20
CB21
CA19
CA21
BY20
BK20
BK21
BJ21
BJ19
BH20
BH21
BG21
BR19
BM 20
BL19
BP20
BN19
BM 21
BC21
AM 21
AF21
Y21
P21
H21
AM 20
AF20
Y20
P20
H20
AN21
AG21
AA21
R21
J21
AL19
AE19
W19
N19
G19
AJ21
AH20
AH21
AG19
AE21
AD20
AD21
AC19
AC21
AB20
AB21
AA19
W21
V20
V21
U19
U21
T 20
T 21
R19
N21
M 20
M 21
L19
L21
K20
K21
J19
G21
F20
F21
E19
AR21
AP20
AP21
AN19
AL21
AK20
AK21
AJ19
BB21
BB20
BA19
BA21
AY21
AY20
AW19
BP21
AW21
AV20
BN21
AV21
AU19
AU21
AT 21
BG19
BF20
BD20
BC19
U26
6
5
4
3
2
6
5
1
0
4
3
2
0
1
8
9
9
7
6
5
3
4
1
2
0
9
8
8
7
6
4
3
5
2
1
9
0
6
7
4
3
5
1
2
0
8
7
6
4
5
3
2
1
0
6
7
5
4
3
1
2
7
0
4
5
6
2
3
1
0
31
29
30
27
28
26
25
24
22
20
23
21
19
18
17
16
14
15
13
12
11
10
9
8
7
6
5
4
3
2
1
0
31
30
29
27
28
25
24
26
23
21
22
20
18
19
17
16
15
14
11
12
13
9
10
7
8
5
6
4
2
3
0
1
CAD NOTE:
9/40
TEST39I
MIA_DATA5
MIA_DATA17
MIA_DATA28
MIA_DQS_H0
MIA_DQS_L4
MIB_CHECK2
MIB_DATA5
MIB_DATA11
MIB_DATA22
MI_ALERT_L
MIA0_RSP_L
MIA1_RSP_L
MIA_CHECK7
MIA_DATA4
MIA_DATA16
MIA_DATA27
MIA_DQS_L3
MIB_CHECK1
MIB_DATA4
MIB_DATA10
MIB_DATA21
MIB_PAR
MIA_CHECK6
MIA_DATA3
MIA_DATA15
MIA_DATA26
MIA_DQS_L2
MIA_PAR
MIB1_CS_L1
MIB_CHECK0
MIB_DATA3
MIB_DATA20
MIB_DATA31
MIB_DQS_H9
MIA_CHECK5
MIA_DATA2
MIA_DATA14
MIA_DATA25
MIA_DQS_L1
MIB0_CS_L1
MIB1_CS_L0
MIB_DATA2
MIB_DATA30
MIB_DQS_H8
MIA_CHECK4
MIA_DATA1
MIA_DATA13
MIA_DATA24
MIA_DQS_L0
MIB0_CS_L0
MIB_DATA1
MIB_DQS_H7
MIA_CHECK3
MIA_DATA0
MIA_DATA12
MIA_DATA23
MIB_DATA0
MIB_DQS_H6
MI_RESET_L
MI0_CLK_L
MI1_CLK_L
MIA_CHECK2
MIA_DATA11
MIA_DATA22
MIB_DQS_H5
MIB_DQS_L9
MIA_CHECK1
MIA_DATA10
MIA_DATA21
MIB_DQS_H4
MIB_DQS_L8
MIA_CHECK0
MIA_DATA20
MIA_DATA31
MIA_DQS_H9
MIB_CA6
MIB_DQS_H3
MIB_DQS_L7
MIA0_CS_L1
MIA1_CS_L1
MIA_CA6
MIA_DATA30
MIA_DQS_H8
MIB_CA5
MIB_DATA19
MIB_DQS_H2
MIB_DQS_L6
MI0_CLK_H
MI1_CLK_H
MIA0_CS_L0
MIA1_CS_L0
MIA_CA5
MIA_DQS_H7
MIB_CA4
MIB_DATA18
MIB_DATA29
MIB_DQS_H1
MIB_DQS_L5
MIA_CA4
MIA_DQS_H6
MIB1_RSP_L
MIB_CA3
MIB_DATA17
MIB_DATA28
MIB_DQS_H0
MIB_DQS_L4
MIA_CA3
MIA_DQS_H5
MIA_DQS_L9
MIB0_RSP_L
MIB_CA2
MIB_CHECK7
MIB_DATA16
MIB_DATA27
MIB_DQS_L3
MIA_CA2
MIA_DATA9
MIA_DQS_H4
MIA_DQS_L8
MIB_CA1
MIB_CHECK6
MIB_DATA9
MIB_DATA15
MIB_DATA26
MIB_DQS_L2
MIA_CA1
MIA_DATA8
MIA_DQS_H3
MIA_DQS_L7
MIB_CA0
MIB_CHECK5
MIB_DATA8
MIB_DATA14
MIB_DATA25
MIB_DQS_L1
MIA_CA0
MIA_DATA7
MIA_DATA19
MIA_DQS_H2
MIA_DQS_L6
MIB_CHECK4
MIB_DATA7
MIB_DATA13
MIB_DATA24
MIB_DQS_L0
MIA_DATA6
MIA_DATA18
MIA_DATA29
MIA_DQS_H1
MIA_DQS_L5
MIB_CHECK3
MIB_DATA6
MIB_DATA12
MIB_DATA23
1
SHEETDATE
23
7 3 2 16 5 4
E
A
B
C
E
D
C
B
A
7 6 5 4
D
DEPARTMENT
SIZE
PROJECT DOCUMENT NUMBER REV
REVIEWER
DESIGNER
OUT
IN
OUT
IN
OUT
OUT
OUT
OUT
IN
OUT
OUT
OUT
OUT
OUT
BI
BI
BI
BI
BI
BI
BI
BI
C



Thu Aug 24 14:08:43 2023<NAME_2>
<NAME_1>
MB FABCGTI V02
46 OF 365
107
107
107
107
107
107
107
107
107
107
107
107
107
107
107
107
107
107
107
107
107
107
15 M_J_CP U1_A LE RT_R_NM_J_CP U1_A LE RT_N 1%
0402LF
S O CK E T6096_13568-001
IO
TP _M_J_CP U1_S A _TE S T39J
M_J_CP U1_S A _CA <6:0>
M_J_CP U1_S B _CA <6:0>
M_J_CP U1_CLK _DP <0>
M_J_CP U1_CLK _DN<0>
M_J_CP U1_S A _CS _N<0>
M_J_CP U1_S A _CS _N<1>
M_J_CP U1_S A _RS P <0>
M_J_CP U1_S B _CS _N<0>
M_J_CP U1_S B _CS _N<1>
M_J_CP U1_S A _P A R
M_J_CP U1_S B _P A R
M_J_CP U1_S B _RS P <0>
M_J_CP U1_RE S E T_N
M_J_CP U1_S A _DQ S _DP <9:0>
M_J_CP U1_S B _DQ S _DP <9:0>
M_J_CP U1_S B _DQ S _DN<9:0>
M_J_CP U1_S A _DQ S _DN<9:0>
M_J_CP U1_S B _CB <7:0>
M_J_CP U1_S A _CB <7:0>
M_J_CP U1_S A _DQ <31:0>
M_J_CP U1_S B _DQ <31:0>
CPU1 DDR CHJ
R1983 PLACE CLOSE TO CPU < 25MM
SMLF
21R509
BF18
BL17
BW16
DC17
CU17
CL17
CE17
BW17
DC16
CU16
CL16
CE16
BV16
DD18
CV18
CM 18
CF18
BY18
DB16
CT 16
CK16
CD16
DF16
DE16
DE17
DD16
DB18
DA16
DA17
CY16
CY18
CW16
CW17
CV16
CT 18
CR16
CR17
CP16
CP18
CN16
CN17
CM 16
CK18
CJ16
CJ17
CH16
CH18
CG16
CG17
CF16
CD18
CC16
CC17
CB16
BV18
BU16
BU17
BT 16
CB18
CA16
CA17
BY16
BK16
BK18
BJ17
BJ16
BH16
BH18
BG17
BR16
BM 16
BL16
BP16
BN16
BM 18
BC17
AM 18
AF18
Y18
P18
H18
AM 16
AF16
Y16
P16
H16
AN17
AG17
AA17
R17
J17
AL16
AE16
W16
N16
G16
AJ17
AH16
AH18
AG16
AE17
AD16
AD18
AC16
AC17
AB16
AB18
AA16
W17
V16
V18
U16
U17
T 16
T 18
R16
N17
M 16
M 18
L16
L17
K16
K18
J16
G17
F16
F18
E16
AR17
AP16
AP18
AN16
AL17
AK16
AK18
AJ16
BB18
BB16
BA16
BA17
AY18
AY16
AW16
BP18
AW17
AV16
BN17
AV18
AU16
AU17
AT 18
BG16
BF16
BD16
BC16
U26
6
5
4
3
1
2
0
6
5
4
2
3
1
0
9
8
9
8
6
7
5
4
2
3
1
0
8
9
7
6
5
4
3
2
1
0
8
9
7
5
6
4
3
1
2
0
7
6
5
4
3
2
1
0
7
6
5
4
2
3
0
1
6
7
5
4
3
2
1
0
31
29
28
30
27
26
24
25
23
22
19
20
21
18
17
16
15
14
13
12
10
11
9
8
6
7
5
3
4
1
2
31
0
30
29
28
27
26
24
25
22
23
21
20
19
18
17
16
15
14
13
12
11
10
8
9
7
6
5
3
4
2
1
0
CAD NOTE:
10/40
TEST39J
MJB_DATA7
MJB_DATA6
MJB_DATA5
MJB_DQS_H5
MJB_DQS_L4
MJB_DQS_L0
MJA_DATA31
MJB_DATA0
MJB_DATA3
MJB_DATA4
MJA_DQS_H4
MJA_DQS_H8
MJA_DQS_L4
MJA_DQS_L5
MJA_DQS_L7
MJA_DATA22
MJA_CA5
MJA_CA6
MJ0_CLK_H
MJ0_CLK_L
MJ1_CLK_H
MJ1_CLK_L
MJA0_CS_L0
MJA0_CS_L1
MJA0_RSP_L
MJA1_CS_L0
MJA1_CS_L1
MJA1_RSP_L
MJA_CA0
MJA_CA1
MJA_CA2
MJA_CA3
MJA_CA4
MJA_CHECK0
MJA_CHECK1
MJA_CHECK2
MJA_CHECK3
MJA_CHECK4
MJA_CHECK5
MJA_CHECK6
MJA_CHECK7
MJA_DATA0
MJA_DATA1
MJA_DATA2
MJA_DATA3
MJA_DATA4
MJA_DATA5
MJA_DATA6
MJA_DATA7
MJA_DATA8
MJA_DATA9
MJA_DATA10
MJA_DATA11
MJA_DATA12
MJA_DATA13
MJA_DATA14
MJA_DATA15
MJA_DATA16
MJA_DATA17
MJA_DATA18
MJA_DATA19
MJA_DATA20
MJA_DATA21
MJA_DATA23
MJA_DATA24
MJA_DATA25
MJA_DATA26
MJA_DATA27
MJA_DATA28
MJA_DATA29
MJA_DATA30
MJA_DQS_H0
MJA_DQS_H1
MJA_DQS_H2
MJA_DQS_H3
MJA_DQS_H5
MJA_DQS_H6
MJA_DQS_H7
MJA_DQS_H9
MJA_DQS_L0
MJA_DQS_L1
MJA_DQS_L2
MJA_DQS_L3
MJA_DQS_L6
MJA_DQS_L8
MJA_DQS_L9
MJA_PAR
MJB0_CS_L0
MJB0_CS_L1
MJB0_RSP_L
MJB1_CS_L0
MJB1_CS_L1
MJB1_RSP_L
MJB_CA0
MJB_CA1
MJB_CA2
MJB_CA3
MJB_CA4
MJB_CA5
MJB_CA6
MJB_CHECK0
MJB_CHECK1
MJB_CHECK2
MJB_CHECK3
MJB_CHECK4
MJB_CHECK5
MJB_CHECK6
MJB_CHECK7
MJB_DATA1
MJB_DATA2
MJB_DATA8
MJB_DATA9
MJB_DATA10
MJB_DATA11
MJB_DATA12
MJB_DATA13
MJB_DATA14
MJB_DATA15
MJB_DATA16
MJB_DATA17
MJB_DATA18
MJB_DATA19
MJB_DATA20
MJB_DATA21
MJB_DATA22
MJB_DATA23
MJB_DATA24
MJB_DATA25
MJB_DATA26
MJB_DATA27
MJB_DATA28
MJB_DATA29
MJB_DATA30
MJB_DATA31
MJB_DQS_H0
MJB_DQS_H1
MJB_DQS_H2
MJB_DQS_H3
MJB_DQS_H4
MJB_DQS_H6
MJB_DQS_H7
MJB_DQS_H8
MJB_DQS_H9
MJB_DQS_L1
MJB_DQS_L2
MJB_DQS_L3
MJB_DQS_L5
MJB_DQS_L6
MJB_DQS_L7
MJB_DQS_L8
MJB_DQS_L9
MJB_PAR
MJ_ALERT_L
MJ_RESET_L
1
SHEETDATE
23
7 3 2 16 5 4
E
A
B
C
E
D
C
B
A
7 6 5 4
D
DEPARTMENT
SIZE
PROJECT DOCUMENT NUMBER REV
REVIEWER
DESIGNER
IN
OUT
IN
OUT
OUT
OUT
OUT
IN
OUT
OUT
OUT
OUT
OUT
OUT
BI
BI
BI
BI
BI
BI
BI
BI
C



Thu Aug 24 14:08:43 2023<NAME_2>
<NAME_1>
MB FABCGTI V02
47 OF 365
108
108
108
108
108
108
108
108
108
108
108
108
108
108
108
108
108
108
108
108
108
108
15 M_K _CP U1_A LE RT_R_NM_K _CP U1_A LE RT_N 1%
0402LF
S O CK E T6096_13568-001
IO
TP _M_K _CP U1_S A _TE S T39K
M_K _CP U1_S A _CA <6:0>
M_K _CP U1_S B _CA <6:0>
M_K _CP U1_CLK _DN<0>
M_K _CP U1_CLK _DP <0>
M_K _CP U1_S A _CS _N<0>
M_K _CP U1_S A _CS _N<1>
M_K _CP U1_S A _RS P <0>
M_K _CP U1_S A _P A R
M_K _CP U1_S B _CS _N<0>
M_K _CP U1_S B _CS _N<1>
M_K _CP U1_S B _RS P <0>
M_K _CP U1_S B _P A R
M_K _CP U1_RE S E T_N
M_K _CP U1_S A _DQ S _DP <9:0>
M_K _CP U1_S B _DQ S _DP <9:0>
M_K _CP U1_S B _DQ S _DN<9:0>
M_K _CP U1_S A _DQ S _DN<9:0>
M_K _CP U1_S B _CB <7:0>
M_K _CP U1_S A _CB <7:0>
M_K _CP U1_S A _DQ <31:0>
M_K _CP U1_S B _DQ <31:0>
CPU1 DDR CHK
R1956 PLACE CLOSE TO CPU < 25MM
SMLF
21R510
BF7
BL7
BW5
DC7
CU7
CL7
CE7
BW7
DC5
CU5
CL5
CE5
BV6
DD7
CV7
CM 7
CF7
BY7
DB6
CT 6
CK6
CD6
DF7
DE5
DE7
DD6
DB7
DA5
DA7
CY6
CY7
CW5
CW7
CV6
CT 7
CR5
CR7
CP6
CP7
CN5
CN7
CM 6
CK7
CJ5
CJ7
CH6
CH7
CG5
CG7
CF6
CD7
CC5
CC7
CB6
BV7
BU5
BU7
BT 6
CB7
CA5
CA7
BY6
BK6
BK7
BJ7
BJ5
BH6
BH7
BG7
BR5
BM 6
BL5
BP6
BN5
BM 7
BC7
AM 7
AF7
Y7
P7
H7
AM 6
AF6
Y6
P6
H6
AN7
AG7
AA7
R7
J7
AL5
AE5
W5
N5
G5
AJ7
AH6
AH7
AG5
AE7
AD6
AD7
AC5
AC7
AB6
AB7
AA5
W7
V6
V7
U5
U7
T 6
T 7
R5
N7
M 6
M 7
L5
L7
K6
K7
J5
G7
F6
F7
E5
AR7
AP6
AP7
AN5
AL7
AK6
AK7
AJ5
BB7
BB6
BA5
BA7
AY7
AY6
AW5
BP7
AW7
AV6
BN7
AV7
AU5
AU7
AT 7
BG5
BF6
BD6
BC5
U26
6
5
4
3
1
2
5
6
4
0
2
1
0
3
9
8
8
9
7
5
6
4
3
2
1
0
8
9
7
5
6
4
3
2
1
0
9
8
7
6
5
4
3
2
0
1
7
6
4
5
3
2
1
0
7
6
4
5
3
2
0
1
7
6
5
4
3
2
1
0
31
30
28
29
27
26
25
24
23
22
20
21
19
18
17
16
15
13
14
12
11
10
8
9
7
6
4
5
3
2
1
0
31
30
29
28
27
26
25
24
23
22
21
20
19
18
16
15
17
14
13
12
11
10
8
9
7
6
4
5
3
2
1
0
CAD NOTE:
36/40
TEST39K
MKA0_CS_L0
MKA_CA0
MKA_DQS_H7
MKB_DATA9
MKB_DATA18
MKB_DATA29
MKB_DQS_H1
MKB_DQS_L5
MKA_DATA9
MKA_DQS_H6
MKB1_RSP_L
MKB_DATA8
MKB_DATA17
MKB_DATA28
MKB_DQS_H0
MKB_DQS_L4
MKA_DATA8
MKA_DQS_H5
MKA_DQS_L9
MKB0_RSP_L
MKB_CHECK7
MKB_DATA7
MKB_DATA16
MKB_DATA27
MKB_DQS_L3
MKA_DATA7
MKA_DQS_H4
MKA_DQS_L8
MKB_CHECK6
MKB_DATA6
MKB_DATA15
MKB_DATA26
MKB_DQS_L2
MKB_PAR
MKA_DATA6MKA_DQS_H3
MKA_DQS_L7
MKA_PAR
MKB_CHECK5
MKB_DATA5
MKB_DATA14
MKB_DATA25
MKB_DQS_L1
MKA_DATA5
MKA_DATA19
MKA_DQS_H2
MKA_DQS_L6
MKB_CHECK4
MKB_DATA4
MKB_DATA13
MKB_DATA24
MKB_DQS_L0
MKA_DATA4
MKA_DATA18
MKA_DATA29
MKA_DQS_H1
MKA_DQS_L5
MKB_CHECK3
MKB_DATA3
MKB_DATA12
MKB_DATA23
MKA1_RSP_L
MKA_DATA3
MKA_DATA17
MKA_DATA28
MKA_DQS_H0
MKA_DQS_L4
MKB_CHECK2
MKB_DATA2
MKB_DATA11
MKB_DATA22
MK_ALERT_L
MKA0_RSP_L
MKA_CHECK7
MKA_DATA2
MKA_DATA16
MKA_DATA27
MKA_DQS_L3
MKB_CHECK1
MKB_DATA1
MKB_DATA10
MKB_DATA21
MKA_CHECK6
MKA_DATA1
MKA_DATA15
MKA_DATA26
MKA_DQS_L2
MKB1_CS_L1
MKB_CHECK0
MKB_DATA0
MKB_DATA20
MKB_DATA31
MKB_DQS_H9
MK1_CLK_L
MKA_CHECK5
MKA_DATA0
MKA_DATA14
MKA_DATA25
MKA_DQS_L1
MKB0_CS_L1
MKB1_CS_L0
MKB_CA6
MKB_DATA30
MKB_DQS_H8
MK0_CLK_L
MKA_CA6
MKA_CHECK4
MKA_DATA13
MKA_DATA24
MKA_DQS_L0
MKB0_CS_L0
MKB_CA5
MKB_DQS_H7
MKA_CA5
MKA_CHECK3
MKA_DATA12
MKA_DATA23
MKB_CA4
MKB_DQS_H6
MK_RESET_L
MKA_CA4
MKA_CHECK2
MKA_DATA11
MKA_DATA22
MKB_CA3
MKB_DQS_H5
MKB_DQS_L9
MK1_CLK_H
MKA_CA3
MKA_CHECK1
MKA_DATA10
MKA_DATA21
MKB_CA2
MKB_DQS_H4
MKB_DQS_L8
MK0_CLK_H
MKA1_CS_L1
MKA_CA2
MKA_CHECK0
MKA_DATA20
MKA_DATA31
MKA_DQS_H9
MKB_CA1
MKB_DQS_H3
MKB_DQS_L7
MKA0_CS_L1
MKA1_CS_L0
MKA_CA1
MKA_DATA30
MKA_DQS_H8
MKB_CA0
MKB_DATA19
MKB_DQS_H2
MKB_DQS_L6
1
SHEETDATE
23
7 3 2 16 5 4
E
A
B
C
E
D
C
B
A
7 6 5 4
D
DEPARTMENT
SIZE
PROJECT DOCUMENT NUMBER REV
REVIEWER
DESIGNER
IN
OUT
OUT
IN
OUT
OUT
OUT
IN
OUT
OUT
OUT
OUT
OUT
OUT
BI
BI
BI
BI
BI
BI
BI
BI
C



Thu Aug 24 14:08:44 2023<NAME_2>
<NAME_1>
MB FABCGTI V02
48 OF 365
109
109
109
109
109
109
109
109
109
109
109
109
109
109
109
109
109
109
109
109
109
109
15 M_L_CP U1_A LE RT_R_NM_L_CP U1_A LE RT_N 1%
0402LF
S O CK E T6096_13568-001
IO
TP _M_L_CP U1_S A _TE S T39L
M_L_CP U1_S A _CA <6:0>
M_L_CP U1_S B _CA <6:0>
M_L_CP U1_CLK _DP <0>
M_L_CP U1_CLK _DN<0>
M_L_CP U1_S A _CS _N<0>
M_L_CP U1_S A _CS _N<1>
M_L_CP U1_S A _RS P <0>
M_L_CP U1_S A _P A R
M_L_CP U1_S B _CS _N<1>
M_L_CP U1_S B _CS _N<0>
M_L_CP U1_S B _P A R
M_L_CP U1_S B _RS P <0>
M_L_CP U1_RE S E T_N
M_L_CP U1_S A _DQ S _DP <9:0>
M_L_CP U1_S B _DQ S _DP <9:0>
M_L_CP U1_S B _DQ S _DN<9:0>
M_L_CP U1_S A _DQ S _DN<9:0>
M_L_CP U1_S B _CB <7:0>
M_L_CP U1_S A _CB <7:0>
M_L_CP U1_S A _DQ <31:0>
M_L_CP U1_S B _DQ <31:0>
CPU1 DDR CHL
R1957 PLACE CLOSE TO CPU < 25MM
SMLF
21R511
BF11
BL10
BW9
DC10
CU10
CL10
CE10
BW10
DC9
CU9
CL9
CE9
BV9
DD11
CV11
CM 11
CF11
BY11
DB9
CT 9
CK9
CD9
DF9
DE9
DE10
DD9
DB11
DA9
DA10
CY9
CY11
CW9
CW10
CV9
CT 11
CR9
CR10
CP9
CP11
CN9
CN10
CM 9
CK11
CJ9
CJ10
CH9
CH11
CG9
CG10
CF9
CD11
CC9
CC10
CB9
BV11
BU9
BU10
BT 9
CB11
CA9
CA10
BY9
BK9
BK11
BJ10
BJ9
BH9
BH11
BG10
BR9
BM 9
BL9
BP9
BN9
BM 11
BC10
AM 11
AF11
Y11
P11
H11
AM 9
AF9
Y9
P9
H9
AN10
AG10
AA10
R10
J10
AL9
AE9
W9
N9
G9
AJ10
AH9
AH11
AG9
AE10
AD9
AD11
AC9
AC10
AB9
AB11
AA9
W10
V9
V11
U9
U10
T 9
T 11
R9
N10
M 9
M 11
L9
L10
K9
K11
J9
G10
F9
F11
E9
AR10
AP9
AP11
AN9
AL10
AK9
AK11
AJ9
BB11
BB9
BA9
BA10
AY11
AY9
AW9
BP11
AW10
AV9
BN10
AV11
AU9
AU10
AT 11
BG9
BF9
BD9
BC9
U26
4
5
6
2
3
1
0
4
5
6
2
3
0
1
9
8
9
8
7
5
6
7
6
4
3
5
3
4
2
1
0
2
1
9
8
9
0
7
5
6
8
6
7
4
3
5
4
2
0
1
2
3
1
0
7
5
6
3
4
2
1
0
7
6
5
4
3
2
1
0
31
29
30
28
27
26
24
25
23
22
20
21
19
18
17
15
16
13
14
11
10
12
8
9
6
7
4
5
2
1
3
0
30
31
29
26
27
28
24
25
22
23
21
20
17
18
19
16
14
15
13
12
11
10
8
9
6
7
5
4
1
2
3
0
CAD NOTE:
35/40
TEST39L
MLA_CA1
MLA_CHECK1
MLA_DATA4
MLA_DATA10
MLA_DATA21
MLB_CA0
MLB_DATA3
MLB_DQS_H4
MLB_DQS_L8
MLA_CA0
MLA_CHECK0
MLA_DATA3
MLA_DATA20
MLA_DATA31
MLA_DQS_H9
MLB_DATA2
MLB_DQS_H3
MLB_DQS_L7
MLA1_CS_L1
MLA_DATA2
MLA_DATA30
MLA_DQS_H8
MLB_DATA1
MLB_DATA19
MLB_DQS_H2
MLB_DQS_L6
MLA0_CS_L1
MLA1_CS_L0
MLA_DATA1
MLA_DQS_H7
MLB_DATA0
MLB_DATA18
MLB_DATA29
MLB_DQS_H1
MLB_DQS_L5
ML1_CLK_L
MLA0_CS_L0
MLA_DATA0
MLA_DQS_H6
MLB_DATA17
MLB_DATA28
MLB_DQS_H0
MLB_DQS_L4
MLB_PAR
ML0_CLK_L
MLA_DQS_H5
MLA_DQS_L9
MLA_PAR
MLB1_RSP_L
MLB_CHECK7
MLB_DATA16
MLB_DATA27
MLB_DQS_L3
MLA_DQS_H4
MLA_DQS_L8
MLB0_RSP_L
MLB_CHECK6
MLB_DATA15
MLB_DATA26
MLB_DQS_L2
MLA_DQS_H3
MLA_DQS_L7
MLB_CHECK5
MLB_DATA14
MLB_DATA25
MLB_DQS_L1
ML1_CLK_H
MLA_DATA19
MLA_DQS_H2
MLA_DQS_L6
MLB_CHECK4
MLB_DATA13
MLB_DATA24
MLB_DQS_L0
ML0_CLK_H
MLA_DATA18
MLA_DATA29
MLA_DQS_H1
MLA_DQS_L5
MLB_CHECK3
MLB_DATA12
MLB_DATA23
MLA_DATA17
MLA_DATA28
MLA_DQS_H0
MLA_DQS_L4
MLB_CHECK2
MLB_DATA11
MLB_DATA22
ML_ALERT_L
MLA1_RSP_L
MLA_CHECK7
MLA_DATA16
MLA_DATA27
MLA_DQS_L3
MLB_CA6
MLB_CHECK1
MLB_DATA9
MLB_DATA10
MLB_DATA21
MLA0_RSP_L
MLA_CA6
MLA_CHECK6
MLA_DATA9
MLA_DATA15
MLA_DATA26
MLA_DQS_L2
MLB_CA5
MLB_CHECK0
MLB_DATA8
MLB_DATA20
MLB_DATA31
MLB_DQS_H9
MLA_CA5
MLA_CHECK5
MLA_DATA8
MLA_DATA14
MLA_DATA25
MLA_DQS_L1
MLB1_CS_L1
MLB_CA4
MLB_DATA7
MLB_DATA30
MLB_DQS_H8
MLA_CA4
MLA_CHECK4
MLA_DATA7
MLA_DATA13
MLA_DATA24
MLA_DQS_L0
MLB0_CS_L1
MLB1_CS_L0
MLB_CA3
MLB_DATA6
MLB_DQS_H7
MLA_CA3
MLA_CHECK3
MLA_DATA6
MLA_DATA12
MLA_DATA23
MLB0_CS_L0
MLB_CA2
MLB_DATA5
MLB_DQS_H6
ML_RESET_L
MLA_CA2
MLA_CHECK2
MLA_DATA5
MLA_DATA11
MLA_DATA22
MLB_CA1
MLB_DATA4
MLB_DQS_H5
MLB_DQS_L9
1
SHEETDATE
23
7 3 2 16 5 4
E
A
B
C
E
D
C
B
A
7 6 5 4
D
DEPARTMENT
SIZE
PROJECT DOCUMENT NUMBER REV
REVIEWER
DESIGNER
IN
OUT
IN
OUT
OUT
OUT
OUT
IN
OUT
OUT
OUT
OUT
OUT
OUT
BI
BI
BI
BI
BI
BI
BI
BI
C



LANE REVERSAL
CPU1 G1[15:0] TO OCP SLOT#1
Thu Aug 24 14:08:44 2023<NAME_2>
<NAME_1>
MB FABCGTI V02
49 OF 365
67
67
23
23 23
23
137
137
P 5E _CP U1_G 1_TX _DN<15:0>
P 5E _CP U1_G 1_TX _DP <15:0>
SMLF
CPU1 PCIE G0/G1
IO
S O CK E T6096_13568-001
SMLF
S O CK E T6096_13568-001
G MI_CP U0_G 2_CP U1_G 0_TX _DP <0:15>
G MI_CP U0_G 2_CP U1_G 0_TX _DN<0:15> G MI_CP U1_G 0_CP U0_G 2_TX _DN<0:15>
G MI_CP U1_G 0_CP U0_G 2_TX _DP <0:15>
IO
P 5E _CP U1_G 1_RX _DN<15:0>
P 5E _CP U1_G 1_RX _DP <15:0>
AL52
AJ52
AN52
AL49
AJ49
AN49
AL46
AJ46
AN46
AL43
AJ43
AN43
AK40
AH40
AM 40
AP40
AL53
AJ53
AN53
AL50
AJ50
AN50
AL47
AJ47
AN47
AL44
AJ44
AN44
AK41
AH41
AM 41
AP41
U53
R53
W53
U50
R50
N50
W50
R47
N47
U47
R44
N44
U44
P41
T 41
V41
U52
R52
W52
U49
R49
N49
W49
R46
N46
U46
R43
N43
U43
P40
T 40
V40
U26
AE52
AC52
AG52
AE49
AC49
AG49
AE46
AC46
AG46
AE43
AC43
AA43
AG43
AB40
AD40
AF40
AE53
AC53
AG53
AE50
AC50
AG50
AE47
AC47
AG47
AE44
AC44
AA44
AG44
AB41
AD41
AF41
N53
J53
G53
L53
J50
G50
L50
J47
G47
L47
J44
G44
L44
H41
K41
M 41
N52
J52
G52
L52
J49
G49
L49
J46
G46
L46
J43
G43
L43
H40
K40
M 40
U26
1
8
2
5
4
1
2
0
15
14
13
12
11
10
9
7
6
5
4
3
2
1
0
15
14
13
12
11
10
8
7
6
5
4
3
2
1
0
14
13
12
11
10
9
8
7
6
5
4
3
2
1
0
13
12
10
11
9
8
7
6
5
4
3
2
0
1
15
13
10
9
8
7
5
6
4
3
1
2
0
15
14
13
12
10
11
9
8
7
6
5
4
3
2
0
1
15
14
14
15
12
11
9
0
15
14
13
11
12
10
9
8
7
6
3
3
4
5
6
7
8
9
10
11
12
13
14
15
12/40
G1_RXN7
G1_RXN6
G1_RXN5
G1_RXP7
G1_TXN7
G1_RXN4
G1_RXP6
G1_TXN6
G1_RXN3
G1_RXP5
G1_TXN5
G1_TXP7
G1_RXN2
G1_RXP4
G1_TXN4
G1_TXP6
G1_RXN1
G1_RXP3
G1_TXN3
G1_TXP5
G1_RXN0
G1_RXP2
G1_TXN2
G1_TXP4
G1_RXP1
G1_TXN1
G1_TXP3
G1_RXP0
G1_TXN0
G1_TXP2
G1_TXP1
G1_TXP0
G1_RXN8
G1_RXN9
G1_RXN10
G1_RXN11
G1_RXN12
G1_RXN13
G1_RXN14
G1_RXN15
G1_RXP8
G1_RXP9
G1_RXP10
G1_RXP11
G1_RXP12
G1_RXP13
G1_RXP14
G1_RXP15
G1_TXN8
G1_TXN9
G1_TXN10
G1_TXN11
G1_TXN12
G1_TXN13
G1_TXN14
G1_TXN15
G1_TXP8
G1_TXP9
G1_TXP10
G1_TXP11
G1_TXP12
G1_TXP13
G1_TXP14
G1_TXP15
11/40
G0_TXP15
G0_TXP14
G0_TXP13
G0_TXP12
G0_TXP11
G0_TXP10
G0_TXP9
G0_TXP8
G0_TXP7
G0_TXP6
G0_TXP5
G0_TXP4
G0_TXP3
G0_TXP2
G0_TXP1
G0_TXP0
G0_TXN15
G0_TXN14
G0_TXN13
G0_TXN12
G0_TXN11
G0_TXN10
G0_TXN9
G0_TXN8
G0_TXN7
G0_TXN6
G0_TXN5
G0_TXN4
G0_TXN3
G0_TXN2
G0_TXN1
G0_TXN0
G0_RXP15
G0_RXP14
G0_RXP13
G0_RXP12
G0_RXP11
G0_RXP10
G0_RXP9
G0_RXP8
G0_RXP7
G0_RXP6
G0_RXP5
G0_RXP4
G0_RXP3
G0_RXP2
G0_RXP1
G0_RXP0
G0_RXN15
G0_RXN14
G0_RXN13
G0_RXN12
G0_RXN11
G0_RXN10
G0_RXN9
G0_RXN8
G0_RXN7
G0_RXN6
G0_RXN5
G0_RXN4
G0_RXN3
G0_RXN2
G0_RXN1
G0_RXN0
1
SHEETDATE
23
7 3 2 16 5 4
E
A
B
C
E
D
C
B
A
7 6 5 4
D
DEPARTMENT
SIZE
PROJECT DOCUMENT NUMBER REV
REVIEWER
DESIGNER
OUTIN
IN OUT
IN
IN
OUT
OUT
C



LANE REVERSAL
LANE REVERSAL
Thu Aug 24 14:08:44 2023<NAME_2>
<NAME_1>
MB FABCGTI V02
50 OF 365
22
22
22
22
22
22
22
22
S O CK E T6096_13568-001
S O CK E T6096_13568-001
IO
IOG MI_CP U0_G 0_CP U1_G 2_TX _DP <15:0>
G MI_CP U0_G 0_CP U1_G 2_TX _DN<15:0>
G MI_CP U1_G 3_CP U0_G 1_TX _DP <15:0>
G MI_CP U1_G 3_CP U0_G 1_TX _DN<15:0>
G MI_CP U1_G 2_CP U0_G 0_TX _DP <15:0>
G MI_CP U1_G 2_CP U0_G 0_TX _DN<15:0>
G MI_CP U0_G 1_CP U1_G 3_TX _DP <15:0>
G MI_CP U0_G 1_CP U1_G 3_TX _DN<15:0>
CPU1 PCIE G2/G3
SMLF
SMLF
V35
T 35
P35
U32
N32
R32
U29
N29
R29
W26
N26
R26
U26
W23
R23
U23
V36
T 36
P36
U33
N33
R33
U30
N30
R30
W27
N27
R27
U27
W24
R24
U24
AP36
AM 36
AH36
AK36
AN33
AJ33
AL33
AN30
AJ30
AL30
AN27
AJ27
AL27
AN24
AJ24
AL24
AP35
AM 35
AH35
AK35
AN32
AJ32
AL32
AN29
AJ29
AL29
AN26
AJ26
AL26
AN23
AJ23
AL23
U26
M 35
K35
H35
L32
G32
J32
L29
G29
J29
L26
G26
J26
L23
G23
J23
N23
M 36
K36
H36
L33
G33
J33
L30
G30
J30
L27
G27
J27
L24
G24
J24
N24
AF36
AD36
AB36
AG33
AA33
AC33
AE33
AG30
AC30
AE30
AG27
AC27
AE27
AG24
AC24
AE24
AF35
AD35
AB35
AG32
AA32
AC32
AE32
AG29
AC29
AE29
AG26
AC26
AE26
AG23
AC23
AE23
U26
1
0
2
3
5
4
6
7
8
10
9
11
12
13
14
15
0
2
1
3
4
5
6
7
8
9
10
11
12
13
14
15
1
2
3
0
7
8
5
4
6
13
12
11
9
10
14
15
0
1
3
2
5
4
6
8
7
10
11
9
13
12
14
15
0
1
2
3
4
5
6
7
9
8
10
11
12
14
13
15
0
2
1
3
4
5
7
6
8
9
10
11
12
13
14
15
0
1
3
4
2
5
6
7
9
8
10
11
14
12
13
15
0
1
2
3
5
4
6
7
8
10
9
12
13
11
14
15
14/40
G3_RXN2||SATA22_RXN
G3_TXN9||SATA31_TXN
G3_RXN12||SATA34_RXN
G3_RXN15||SATA37_RXN
G3_TXP5||SATA25_TXP
G3_RXN9||SATA31_RXN
G3_TXP2||SATA22_TXPG3_RXP2||SATA22_RXP
G3_RXP5||SATA25_RXP
G3_RXP14||SATA36_RXP
G3_TXN4||SATA24_TXN
G3_TXN7||SATA27_TXN
G3_TXN10||SATA32_TXN
G3_TXN13||SATA35_TXN
G3_RXP11||SATA33_RXP
G3_TXN1||SATA21_TXN
G3_TXP9||SATA31_TXP
G3_TXP15||SATA37_TXP
G3_RXN1||SATA21_RXN
G3_RXN4||SATA24_RXN
G3_RXN7||SATA27_RXN
G3_TXP12||SATA34_TXP
G3_RXP9||SATA31_RXP
G3_TXP7||SATA27_TXP
G3_TXN8||SATA30_TXN
G3_RXN11||SATA33_RXN
G3_RXN14||SATA36_RXN
G3_TXP1||SATA21_TXP
G3_TXP4||SATA24_TXP
G3_RXP7||SATA27_RXP
G3_RXN8||SATA30_RXN
G3_TXN12||SATA34_TXN
G3_TXN15||SATA37_TXN
G3_RXP1||SATA21_RXP
G3_RXP4||SATA24_RXP
G3_RXP10||SATA32_RXP
G3_RXP13||SATA35_RXP
G3_TXN3||SATA23_TXN
G3_TXN6||SATA26_TXNG3_RXN6||SATA26_RXN
G3_TXN0||SATA20_TXN
G3_TXP8||SATA30_TXP
G3_TXP14||SATA36_TXP
G3_RXN0||SATA20_RXN
G3_RXN3||SATA23_RXN
G3_RXP8||SATA30_RXP
G3_TXP11||SATA33_TXP
G3_RXN13||SATA35_RXN
G3_TXP6||SATA26_TXP
G3_RXN10||SATA32_RXN
G3_TXP0||SATA20_TXP
G3_TXP3||SATA23_TXPG3_RXP3||SATA23_RXP
G3_RXP6||SATA26_RXP
G3_RXP15||SATA37_RXP
G3_TXN5||SATA25_TXN
G3_TXN11||SATA33_TXN
G3_TXN14||SATA36_TXN
G3_RXP0||SATA20_RXP
G3_RXP12||SATA34_RXP
G3_TXN2||SATA22_TXN
G3_RXN5||SATA25_RXN
G3_TXP10||SATA32_TXP
G3_TXP13||SATA35_TXP
13/40
G2_TXP0
G2_RXN7
G2_RXN6
G2_RXN5
G2_RXP7
G2_TXN7
G2_RXN4
G2_RXP6
G2_TXN6
G2_RXN3
G2_RXP5
G2_TXN5
G2_TXP7
G2_RXN2
G2_RXP4
G2_TXN4
G2_TXP6
G2_RXN1
G2_RXP3
G2_TXN3
G2_TXP5
G2_RXN0
G2_RXP2
G2_TXN2
G2_TXP4
G2_RXP1
G2_TXN1
G2_TXP3
G2_RXP0
G2_TXN0
G2_TXP2
G2_TXP1
G2_RXN15
G2_RXP15
G2_RXN13
G2_RXP13
G2_RXN11
G2_RXP11
G2_RXN9
G2_RXP9
G2_RXN14
G2_RXP14
G2_RXN12
G2_RXP12
G2_RXN10
G2_RXP10
G2_RXN8
G2_RXP8
G2_TXN15
G2_TXP15
G2_TXN13
G2_TXP13
G2_TXN11
G2_TXP11
G2_TXN9
G2_TXP9
G2_TXN14
G2_TXP14
G2_TXN12
G2_TXP12
G2_TXN10
G2_TXP10
G2_TXN8
G2_TXP8
1
SHEETDATE
23
7 3 2 16 5 4
E
A
B
C
E
D
C
B
A
7 6 5 4
D
DEPARTMENT
SIZE
PROJECT DOCUMENT NUMBER REV
REVIEWER
DESIGNER
IN OUT
OUTIN
IN
IN
OUT
OUT
C



CPU1 P0[15:0] TO EXAMAX
CPU1 P1[15:0] TO EXAMAX
Thu Aug 24 14:08:44 2023<NAME_2>
<NAME_1>
MB FABCGTI V02
51 OF 365
329
329 66
66
318
318
65
65
P 5E _CP U1_P 1_RX _DP <15:0>
P 5E _CP U1_P 1_RX _DN<15:0> P 5E _CP U1_P 1_TX _DN<15:0>
P 5E _CP U1_P 1_TX _DP <15:0>S O CK E T6096_13568-001
IO
P 5E _CP U1_P 0_RX _DP <15:0>
SMLF
S O CK E T6096_13568-001
CPU1 PCIE P0/P1
SMLF
P 5E _CP U1_P 0_RX _DN<15:0>
P 5E _CP U1_P 0_TX _DP <15:0>
P 5E _CP U1_P 0_TX _DN<15:0>IO
CV41
CY41
DB41
CW44
DC44
DA44
CW47
DC47
DA47
CW50
DC50
DA50
CW53
DC53
DA53
CU53
CV40
CY40
DB40
CW43
DC43
DA43
CW46
DC46
DA46
CW49
DC49
DA49
CW52
DC52
DA52
CU52
CD40
CF40
CH40
CC43
CJ43
CG43
CE43
CC46
CG46
CE46
CC49
CG49
CE49
CC52
CG52
CE52
CD41
CF41
CH41
CC44
CJ44
CG44
CE44
CC47
CG47
CE47
CC50
CG50
CE50
CC53
CG53
CE53
U26
CM 41
CP41
CT 41
CN44
CU44
CR44
CN47
CU47
CR47
CL50
CU50
CR50
CN50
CL53
CR53
CN53
CM 40
CP40
CT 40
CN43
CU43
CR43
CN46
CU46
CR46
CL49
CU49
CR49
CN49
CL52
CR52
CN52
BT 40
BV40
CB40
BY40
BU43
CA43
BW43
BU46
CA46
BW46
BU49
CA49
BW49
BU52
CA52
BW52
BT 41
BV41
CB41
BY41
BU44
CA44
BW44
BU47
CA47
BW47
BU50
CA50
BW50
BU53
CA53
BW53
U26
14
13
12
11
10
9
8
7
6
5
4
3
2
1
15
14
13
12
11
9
8
7
6
5
4
3
1
0
10
2
9
9
1
15
4
0
1
2
4
3
5
6
8
7
0
2
1
3
4
5
6
7
8
9
10
11
13
12
14
15
9
10
11
12
13
14
15
2
0
10
15
14
15
11
12
13
10
7
8
6
1
2
3
4
5
3
4
5
6
7
8
10
11
12
14
15
2
3
4
6
7
8
9
11
13
0
0
1
2
3
5
6
7
8
9
10
11
12
13
14
12
5
13
0
0
1
14
15
16/40
P1_RXN6
P1_RXN5
P1_RXP7
P1_TXN7
P1_RXN4
P1_RXP6
P1_TXN6
P1_RXN3
P1_RXP5
P1_TXN5
P1_TXP7
P1_RXN2
P1_RXP4
P1_TXN4
P1_TXP6
P1_RXN1
P1_RXP3
P1_TXN3
P1_TXP5
P1_RXN0
P1_RXP2
P1_TXN2
P1_TXP4
P1_RXP1
P1_TXN1
P1_TXP3
P1_RXP0
P1_TXN0
P1_TXP2
P1_TXP1
P1_TXP0
P1_RXN7
P1_TXN15
P1_TXP15
P1_TXN14
P1_TXP14
P1_TXN13
P1_TXP13
P1_TXN12
P1_TXP12
P1_TXN11
P1_TXP11
P1_TXN10
P1_TXP10
P1_TXN9
P1_TXP9
P1_TXN8
P1_TXP8
P1_RXN15
P1_RXP15
P1_RXN14
P1_RXP14
P1_RXN13
P1_RXP13
P1_RXN12
P1_RXP12
P1_RXN11
P1_RXP11
P1_RXN10
P1_RXP10
P1_RXN9
P1_RXP9
P1_RXN8
P1_RXP8
15/40
P0_RXP11||SATA13_RXP
P0_TXP12||SATA14_TXP
P0_TXP15||SATA17_TXP
P0_RXN11||SATA13_RXN
P0_RXN14||SATA16_RXN
P0_TXN15||SATA17_TXN
P0_RXP13||SATA15_RXP
P0_TXN9||SATA11_TXN
P0_TXN12||SATA14_TXN
P0_RXP10||SATA12_RXP
P0_RXN9||SATA11_RXN
P0_TXP11||SATA13_TXP
P0_TXP14||SATA16_TXP
P0_RXN10||SATA12_RXN
P0_RXN13||SATA15_RXN
P0_TXP9||SATA11_TXPP0_RXP9||SATA11_RXP
P0_TXN14||SATA16_TXN
P0_RXP12||SATA14_RXP
P0_RXP15||SATA17_RXP
P0_TXN8||SATA10_TXN
P0_TXN11||SATA13_TXN
P0_RXN8||SATA10_RXN
P0_TXP13||SATA15_TXP
P0_TXP10||SATA12_TXP
P0_RXN15||SATA17_RXN
P0_TXP8||SATA10_TXP
P0_RXN12||SATA14_RXN
P0_RXP8||SATA10_RXP
P0_RXP14||SATA16_RXP
P0_TXN10||SATA12_TXN
P0_TXN13||SATA15_TXN
P0_TXP3||SATA03_TXP
P0_TXP6||SATA06_TXP
P0_TXP0||SATA00_TXP
P0_RXP3||SATA03_RXP
P0_RXP6||SATA06_RXP
P0_TXN5||SATA05_TXN
P0_RXP0||SATA00_RXP
P0_TXN2||SATA02_TXNP0_RXN2||SATA02_RXN
P0_RXN5||SATA05_RXN
P0_TXP2||SATA02_TXP
P0_TXP5||SATA05_TXPP0_RXP5||SATA05_RXP
P0_RXP2||SATA02_RXP
P0_TXN1||SATA01_TXN
P0_TXN7||SATA07_TXN
P0_TXN4||SATA04_TXN
P0_RXN7||SATA07_RXN
P0_RXN1||SATA01_RXN
P0_RXN4||SATA04_RXN
P0_TXP7||SATA07_TXP
P0_TXP1||SATA01_TXP
P0_TXP4||SATA04_TXPP0_RXP4||SATA04_RXP
P0_RXP7||SATA07_RXP
P0_TXN6||SATA06_TXN
P0_RXP1||SATA01_RXP
P0_TXN0||SATA00_TXN
P0_TXN3||SATA03_TXNP0_RXN3||SATA03_RXN
P0_RXN6||SATA06_RXN
P0_RXN0||SATA00_RXN
1
SHEETDATE
23
7 3 2 16 5 4
E
A
B
C
E
D
C
B
A
7 6 5 4
D
DEPARTMENT
SIZE
PROJECT DOCUMENT NUMBER REV
REVIEWER
DESIGNER
OUTIN
OUT
IN
IN
IN
OUT
OUT
C



CPU1 P2[15:0] TO EXAMAX
CPU1 P3[15:0] TO EXAMAX
Thu Aug 24 14:08:45 2023<NAME_2>
<NAME_1>
MB FABCGTI V02
52 OF 365
67
67
351
351
66
340
340
66
P 5E _CP U1_P 3_TX _DN<15:0>
P 5E _CP U1_P 3_TX _DP <15:0>
P 5E _CP U1_P 3_RX _DN<15:0>
P 5E _CP U1_P 3_RX _DP <15:0>
P 5E _CP U1_P 2_TX _DP <15:0>
P 5E _CP U1_P 2_RX _DN<15:0>
P 5E _CP U1_P 2_RX _DP <15:0>
CPU1 PCIE P2/P3
SMLF
S O CK E T6096_13568-001
SMLF
S O CK E T6096_13568-001IO
IO
P 5E _CP U1_P 2_TX _DN<15:0>
BW24
CA24
BU24
BW27
CA27
BU27
BW30
CA30
BU30
BW33
CA33
BU33
BY36
CB36
BV36
BT 36
BW23
CA23
BU23
BW26
CA26
BU26
BW29
CA29
BU29
BW32
CA32
BU32
BY35
CB35
BV35
BT 35
CN23
CR23
CL23
CN26
CR26
CU26
CL26
CR29
CU29
CN29
CR32
CU32
CN32
CT 35
CP35
CM 35
CN24
CR24
CL24
CN27
CR27
CU27
CL27
CR30
CU30
CN30
CR33
CU33
CN33
CT 36
CP36
CM 36
U26
CE24
CG24
CC24
CE27
CG27
CC27
CE30
CG30
CC30
CE33
CG33
CJ33
CC33
CH36
CF36
CD36
CE23
CG23
CC23
CE26
CG26
CC26
CE29
CG29
CC29
CE32
CG32
CJ32
CC32
CH35
CF35
CD35
CU23
DA23
DC23
CW23
DA26
DC26
CW26
DA29
DC29
CW29
DA32
DC32
CW32
DB35
CY35
CV35
CU24
DA24
DC24
CW24
DA27
DC27
CW27
DA30
DC30
CW30
DA33
DC33
CW33
DB36
CY36
CV36
U26
4
0
1
1
0
0
14
13
12
11
10
9
8
7
6
5
4
3
2
1
0
15
14
13
12
11
10
9
8
7
6
5
4
3
2
1
3
15
15
14
13
12
11
10
8
9
7
6
5
4
3
2
15
14
10
9
8
13
12
11
7
6
5
4
3
2
15
14
14
15
13
12
11
12
13
11
10
9
10
9
8
8
7
6
6
5
5
3
1
1
0
0
14
13
13
12
11
12
11
10
10
9
8
8
9
6
7
7
5
6
5
3
4
4
2
0
2
1
0
1
15
15
14
3
4
7
2
2
17/40
P2_RXN7
P2_RXN6
P2_RXN5
P2_RXP7
P2_TXN7
P2_RXN4
P2_RXP6
P2_TXN6
P2_RXN3
P2_RXP5
P2_TXN5
P2_TXP7
P2_RXN2
P2_RXP4
P2_TXN4
P2_TXP6
P2_RXN1
P2_RXP3
P2_TXN3
P2_TXP5
P2_RXN0
P2_RXP2
P2_TXN2
P2_TXP4
P2_RXP1
P2_TXN1
P2_TXP3
P2_RXP0
P2_TXN0
P2_TXP2
P2_TXP1
P2_TXP0
P2_TXN15
P2_TXP15
P2_TXN14
P2_TXP14
P2_TXN13
P2_TXP13
P2_TXN12
P2_TXP12
P2_TXN11
P2_TXP11
P2_TXN10
P2_TXP10
P2_TXN9
P2_TXP9
P2_TXN8
P2_TXP8
P2_RXN15
P2_RXP15
P2_RXN14
P2_RXP14
P2_RXN13
P2_RXP13
P2_RXN12
P2_RXP12
P2_RXN11
P2_RXP11
P2_RXN10
P2_RXP10
P2_RXN9
P2_RXP9
P2_RXN8
P2_RXP8
18/40
P3_TXN15
P3_TXP15
P3_TXN14
P3_TXP14
P3_TXN13
P3_TXP13
P3_TXN12
P3_TXP12
P3_TXN11
P3_TXP11
P3_TXN10
P3_TXP10
P3_TXN9
P3_TXP9
P3_TXN8
P3_TXP8
P3_TXN7
P3_TXP7
P3_TXN6
P3_TXP6
P3_TXN5
P3_TXP5
P3_TXN4
P3_TXP4
P3_TXN3
P3_TXP3
P3_TXN2
P3_TXP2
P3_TXN1
P3_TXP1
P3_TXN0
P3_TXP0
P3_RXN15
P3_RXP15
P3_RXN14
P3_RXP14
P3_RXN13
P3_RXP13
P3_RXN12
P3_RXP12
P3_RXN11
P3_RXP11
P3_RXN10
P3_RXP10
P3_RXN9
P3_RXP9
P3_RXN8
P3_RXP8
P3_RXN7
P3_RXP7
P3_RXN6
P3_RXP6
P3_RXN5
P3_RXP5
P3_RXN4
P3_RXP4
P3_RXN3
P3_RXP3
P3_RXN2
P3_RXP2
P3_RXN1
P3_RXP1
P3_RXN0
P3_RXP0
1
SHEETDATE
23
7 3 2 16 5 4
E
A
B
C
E
D
C
B
A
7 6 5 4
D
DEPARTMENT
SIZE
PROJECT DOCUMENT NUMBER REV
REVIEWER
DESIGNER
IN
IN
IN
IN
OUT
OUT
OUT
OUT
C



CPU1 P5[3:2] TO EXAMAX
P3E_CPU1_P5_RX_DP/N<1> PN SWAP
P3E_CPU1_P5_RX_DP/N<0> PN SWAP
CPU1 P4[3:0] TO M.2
Thu Aug 24 14:09:22 2023<NAME_2>
<NAME_1>
MB FABCGTI V02
53 OF 365
122
122
122
122
26
26
122
122
122
122
67
67
26
26
144
144
P 3E _CP U1_P 5_TX _DP <0>
P 3E _CP U1_P 5_TX _DN<0>
P 3E _CP U1_P 5_TX _DN<1>
P 3E _CP U1_P 5_TX _DP <1>
P 3E _CP U1_P 5_RX _DP <1>
P 3E _CP U1_P 5_RX _DN<1>
P 3E _CP U1_P 5_RX _DP <0>
P 3E _CP U1_P 5_RX _DN<0>
W A FL_CP U0_TX 0_CP U1_RX 1_DN
W A FL_CP U0_TX 0_CP U1_RX 1_DP
P 3E _CP U1_P 5_TX _C_DP <0>
P 3E _CP U1_P 5_TX _C_DN<0>
P 3E _CP U1_P 5_TX _C_DP <1>
P 3E _CP U1_P 5_TX _C_DN<1>
D IFF BU S_0.22U F
D IFF BU S_0.22U F
P 3E _CP U1_P 4_TX _DP <3:0>
P 3E _CP U1_P 4_TX _DN<3:0>
W A FL_CP U1_TX 1_CP U0_RX 0_DP
W A FL_CP U1_TX 1_CP U0_RX 0_DN
P 3E _CP U1_P 4_RX _DN<3:0>
P 3E _CP U1_P 4_RX _DP <3:0>
C0201
X 6S
D IFF BU S_0.22U F
20% 6.3V
D IFF BU S_0.22U F
SMLF
S O CK E T6096_13568-001
IO
CPU1 PCIE P4/P5/WAFL
C47
C50
C48
C51
E46
E49
E47
E50
C41
C44
C42
C45
E40
E43
E41
E44
DE44
DE47
DE50
DE53
DE43
DE46
DE49
DE52
DG45
DG48
DG51
DG54
DG44
DG47
DG50
DG53
U26
2 1
2 1
2 1
2 1
2 1
2 1
2 1
2 1
0
1
0
1
2
3
2
3
0
2
1
0
1
3
2
3
C2075
C2076
C2074
C2073
19/40
WAFL_TXP1||P5_TXP1
WAFL_TXN1||P5_TXN1
WAFL_TXP0||P5_TXP0
WAFL_TXN0||P5_TXN0
WAFL_RXP1||P5_RXP1
WAFL_RXN1||P5_RXN1
WAFL_RXP0||P5_RXP0
WAFL_RXN0||P5_RXN0
P4_RXN1
P4_RXN0
P4_RXP1
P4_TXN1
P4_RXP0
P4_TXN0
P4_TXP1
P4_TXP0
P5_TXP3
P5_TXP2
P5_TXN3
P5_TXN2
P5_RXP3
P5_RXP2
P5_RXN3
P5_RXN2
P4_TXP3
P4_TXP2
P4_TXN3
P4_TXN2
P4_RXP3
P4_RXP2
P4_RXN3
P4_RXN2
1
SHEETDATE
23
7 3 2 16 5 4
E
A
B
C
E
D
C
B
A
7 6 5 4
D
DEPARTMENT
SIZE
PROJECT DOCUMENT NUMBER REV
REVIEWER
DESIGNER
OUT
OUT
OUT
OUT
OUT
OUT
OUT
OUT
IN
IN
IN
IN
IN
IN
IN
IN
C



Thu Aug 24 14:08:45 2023<NAME_2>
<NAME_1>
MB FABCGTI V02
54 OF 365
P V DD18_S 5_P 1
P V DD18_S 5_P 1
P 3V 3_A UX
P V DD18_S 5_P 1
54
54
54
54
54 82
5482
5482
5482
275482
275482
81
8254
275482
275482
54 82
54
54
54
54
161
161
54173
54173
54173
54174
217
8183
8183
5482
5482
5482
5482
5482
5482
167
210
217
226
224
217
226
217224
217
210
54 82
54 82
54 82
54 82
54 82
54 82
17354
17354
17354
17454
17354
82 54
82 54
54174
54173
210
54174
210
210
217
217
27 54 82
27 54 82
27 54 82
27 54 82
27 82
275482
275482
54
54
54
54
210
275482
275482
54
54
33
33
2.2K
2.2K
2.2K
2.2K
E MP TY
A P ML_CP U1_A LE RT_N
CP U1_B P 3
CP U1_B P 2
CP U1_B P 0
CP U1_CO RE TY P E 0
CP U1_S P 5R3
CP U1_S P 5R4
CP U1_CO RE TY P E 0
CP U1_X TRIG _L6
CP U1_X TRIG _L4
TP _CP U1_TE S T6_CCD3
TP _CP U1_TE S T6_CCD2
TP _CP U1_TE S T6_CCD0
A P ML_CP U1_A LE RT_R_N
CP U1_P RO CHO T_N
CP U1_X TRIG _L7
CP U1_X TRIG _L6
2.2K
CPU1 MISC 1/2
CP U1_P RO CHO T_N
NC_CP U1_A Z_S Y NC
NC_CP U1_A Z_S DIN0
NC_CP U1_A Z_RS T_N
NC_CP U1_A Z_S DIN1
NC_CP U1_A Z_S DO UT
NC_CP U1_A Z_S DIN2
NC_CP U1_A Z_B ITCLK
CP U1_B P 3
CP U1_B P 2
CP U1_B P 0
CP U1_B P 1
TP _CP U1_TE S T6_X 3D3
TP _CP U1_TE S T6_X 3D2
TP _CP U1_TE S T6_X 3D1
TP _CP U1_TE S T6_X 3D0
TP _CP U1_TE S T4_CCD6
TP _CP U1_TE S T4_CCD5
TP _CP U1_TE S T4_CCD4
TP _CP U1_TE S T6_IO D
TP _CP U1_TE S T4_CCD3
TP _CP U1_TE S T4_CCD2
TP _CP U1_TE S T4_CCD1
TP _CP U1_TE S T4_CCD0
TP _CP U1_TE S T6_X 3D5
TP _CP U1_TE S T6_CCD1
TP _CP U1_TE S T6_X 3D4
TP _CP U1_TE S T5_CCD11
TP _CP U1_TE S T4_CCD11
TP _CP U1_TE S T5_CCD10
TP _CP U1_TE S T4_CCD9
TP _CP U1_TE S T4_CCD10
TP _CP U1_TE S T4_CCD8
TP _CP U1_TE S T5_CCD9
TP _CP U1_TE S T4_CCD7
TP _CP U1_TE S T5_CCD8
TP _CP U1_TE S T5_CCD7
TP _CP U1_TE S T5_CCD6
TP _CP U1_TE S T5_CCD5
TP _CP U1_TE S T5_CCD4
TP _CP U1_TE S T4_IO D
TP _CP U1_TE S T5_CCD3
TP _CP U1_TE S T5_CCD1
TP _CP U1_TE S T5_CCD0
TP _CP U1_UA RT1_RX
TP _CP U1_UA RT0_CTS _N
TP _CP U1_UA RT0_TX
TP _CP U1_UA RT0_RTS _N
TP _CP U1_UA RT0_RX
TP _CP U1_TE S T41_IO D
TP _CP U1_TE S T5_IO D
TP _CP U1_UA RT0_INTR
S MB _A P ML_CP U1_S CL
S MB _A P ML_CP U1_S DA
JTA G _CP U1_DB RE Q _N
JTA G _CP U1_TMS
JTA G _CP U1_TCK
JTA G _CP U1_TDI
S V ID_P V DDCR_CP U1_P 1_S V TO
FM_P 1_P CC1_N
FM_P 1_P CC0_N
CP U1_CO RE TY P E 2
CP U1_CO RE TY P E 1
CP U1_S P 5R2
CP U1_S P 5R1
CP U1_S A 1
CP U1_S A 0
P RS NT_CP U1_N
TP _CP U1_TE S T47_CCD3
TP _CP U1_TE S T47_IO D1
TP _CP U1_TE S T47_IO D0
TP _CP U1_TE S T47_CCD2
TP _CP U1_TE S T47_CCD1
TP _CP U1_TE S T47_CCD0
V S E NS E _P V DDCR_CP U0_P 1_DP
V S E NS E _P V DDCR_CP U1_P 1_DP
TP _V S E NS E _P V DD33_S 5_P 1
V S E NS E _P V DD18_S 5_P 1_DP
V S E NS E _P V DD11_S 3_P 1_DP
V S E NS E _P V DDIO _P 1_DP
V S E NS E _P V DD18_S 5_P 1_DN
V S E NS E _V S S _S E NS E _C_P 1
V S E NS E _V S S _S E NS E _B _P 1
V S E NS E _V S S _S E NS E _A _P 1
TP _CP U1_TE S T50_IO D
CP U1_CO RE TY P E 2
CP U1_CO RE TY P E 1
CP U1_S P 5R4
CP U1_S P 5R3
CP U1_S P 5R2
CP U1_S P 5R1
JTA G _CP U1_DB RE Q _N
JTA G _CP U1_TMS
JTA G _CP U1_TCK
JTA G _CP U1_TDI
JTA G _CP U1_TRS T_N
CP U1_S A 1
CP U1_S A 0
JTA G _CP U1_TDO
IO
NANANANANANANANANANA
CHIP
CHIP
E MP TYE MP TYE MP TYE MP TYE MP TYE MP TY
E MP TY
10%10%10%10%10%10%
0.001UF0.001UF0.001UF0.001UF0.001UF0.001UF
2.2K
2.2K
2.2K
2.2K
2.2K
2.2K
2.2K
2.2K
2.2K 2.2K
50V50V50V50V50V50V
C0402C0402C0402C0402C0402C0402
0402LF
0402LF 0402LF
2.2K
JTA G _CP U1_TRS T_N
S V ID_P V DDCR_CP U0_P 1_S V TO
S O CK E T6096_13568-001
SMLF
0 JTA G _CP U1_R_TDOJTA G _CP U1_TDO
0S V ID_P V DDCR_CP U0_P 1_S V D_R S V ID_P V DDCR_CP U0_P 1_S V D
0S V ID_P V DDCR_CP U0_P 1_S V C_R S V ID_P V DDCR_CP U0_P 1_S V C
0S V ID_P V DDCR_CP U1_P 1_S V D_R S V ID_P V DDCR_CP U1_P 1_S V D
0S V ID_P V DDCR_CP U1_P 1_S V C_R S V ID_P V DDCR_CP U1_P 1_S V C
0CP U1_X TRIG _R2_L5 CP U1_X TRIG _L5
0CP U1_X TRIG _R2_L4 CP U1_X TRIG _L4
0CP U1_X TRIG _R2_L7 CP U1_X TRIG _L7
0CP U1_X TRIG _R2_L6 CP U1_X TRIG _L6
0
0
0
0
0402LF
1K
CHIP
1/16W
1%
0402LF
1K
CHIP
1/16W
1%
0402LF
1K
CHIP
1/16W
1%
0402LF
1K
CHIP
1/16W
1%
0402LF
1K
CHIP
1/16W
1%
0402LF
1K
CHIP
1/16W
1%
A P ML_CP U1_A LE RT_N
CP U1_THE RMTRIP _N CP U1_THE RMTRIP _R_N
CP U1_X TRIG _L7
CP U1_X TRIG _L5
CP U1_X TRIG _R1_L7
CP U1_X TRIG _R1_L6
CP U1_X TRIG _R1_L5
CP U1_X TRIG _R1_L4
SMLF
IO
CP U1_B P 3
CP U1_B P 2
CP U1_B P 1
CP U1_B P 0
SCONN8_G802M0083150RD3HR
SMLF
IO
SCONN8_G802M0083150RD3HR
TP _CP U1_TE S T5_CCD2
V S E NS E _P V DDCR_S O C_P 1_DP
2.2K
CP U1_X TRIG _L5
CP U1_X TRIG _L4
2.2K
2.2K
2.2K
2.2K
CP U1_THE RMTRIP _N
CP U1_B P 1
54
54
R536
21 R497
21 R488
21R540
21R539
21R538
21R537
21R534
21R533
21R532
21R531
2
1 R521
2
1R519
2
1R518
21R516
21R514
21R512
21R535
21R520
21R515
21R513
21R522
21R517
21 R931
21 R932
21 R930
21 R929
21 R862
21 R928
21 R486
21 R618
21PR236
21PR237
21PR169
21PR170
2
1 C230
2
1
R523
2
1 C231
2
1 C232
2
1
R524
2
1
R525
2
1 C233
2
1
R526
2
1 C234
2
1 C235
2
1
R527
2
1
R528
T P11T P12T P13T P14 T P15T P16T P17T P18 T P19T P20
2 1R529
A65
A66
C65
C66
B73
DJ3
BR54
C3
BR53
B3
DG3
C2
BP53
C74
DH3
DJ32
DH33
DJ34
DG35
DF34
DG34
DJ33
A17
A16
DJ9
B61
D7
B58
E32
CK46
CJ24
B60
W31
CJ53
AA23
CJ52
AA29
CJ29
AA47
AA49
Y46
CJ46
CJ30
AA46
AA24
Y29
CK47
CK29
Y47
AA26
CJ51
CJ25
AA53
Y30
CJ49
CJ27
AA51
AA25
AA28
CJ47
CK30
AA48
AA27
CJ50
CJ26
AA52
AA30
CJ48
CJ28
AA50
C18
C17
B17
DG73
B21
DH72
A22
DJ72
A23
DH10
DH73
C68
C19
DH71
DJ71
DJ56
DJ55
DH8
A69
DG72
C22
C16
B66
D68
B69
C70
A62
A63
C62
C63
D32
A32
A33
D33
C33
A34
C32
A68
U26
1
1
1
1
1
1
1
1
1
1
87
65
43
21
87
65
43
21
J49
J7
87
65
43
21
87
65
43
21
20/40
CORETYPE2
BP3
BP2
BP1
BP0
TEST41_IOD
TEST47_CCD3
TEST6_CCD0
TEST6_X3D3
TEST6_X3D2
TEST47_IOD1 TEST6_X3D1
TEST47_IOD0 TEST6_X3D0
TEST5_CCD11
TEST4_CCD11
TEST5_CCD10
TEST4_CCD9
TEST4_CCD10
TEST47_CCD2
TEST4_CCD8
TEST5_CCD9
TEST47_CCD1
TEST4_CCD7
TEST50_IOD
TEST5_CCD8
TEST47_CCD0
TEST4_CCD6
TEST5_CCD7
TEST4_CCD5
TEST5_CCD6
TEST4_CCD4
TEST5_CCD5
TEST6_IOD
TEST4_CCD3
TEST5_CCD4
TEST5_IOD
TEST4_CCD2
TEST4_IOD
TEST5_CCD3
TEST4_CCD1
TEST5_CCD2
TEST6_CCD3
TEST4_CCD0
TEST5_CCD1
TEST6_CCD2
TEST6_X3D5
TEST5_CCD0
TEST6_CCD1
TEST6_X3D4
VDDCR_CPU0_SENSE
VDDCR_CPU1_SENSE
VDDCR_SOC_SENSE
VDD_33_S5_SENSE
VDD_18_S5_SENSE
VDD_11_S3_SENSE
VDDIO_SENSE
VSS_SENSE_D
VSS_SENSE_C
VSS_SENSE_B
VSS_SENSE_A
UART1_TXD||AGPIO142
UART1_RXD||AGPIO141
RTC_LDO_SELECT
TCK
SP5R1
AZ_SDIN1||SW_MCLK
AZ_SDIN0||SW_MDATA3
AZ_RST_L||SW_MDATA1
AZ_SDOUT||SW_MDATA2
AZ_SDIN2||SW_MDATA0
UART0_CTS_L||UART2_TXD||AGPIO135
UART0_TXD||AGPIO138
UART0_INTR||AGPIO139
UART0_RTS_L||UART2_RXD||AGPIO137
UART0_RXD||AGPIO136
SVC1
SVT1
SVC0
SVD1
SVT0
SVD0 AZ_SYNC
AZ_BITCLK
PCC1_L
PCC0_L
SP5R4
SP5R3
SP5R2
CORETYPE1
CORETYPE0
SA1
XTRIG_L7
XTRIG_L6
XTRIG_L5
XTRIG_L4
TRST_L
TMS
THERMTRIP_L
TDO
TDI
SID
SIC
SA0
PROCHOT_L
DBREQ_L
CPU_PRESENT_L
ALERT_L
21
1
SHEETDATE
23
7 3 2 16 5 4
E
A
B
C
E
D
C
B
A
7 6 5 4
D
DEPARTMENT
SIZE
PROJECT DOCUMENT NUMBER REV
REVIEWER
DESIGNER
OUT
OUT
OUT
OUT
OUT
OUT
OUT
OUT
OUT
OUT
OUT
OUT
OUT
OUT
OUT
OUT
OUT
OUT
BI
BI
BI
BI
OUT
OUT
OUT
OUT
OUT
OUT
OUT
OUT
OUT
OUT
OUT
OUT
OUT
OUT
OUT
OUT
OUT
OUT
OUT
OUT
OUT
OUT
OUT
OUT
OUT
OUT
OUT
IN
IN
OUT
OUT
OUT
IN
IN
IN
IN
OUT
IN
IN
IN
IN
IN
IN
IN
BI
BI
BI
BI
IN
OUT
OUT
OUT
OUT
OUT
OUT
OUT
OUT
OUT
OUT
C



20220926 ADD R6503
Thu Aug 24 14:08:45 2023<NAME_2>
<NAME_1>
MB FABCGTI V02
55 OF 365
P V DD18_S 5_P 1
P V DD18_S 5_P 1
P V DD11_S 3_P 1
P V DD18_S 5_P 1
2.7P F
C0402
NP O
50V
0.1P F
2.7P F
NP O
50V
0.1P F
C0402
1/16W CHIP
55 82
55 81 85 78
55 159
5582
5582
5582
55
55
55 81
183
183
144
144
82 55
55 81
82 55
81 55
81 55
55 81
55 81 85
55 81
55 81
55 81
155 28
55 159
5582
161
81
81
55
2876
5581
2881
5581
55
55
5581
122
122
137
137
137
137
137
137
137
137
122
122
81 83
81 83
55 81
5581
55
55
55159
55159
55159
55159
161
55
28
28
55 81 85 78
55 81 85
55 81
76
55 159
55 159
82 55
81 55
55 81
55
55
5581
0E MP TY
0E MP TY
FM_CP U1_B MC_RS T_N
P W RG D_CP U1_P W RO K
I3C_1_S P D_DDRG L_CP U1_R_S CL
TP _S LO T2_B UF_S K U_ID1
TP _S LO T2_B UF_S K U_ID0
FM_CP U1_B MC_RS T_N
FM_BMC _TPM_PR ES_N
FM_BMC _R EAD Y_N
CP U1_S LP _S 3_N
CP U1_S LP _S 5_N
1K
CP U1_S ME RR_N
2.2K
0402LF
5%
CLK _100M_CP U1_CLK 13_DN
CLK _100M_CP U1_CLK 13_DP
CLK _100M_CP U1_CLK 12_DN
CLK _100M_CP U1_CLK 13_R_DN
CLK _100M_CP U1_CLK 13_R_DP
1/16W
CLK _100M_CP U1_CLK 12_DP
5%
0402LF
CLK _100M_CP U1_CLK 12_R_DN
CLK _100M_CP U1_CLK 12_R_DP
CLK _100M_CP U1_CLK 11_R_DN
CLK _100M_CP U1_CLK 11_R_DP
0402LF
E MP TY
FM_BMC _TPM_PR ES_N
CP U1_P W RG D_O UT
FM_BMC _R EAD Y_N
4.7K
4.7K
CP U1_NMI_S Y NC_FLO O D_N
RS T_CP U1_S Y S _N
CP U1_FO RCE _S E LFRE FRE S H
CHIPCHIP
E MP TY
RS T_CP U1_RE S E TL_N
E MP TY
E MP TY
4.7K
CP U1_NV _S A V E _N4.7K
E MP TY
E MP TY
CP U1_S P D_HO S T_CTRL_N
CP U1_FO RCE _S E LFRE FRE S H
IRQ _W A K E _N
CLK _100M_CP U1_CLK 05_R_DP
1%20M
0402LF1/16W CHIP
50V
I3C_1_S P D_DDRG L_CP U1_R_S DA
IR Q_C PU _BMC _N MI_N
S MB _CP U1_S E C_S CL
1%
1K
E MP TY
1%
E MP TY
1K
1%
1K
E MP TY
1%
E MP TY
1K
CP U1_S LP _S 3_NFM_CP U1_S LP _S 3_N
CP U1_S LP _S 5_NFM_CP U1_S LP _S 5_N
X TA L_CP U1_X 32K _X 2X TA L_CP U1_R_X 32K _X 2 E MP TY 0
X TA L_CP U1_R_X 32K _X 1 E MP TY 0
CP U1_S P D_HO S T_CTRL_R_N0
CLK _CP U0_RTCCLK
CHIP
0
4.7K
4.7K
4.7K
CHIP
4.7K4.7K
E MP TY
4.7K
E MP TY
4.7K
E MP TY
4.7K
E MP TY
4.7K
4.7K
E MP TY
E MP TY
4.7K
1%10M
0402LF
RS T_CP U1_RS MRS T_N
1000P F
CP U1_P W R_G D_IN
50V
5%
X 7R
0402
CP U1_NMI_S Y NC_FLO O D_N
INT_CP U1_HP _UB M_N
X TA L_CP U1_X 32K _X 2
X TA L_CP U1_X 32K _X 1
CP U1_S ME RR_N
CLK _100M_CP U1_CLK 11_DN
CLK _100M_CP U1_CLK 11_DP
CLK _100M_CP U1_CLK 05_DN
CLK _100M_CP U1_CLK 05_DP
CLK _100M_CP U1_CLK 04_DN
CLK _100M_CP U1_CLK 04_DP
CLK _100M_CP U1_CLK 03_DN
CLK _100M_CP U1_CLK 03_DP
CLK _100M_CP U1_CLK 02_DN
CLK _100M_CP U1_CLK 02_DP
CLK _100M_CP U1_CLK 01_DN
CLK _100M_CP U1_CLK 01_DP
1/16W
5%
5%
1/16W
1/16W
1/16W
0
0402LF
1/16W
1/16W
1/16W
5%
0402LF 5%
5%
CHIP
CLK _100M_CP U1_CLK 01_R_DP
CLK _100M_CP U1_CLK 01_R_DN
CHIP
1/16W
0402LF
CLK _100M_CP U1_CLK 04_R_DN
0402LF
5%
0
0402LF
0402LF
0
00402LF
0
0
0
CHIP
0402LF
CHIP
0
5%
CHIP
RS T_CP U1_P E RS T0_N
RS T_CP U1_P E RS T1_N
1/16W
5% 1/16W
5%0
0
CP U1_NV _S A V E _N
1/16W
5%
5%
0
5%
S MLF
32.768K HZ
2.2K
S O CK E T6096_13568-001
IO
NC_CP U1_P W R_B TN_N
RS T_CP U1_S Y S _N
X TA L_CP U1_X 48M_X 2
X TA L_CP U1_X 48M_X 1
I3C_0_S P D_DDRA F_CP U1_R_S CL
I3C_0_S P D_DDRA F_CP U1_R_S DA
I3C_1_S P D_DDRG L_CP U1_R_S CL
I3C_1_S P D_DDRG L_CP U1_R_S DA
S MB _CP U1_S E C_S DA
X TA L_CP U1_X 32K _X 1
CLK _100M_RE F_IN_DP
CLK _100M_RE F_IN_DN
P W RG D_CP U1_P W RO K
RS T_CP U1_RE S E TL_N
CP U1_P W RG D_O UT
CLK _CP U1_RTCCLK
SMLF
10P F
50V
0402
NP O
1%
10P F
0402
NP O
1%
1/16W0
I3C_0_S P D_DDRA F_CP U1_R_S DA
I3C_0_S P D_DDRA F_CP U1_R_S CL
MIS C
SMLF
48MHZ
E MP TY2.2K
1K
4.7K
IR Q_C PU _BMC _N MI_N
4.7K
RS T_CP U1_RS MRS T_N
CPU1 MISC 2/2
0402LF
CHIP
2.2K
C PU 1_FOR C E_SELFR EFR ESH
X TA L_CP U1_X 48M_X 1
X TA L_CP U1_X 48M_X 2
49.9
CP U1_S P D_HO S T_CTRL_N
X TA L_CP U1_X 48M_X 2_R
0402LF
CLK _100M_CP U1_CLK 03_R_DN
CLK _100M_CP U1_CLK 03_R_DP
CLK _100M_CP U1_CLK 02_R_DN
CLK _100M_CP U1_CLK 02_R_DP
0402LF
0402LF
CHIP
1/16W
CHIP
0
1/16W0 5%
00402LF
0 5% 1/16W0402LF
CLK _100M_CP U1_CLK 05_R_DN
CLK _100M_CP U1_CLK 04_R_DP
CHIP
55
55
R8350
R8351
R6503
2 1 R558
2
1 C5024
2
1 R563
2
1 R543
2
1 R542
2
1 R541
21 R557
2 1 R550
2 1 R547
2 1 R551
2 1 R553
21 R556
21 R559
21 R562
2 1 R549
2 1 R548
R583
R584
R456R546R545R544
R491R5030R5031R5032
R4305
R4306
R3201
R3200
R3199
R3198
R3197
R3196
R3195
R3194
R3354
R3355
R3353
R3352
21 R192
21 R191
21R575
21 R1424
21R570
DJ16
DJ17
DJ13
DJ14
DJ10
DH6
DJ11
DG4
DJ5
B15
D15
D14
B14
DH9
DG10
B67
A19
A20
D69
DH36
DJ8
DH7
DG36
D18
B64
DJ31
B4
A4
B72
C72
A5
C7
B71
A71
DJ20
DJ21
DH12
DG12
DJ51
DJ50
DJ48
DJ47
DJ53
DJ54
DJ45
DJ44
DJ41
DJ42
B9
C9
B12
C12
A10
A11
B6
C6
A8
A7DJ35
B63
B16
A13
C14
A14
DH15
DH16
DG32
DG31
DF31
DE30
DH30
DJ29
DG11
DE32
DF33
DH4
DE40
DF40
DF36
DE36
U26
21R573
21R574
2
1 C237
31
42
Y4
21
R571
2
1 C239
21
Y5
2
1 C238
2
1 C236
2121
21
21
21
21
21
21
21
21
R572
R5103
21
21/40
AGPIO7
NMI_SYNC_FLOOD_L
SEC_SCL||AGPIO262
SEC_SDA||AGPIO263
AGPIO257||SGPIO1_CLK||CLK_REQ01_L
PWROK||SVI_RST_L
AGPIO6||DEVSLP1||SATA_ZP1_L
AGPIO5||DEVSLP0||SATA_ZP0_L
GENINT_L||PM_INTR_L||UBM_CPRSNT_CHANGE_DET_L||AGPIO89
AGPIO22
AGPIO88
AGPIO21
AGPIO87
AGPIO109
AGPIO107
AGPIO106
AGPIO105
AGPIO104
RESET_L
REFCLK100SSC_N||GPP_CLK10N
REFCLK100SSC_P||GPP_CLK10P
SMERR_L||AGPIO24
I2C5_SDA||BMC_SDA||SMBUS1_SDA||AGPIO20
I2C5_SCL||BMC_SCL||SMBUS1_SCL||AGPIO19
I2C4_SDA||HP_SDA||UBM_SDA||AGPIO14
I2C4_SCL||HP_SCL||UBM_SCL||AGPIO13
I3C3_SCL||I2C3_SCL||SPD3_SCL||AGPIO151
I3C1_SDA||I2C1_SDA||SPD1_SDA||AGPIO148
AGPIO116||CLK_REQ12_L
PWRGD_OUT||AGPIO12
AGPIO259||SGPIO3_CLK
I3C0_SCL||I2C0_SCL||SPD0_SCL||SMBUS0_SCL||AGPIO145
I3C2_SCL||I2C2_SCL||SPD2_SCL||AGPIO149
I3C1_SCL||I2C1_SCL||SPD1_SCL||AGPIO147
I3C0_SDA||I2C0_SDA||SPD0_SDA||SMBUS0_SDA||AGPIO146
AGPIO115||CLK_REQ11_L
PCIE_RST0_L||AGPIO266
AGPIO256||SGPIO0_CLK
AGPIO258||SGPIO2_CLK||CLK_REQ02_L
I3C3_SDA||I2C3_SDA||SPD3_SDA||AGPIO152
SGPIO_DATAOUT||AGPIO260
I3C2_SDA||I2C2_SDA||SPD2_SDA||AGPIO150
SGPIO_LOAD||AGPIO261
PCIE_RST1_L||AGPIO26
AGPIO3||SPD_HOST_CTRL_L
AGPIO4||SATA_ACT_L
GPP_CLK11P
GPP_CLK01P
GPP_CLK12P
GPP_CLK02P
GPP_CLK11N
GPP_CLK13P
GPP_CLK01N
GPP_CLK03P
GPP_CLK12N
GPP_CLK14P
GPP_CLK02N
GPP_CLK04P
GPP_CLK13N
GPP_CLK15P
GPP_CLK03N
GPP_CLK05P
GPP_CLK14N
GPP_CLK04N
GPP_CLK15N
GPP_CLK05N
RTCCLK
FORCE_SELFREFRESH
NV_SAVE_L
PWR_BTN_L||AGPIO0
X48M_X2
X48M_X1
X32K_X2
X32K_X1
WAKE_L||AGPIO2
SYS_RESET_L||AGPIO1
SLP_S5_L
SLP_S3_L
RSMRST_L
PWR_GOOD
X2
G2G1
X1
21
21
2
1
21
2
1
21
21
21
21
21
21
21
21
21
21
21
21
21
21
1
SHEETDATE
23
7 3 2 16 5 4
E
A
B
C
E
D
C
B
A
7 6 5 4
D
DEPARTMENT
SIZE
PROJECT DOCUMENT NUMBER REV
REVIEWER
DESIGNER
OUT
OUT
OUT
OUT
OUT
OUT
OUT
OUT
OUT
OUT
OUT
OUT
OUT
OUT
OUT
OUT
OUT
OUT
OUT
IN
IN
IN
OUT
OUT
OUT
OUT
OUT
OUT
OUT
OUT
OUT
OUT
OUT
OUT
OUT
OUT
OUT
OUT
OUT
OUT
OUT
OUT
OUT
OUT
IN
IN
BI
BI
OUT
BI
OUT
OUT
OUT
IN
IN
IN
IN
IN
IN
IN
IN
OUT
OUT
OUT
OUT
OUT
IN
BI
BI
IN
IN
IN
OUT
OUT
OUT
C



Thu Aug 24 14:08:46 2023<NAME_2>
<NAME_1>
MB FABCGTI V02
56 OF 365
76
76
S P I_CP U1_R_CLKS P I_CP U1_CLK 33
S O CK E T6096_13568-001
IO
P D_E S P I_CP U1_CLK 2
NC_CP U1_US B 3_US B 11_TX N
NC_CP U1_US B 3_US B 11_TX P
NC_CP U1_US B 10_O C_N
NC_CP U1_US B 11_O C_N
NC_CP U1_US B 00_O C_N
NC_CP U1_US B 01_O C_N
NC_CP U1_US B 2_US B 00_DN
NC_CP U1_US B 2_US B 00_DP
NC_CP U1_US B 3_US B 00_RX N
NC_CP U1_US B 3_US B 00_RX P
NC_CP U1_US B 3_US B 00_TX P
NC_CP U1_US B 3_US B 00_TX N
NC_CP U1_US B 2_US B 01_DN
NC_CP U1_US B 2_US B 01_DP
NC_CP U1_US B 3_US B 01_RX N
NC_CP U1_US B 3_US B 01_RX P
NC_CP U1_US B 3_US B 01_TX N
NC_CP U1_US B 3_US B 01_TX P
NC_CP U1_US B 2_US B 10_DN
NC_CP U1_US B 2_US B 10_DP
NC_CP U1_US B 3_US B 10_RX N
NC_CP U1_US B 3_US B 10_RX P
NC_CP U1_US B 3_US B 10_TX N
NC_CP U1_US B 3_US B 10_TX P
NC_CP U1_US B 2_US B 11_DN
NC_CP U1_US B 2_US B 11_DP
NC_CP U1_US B 3_US B 11_RX N
NC_CP U1_US B 3_US B 11_RX P
CPU1 SPI/USB
SMLF
21 R738
DG58
DH58
DJ62
DH62
DH40
DH60
DJ60
DH69
DJ69
DJ65
DH65
DG40
DJ67
DH67
E30
E29
C29
C28
E24
A28
A29
C25
C26
E27
E26
E23
A26
A25
DH27
DG26
DF30
DE27
DJ26
DJ23
DG28
DF27
DG23
DJ27
DG25
DF25
DE24
DH24
DF24
DG29
DJ28
DG22
DF28
DJ22
DJ25
U26
22/40
ESPI_RSTOUT_L||AGPIO23
ESPI_CLK1||SPI_CLK1||AGPIO75
ESPI_CLK2||AGPIO74
ESPI0_ALERT_L||AGPIO108
AGPIO76||SPI_TPM_CS_L
ESPI_CLK0||SPI_CLK0||AGPIO117
ESPI1_ALERT_L||AGPIO110
ESPI_RSTIN_L||KBRST_L||AGPIO129
USB01_OC_L||AGPIO265
SPI_CS1_L||AGPIO119
SPI_CS2_L||AGPIO126
ESPI0_DAT0||SPI0_DAT0||AGPIO120
ESPI0_DAT1||SPI0_DAT1||AGPIO121
ESPI0_DAT2||SPI0_DAT2||AGPIO122
ESPI0_DAT3||SPI0_DAT3||AGPIO123
ESPI1_DAT2||SPI1_DAT2||AGPIO133
ESPI1_DAT3||SPI1_DAT3||AGPIO134
ESPI_CS1_L||AGPIO125
ESPI1_DAT0||SPI1_DAT0||AGPIO131
ESPI1_DAT1||SPI1_DAT1||AGPIO132
SPI_CS0_L||AGPIO118
USB00_OC_L||AGPIO264
ESPI_CS0_L||AGPIO124
USB11_OC_L||AGPIO17
USB10_OC_L||AGPIO16
USB11_TXP
USB11_TXN
USB11_RXP
USB11_RXN
USB11_DP
USB11_DN
USB10_TXP
USB10_TXN
USB10_RXP
USB10_RXN
USB10_DP
USB10_DN
USB01_TXP
USB01_TXN
USB01_RXP
USB01_RXN
USB01_DP
USB01_DN
USB00_TXP
USB00_TXN
USB00_RXP
USB00_RXN
USB00_DP
USB00_DN
1
SHEETDATE
23
7 3 2 16 5 4
E
A
B
C
E
D
C
B
A
7 6 5 4
D
DEPARTMENT
SIZE
PROJECT DOCUMENT NUMBER REV
REVIEWER
DESIGNER
OUT
IN
C



Thu Aug 24 14:08:46 2023<NAME_2>
<NAME_1>
MB FABCGTI V02
57 OF 365
P V DDCR_CP U0_P 1
P V DDCR_CP U1_P 1
P V DD18_S 5_P 1
P V DD11_S 3_P 1
P V DD18_S 5_P 1
P V DD_33_S 5
P V DDCR_S O C_P 1P V DDCR_S O C_P 1
P V DDCR_CP U0_P 1
P V DDIO _P 1
P V DDCR_CP U1_P 1
P 1V 5_B A T
SMLF
CPU1 POWER
IO
IO
IO
SMLF
S O CK E T6096_13568-001
SMLF
S O CK E T6096_13568-001
SMLF
IO S O CK E T6096_13568-001
S O CK E T6096_13568-001
SMLF
IO S O CK E T6096_13568-001
0402LF
0
5%
CHIP
1/16W
0402LF
0
5%
E MP TY
1/16W
CP U1_V DDB T_RTC_G
2
1R373
2
1 R374
Y19
Y12
Y5
V22
U18
U11
U4
P22
P19
P12
P5
L18
L11
L4
K22
H19
H12
H5
E11
E4
C4
BM 5
BJ48
BJ11
BJ4
BH48
BH25
BH23
BG48
BG28
BG26
BG24
BG22
BF48
BF27
BF25
BF23
BD48
BD28
BD26
BD24
BD22
BD19
BD12
BD5
BC48
BC27
BC25
BC23
BB49
BB28
BB26
BB24
BB22
BA48
BA27
BA25
BA23
BA18
BA11
BA4
B5
AY49
AY28
AY26
AY24
AY22
AW48
AW27
AW25
AW23
AV47
AV45
AV43
AV41
AV39
AV36
AV34
AV32
AV30
AV28
AV26
AV24
AV22
AV19
AV12
AV5
AU40
AU35
AU31
AU27
AU23
AT 22
AR18
AR11
AR4
AM 22
AM 19
AM 12
AM 5
AJ18
AJ11
AJ4
AH22
AF19
AF12
AF5
AD22
AC18
AC11
AC4
AA22
U26
DJ57
B36
D23
DG42
DH14
C59
C23
DF41
DH13
C58
E36
E33
DJ4
DH21
DH17
DG17
D72
D65
D62
D58
D36
D34
D22
D11
D8
D4
C54
C53
C35
C34
C31
BD72
BD69
BD65
BD62
BD58
BD55
BD21
BD18
BD14
BD11
BD7
BD4
B40
A60
A59
A57
A56
A55
A54
A51
A50
A48
A45
A42
A41
A35
A31
U26
Y71
Y64
Y57
V54
U72
U65
U58
P71
P64
P57
P54
L72
L65
L58
K54
H71
H64
H57
DG71
DG64
DE72
DE65
DE58
DB71
DB64
DB57
CY54
CW72
CW65
CW58
CT 71
CT 64
CT 57
CT 54
CN72
CN65
CN58
CM 54
CK71
CK64
CK57
CJ54
CG72
CG65
CG58
CF54
CD71
CD64
CD57
CB54
CA72
CA65
CA58
BV71
BV64
BV57
BV54
BR72
BR65
BR58
BN54
BM 71
BM 64
BM 57
BM 53
BM 51
BL54
BL52
BL50
BK53
BK51
BJ72
BJ65
BJ58
BJ54
BJ52
BJ50
BH53
BH51
BG54
BG52
BG50
BF71
BF64
BF57
BF53
BF51
BD54
BD52
BD50
BA72
BA65
BA58
AV71
AV64
AV57
BH27
AR72
AR65
AR58
AM 71
AM 64
AM 57
AM 54
AJ72
AJ65
AJ58
AH54
AF71
AF64
AF57
AD54
AC72
AC65
AC58
AA54
BN23
BP51
BN52
BC54
BC52
BB53
BB51
BA54
BA52
BA50
AY53
AY51
AW54
AW52
AW50
AV53
AV51
AV49
AU54
AU52
AU50
AT 53
AT 51
AR54
AR52
DG5
DE18
DE11
DE4
DB19
DB12
DB5
CY22
CW18
CW11
CW4
CT 22
CT 19
CT 12
CT 5
CN18
CN11
CN4
CM 22
CK19
CK12
CK5
CJ22
CG18
CG11
CG4
CF22
CD19
CD12
CD5
CB22
CA18
CA11
CA4
BV22
BV19
BV12
BV5
BR18
BR11
BR4
BP22
BN48
BN44
BN40
BN33
BN29
BN25
BM 49
BM 47
BM 45
BM 43
BM 41
BM 39
BM 36
BM 34
BM 32
BM 30
BM 28
BM 26
BM 24
BM 22
BM 19
BM 12
BL48
BL27
BL25
BL23
BK49
BK28
BK26
BK24
BK22
BJ27
BJ25
BJ23
BJ18
U26
DH57
DH56
DH54
DH53
DH51
DH50
DH48
DH47
DH45
DH44
DH42
DH41
DH35
DH34
DH32
DH31
DH29
DH28
DH26
DH25
DH23
DH22
DH20
DH19
DG57
DG19
DE54
DE51
DE48
DE45
DE42
DE41
DE35
DE34
DE31
DE28
DE25
DE22
DD54
DD51
DD48
DD45
DD42
DD34
DD31
DD28
DD25
DD22
DC41
DC40
DC36
DC35
DB53
DB52
DB50
DB49
DB47
DB46
DB44
DB43
DB33
DB32
DB30
DB29
DB27
DB26
DB24
DB23
DA41
DA40
DA36
DA35
CV53
CV52
CV50
CV49
CV47
CV46
CV44
CV43
CV33
CV32
CV30
CV29
CV27
CV26
CV24
CV23
CU41
CU40
CU36
CU35
CP53
CP52
CP50
CP49
CP47
CP46
CP44
CP43
CP33
CP32
CP30
CP29
CP27
CP26
CP24
CP23
CN41
CN40
CN36
CN35
CL47
CL46
CL44
CL43
CL33
CL32
CL30
CL29
CK41
CK40
CK36
CK35
CH53
CH52
CH50
CH49
CH47
CH46
CH44
CH43
CH33
CH32
CH30
CH29
CH27
CH26
CH24
CH23
CG41
CG40
CG36
CG35
CD53
CD52
CD50
CD49
CD47
CD46
CD44
CD43
CD33
CD32
CD30
CD29
CD27
CD26
CD24
CD23
CC41
CC40
CC36
CC35
BY53
BY52
BY50
BY49
BY47
BY46
BY44
BY43
BY33
BY32
BY30
BY29
BY27
BY26
BY24
BY23
BW41
BW40
BW36
BW35
BT 53
BT 52
BT 50
BT 49
BT 47
BT 46
BT 44
BT 43
BT 33
BT 32
BT 30
BT 29
BT 27
BT 26
BT 24
BT 23
BR52
BR50
BR48
BR46
BR44
BR42
BR40
BR35
BR33
BR31
BR29
BR27
BR25
BR23
BP49
BP47
BP45
BP43
BP41
BP39
BP36
BP34
BP32
BP30
BP28
BP26
BP24
BN50
BN46
BN42
BN35
BN31
BN27
U26
Y41
Y40
Y36
Y35
W47
W46
W44
W43
W33
W32
W30
W29
U41
U40
U36
U35
T 53
T 52
T 50
T 49
T 47
T 46
T 44
T 43
T 33
T 32
T 30
T 29
T 27
T 26
T 24
T 23
N41
N40
N36
N35
M 53
M 52
M 50
M 49
M 47
M 46
M 44
M 43
M 33
M 32
M 30
M 29
M 27
M 26
M 24
M 23
J41
J40
J36
J35
H53
H52
H50
H49
H47
H46
H44
H43
H33
H32
H30
H29
H27
H26
H24
H23
G41
G40
G36
G35
F54
F51
F48
F45
F42
F34
F31
F28
F25
F22
E54
E51
E48
E45
E42
E35
E34
E31
E28
E25
E22
D56
D55
C20
B57
B56
B54
B53
B51
B50
B48
B47
B45
B44
B42
B41
B35
B34
B32
B31
B29
B28
B26
B25
B23
B22
B20
B19
AU48
AU46
AU44
AU42
AU33
AU29
AU25
AT 49
AT 47
AT 45
AT 43
AT 41
AT 39
AT 36
AT 34
AT 32
AT 30
AT 28
AT 26
AT 24
AR50
AR48
AR46
AR44
AR42
AR40
AR35
AR33
AR31
AR29
AR27
AR25
AR23
AP53
AP52
AP50
AP49
AP47
AP46
AP44
AP43
AP33
AP32
AP30
AP29
AP27
AP26
AP24
AP23
AL41
AL40
AL36
AL35
AK53
AK52
AK50
AK49
AK47
AK46
AK44
AK43
AK33
AK32
AK30
AK29
AK27
AK26
AK24
AK23
AG41
AG40
AG36
AG35
AF53
AF52
AF50
AF49
AF47
AF46
AF44
AF43
AF33
AF32
AF30
AF29
AF27
AF26
AF24
AF23
AC41
AC40
AC36
AC35
AB53
AB52
AB50
AB49
AB47
AB46
AB44
AB43
AB33
AB32
AB30
AB29
AB27
AB26
AB24
AB23
U26
26/40
VDDCR_SOC_BG22
VDDCR_SOC_BG24
VDDCR_SOC_BG26
VDDCR_SOC_BG28
VDDCR_SOC_BG48
VDDCR_SOC_BH23
VDDCR_SOC_BH25
VDDCR_SOC_BH48
VDDCR_SOC_BJ4
VDDCR_SOC_BJ11
VDDCR_SOC_BJ48
VDDCR_SOC_BM5
VDDCR_SOC_BF48
VDDCR_SOC_BF27
VDDCR_SOC_BF25
VDDCR_SOC_BF23
VDDCR_SOC_BD48
VDDCR_SOC_BD28
VDDCR_SOC_BD26
VDDCR_SOC_BD24
VDDCR_SOC_BD22
VDDCR_SOC_BD19
VDDCR_SOC_BD12
VDDCR_SOC_BD5
VDDCR_SOC_BC48
VDDCR_SOC_BC27
VDDCR_SOC_BC25
VDDCR_SOC_BC23
VDDCR_SOC_BB49
VDDCR_SOC_BB28
VDDCR_SOC_BB26
VDDCR_SOC_BB24
VDDCR_SOC_BB22
VDDCR_SOC_BA48
VDDCR_SOC_BA27
VDDCR_SOC_BA25
VDDCR_SOC_BA23
VDDCR_SOC_BA18
VDDCR_SOC_BA11
VDDCR_SOC_BA4
VDDCR_SOC_AY49
VDDCR_SOC_AY28
VDDCR_SOC_AY26
VDDCR_SOC_AY24
VDDCR_SOC_AY22
VDDCR_SOC_AW48
VDDCR_SOC_AW27
VDDCR_SOC_AW25
VDDCR_SOC_AW23
VDDCR_SOC_AV47
VDDCR_SOC_AV45
VDDCR_SOC_AV43
VDDCR_SOC_AV41
VDDCR_SOC_AV39
VDDCR_SOC_AV36
VDDCR_SOC_AV34
VDDCR_SOC_AV32
VDDCR_SOC_AV30
VDDCR_SOC_AV28
VDDCR_SOC_AV26
VDDCR_SOC_AV24
VDDCR_SOC_AV22
VDDCR_SOC_AV19
VDDCR_SOC_AV12
VDDCR_SOC_AV5
VDDCR_SOC_AU40
VDDCR_SOC_AU35
VDDCR_SOC_AU31
VDDCR_SOC_AU27
VDDCR_SOC_AU23
VDDCR_SOC_AT22
VDDCR_SOC_AR18
VDDCR_SOC_AR11
VDDCR_SOC_AR4
VDDCR_SOC_AM22
VDDCR_SOC_AM19
VDDCR_SOC_AM12
VDDCR_SOC_AM5
VDDCR_SOC_AJ18
VDDCR_SOC_AJ11
VDDCR_SOC_AJ4
VDDCR_SOC_AH22
VDDCR_SOC_AF19
VDDCR_SOC_AF12
VDDCR_SOC_AF5
VDDCR_SOC_AD22
VDDCR_SOC_AC18
VDDCR_SOC_AC11
VDDCR_SOC_AC4
VDDCR_SOC_AA22
VDDCR_SOC_Y19
VDDCR_SOC_Y12
VDDCR_SOC_Y5
VDDCR_SOC_V22
VDDCR_SOC_U18
VDDCR_SOC_U11
VDDCR_SOC_U4
VDDCR_SOC_P22
VDDCR_SOC_P19
VDDCR_SOC_P12
VDDCR_SOC_P5
VDDCR_SOC_L18
VDDCR_SOC_L11
VDDCR_SOC_L4
VDDCR_SOC_K22
VDDCR_SOC_H19
VDDCR_SOC_H12
VDDCR_SOC_H5
VDDCR_SOC_E11
VDDCR_SOC_E4
VDDCR_SOC_C4
VDDCR_SOC_B5
23/40
TEST6_X3D6
TEST4_CCD15
TEST4_CCD12
TEST5_CCD12
TEST5_CCD15
TEST4_CCD14
TEST5_CCD14
TEST4_CCD13
TEST5_CCD13
TEST6_X3D7
RSVD_A60
RSVD_BD7
RSVD_D36
RSVD_BD58
RSVD_BD55
RSVD_A54
RSVD_A51
RSVD_A50
RSVD_A48
RSVD_C53
RSVD_A45
RSVD_C35
RSVD_D65
RSVD_A42
RSVD_C34
RSVD_D62
RSVD_BD21
RSVD_A41
RSVD_C31
RSVD_D58
RSVD_BD18
RSVD_DJ4
RSVD_A35
RSVD_B40
RSVD_BD14
RSVD_DH21
RSVD_A31
RSVD_D34
RSVD_BD11
RSVD_DH17
RSVD_A59
RSVD_D22
RSVD_DG17
RSVD_A57
RSVD_D11
RSVD_BD4
RSVD_BD72
RSVD_A56
RSVD_D8
RSVD_E36
RSVD_BD69
RSVD_A55
RSVD_D4
RSVD_E33
RSVD_BD65
RSVD_C54
RSVD_D72
RSVD_BD62
27/40
VDD_11_S3_CT19
VDD_11_S3_CT22
VDD_11_S3_CW4
VDD_11_S3_CW11
VDD_11_S3_CW18
VDD_11_S3_CY22
VDD_11_S3_DB5
VDD_11_S3_DB12
VDD_11_S3_DB19
VDD_11_S3_DE4
VDD_11_S3_DE11
VDD_11_S3_DE18
VDD_11_S3_DG5
VDDIO_CT64
VDDIO_CT71
VDDIO_CW58
VDDIO_CW65
VDDIO_CW72
VDDIO_CY54
VDDIO_DB57
VDDIO_DB64
VDDIO_DB71
VDDIO_DE58
VDDIO_DE65
VDDIO_DE72
VDDIO_DG64
VDDIO_DG71
VDDBT_RTC_G
VDDIO_AUDIO
VDD_33_S5_BP51
VDD_33_S5_BN52
VDD_11_S3_CT12
VDD_18_S5_BB53
VDD_18_S5_BB51
VDD_18_S5_BA54
VDD_18_S5_BA52
VDD_18_S5_BA50
VDD_18_S5_AY53
VDD_18_S5_AY51
VDD_18_S5_AW54
VDD_18_S5_AW52
VDD_18_S5_BC54
VDD_18_S5_BC52
VDD_18_S5_AW50
VDD_18_S5_AV53
VDD_18_S5_AV51
VDD_18_S5_AV49
VDD_18_S5_AU52
VDD_18_S5_AU50
VDD_18_S5_AT53
VDD_18_S5_AT51
VDD_18_S5_AR54
VDD_18_S5_AR52
VDD_18_S5_AU54
VDD_11_S3_CT5
VDD_11_S3_CN18
VDD_11_S3_CN11
VDD_11_S3_CN4
VDD_11_S3_CM22
VDD_11_S3_CK19
VDD_11_S3_CK12
VDD_11_S3_CK5
VDD_11_S3_CJ22
VDD_11_S3_CG18
VDD_11_S3_CG11
VDD_11_S3_CG4
VDD_11_S3_CF22
VDD_11_S3_CD19
VDD_11_S3_CD12
VDD_11_S3_CD5
VDD_11_S3_CB22
VDD_11_S3_CA18
VDD_11_S3_CA11
VDD_11_S3_CA4
VDD_11_S3_BV22
VDD_11_S3_BV19
VDD_11_S3_BV12
VDD_11_S3_BV5
VDD_11_S3_BR18
VDD_11_S3_BR11
VDD_11_S3_BR4
VDD_11_S3_BP22
VDD_11_S3_BN48
VDD_11_S3_BN44
VDD_11_S3_BN40
VDD_11_S3_BN33
VDD_11_S3_BN29
VDD_11_S3_BN25
VDD_11_S3_BM49
VDD_11_S3_BM47
VDD_11_S3_BM45
VDD_11_S3_BM43
VDD_11_S3_BM41
VDD_11_S3_BM39
VDD_11_S3_BM36
VDD_11_S3_BM34
VDD_11_S3_BM32
VDD_11_S3_BM30
VDD_11_S3_BM28
VDD_11_S3_BM26
VDD_11_S3_BM24
VDD_11_S3_BM22
VDD_11_S3_BM19
VDD_11_S3_BM12
VDD_11_S3_BL48
VDD_11_S3_BL27
VDD_11_S3_BL25
VDD_11_S3_BL23
VDD_11_S3_BK49
VDD_11_S3_BK28
VDD_11_S3_BK26
VDD_11_S3_BK24
VDD_11_S3_BK22
VDD_11_S3_BJ27
VDD_11_S3_BJ25
VDD_11_S3_BJ23
VDD_11_S3_BJ18
VDDIO_CT57
VDDIO_CT54
VDDIO_CN72
VDDIO_CN65
VDDIO_CN58
VDDIO_CM54
VDDIO_CK71
VDDIO_CK64
VDDIO_CK57
VDDIO_CJ54
VDDIO_CG72
VDDIO_CG65
VDDIO_CG58
VDDIO_CF54
VDDIO_CD71
VDDIO_CD64
VDDIO_CD57
VDDIO_CB54
VDDIO_CA72
VDDIO_CA65
VDDIO_CA58
VDDIO_BV71
VDDIO_BV64
VDDIO_BV57
VDDIO_BV54
VDDIO_BR72
VDDIO_BR65
VDDIO_BR58
VDDIO_BN54
VDDIO_BM71
VDDIO_BM64
VDDIO_BM57
VDDIO_BM53
VDDIO_BM51
VDDIO_BL54
VDDIO_BL52
VDDIO_BL50
VDDIO_BK53
VDDIO_BK51
VDDIO_BJ72
VDDIO_BJ65
VDDIO_BJ58
VDDIO_BJ54
VDDIO_BJ52
VDDIO_BJ50
VDDIO_BH53
VDDIO_BH51
VDDIO_BG54
VDDIO_BG52
VDDIO_BG50
VDDIO_BF71
VDDIO_BF64
VDDIO_BF57
VDDIO_BF53
VDDIO_BF51
VDDIO_BD54
VDDIO_BD52
VDDIO_BD50
VDDIO_BA72
VDDIO_BA65
VDDIO_BA58
VDDIO_AV71
VDDIO_AV64
VDDIO_AV57
VDDIO_AR72
VDDIO_AR65
VDDIO_AR58
VDDIO_AM71
VDDIO_AM64
VDDIO_AM57
VDDIO_AM54
VDDIO_AJ72
VDDIO_AJ65
VDDIO_AJ58
VDDIO_AH54
VDDIO_AF71
VDDIO_AF64
VDDIO_AF57
VDDIO_AD54
VDDIO_AC72
VDDIO_AC65
VDDIO_AC58
VDDIO_AA54
VDDIO_Y71
VDDIO_Y64
VDDIO_Y57
VDDIO_V54
VDDIO_U72
VDDIO_U65
VDDIO_U58
VDDIO_P71
VDDIO_P64
VDDIO_P57
VDDIO_P54
VDDIO_L72
VDDIO_L65
VDDIO_L58
VDDIO_K54
VDDIO_H71
VDDIO_H64
VDDIO_H5725/40
VDDCR_CPU1_BN46
VDDCR_CPU1_BN35
VDDCR_CPU1_BN27
VDDCR_CPU1_BP32
VDDCR_CPU1_BP28
VDDCR_CPU1_BP24
VDDCR_CPU1_DH51
VDDCR_CPU1_DH50
VDDCR_CPU1_DH48
VDDCR_CPU1_DH47
VDDCR_CPU1_DH45
VDDCR_CPU1_DH57
VDDCR_CPU1_DH56
VDDCR_CPU1_DH54
VDDCR_CPU1_DH53
VDDCR_CPU1_DH44
VDDCR_CPU1_DH42
VDDCR_CPU1_DH41
VDDCR_CPU1_DH35
VDDCR_CPU1_DH34
VDDCR_CPU1_DH32
VDDCR_CPU1_DH31
VDDCR_CPU1_DH29
VDDCR_CPU1_DH28
VDDCR_CPU1_DH26
VDDCR_CPU1_DH25
VDDCR_CPU1_DH23
VDDCR_CPU1_DH22
VDDCR_CPU1_DH20
VDDCR_CPU1_DH19
VDDCR_CPU1_DG57
VDDCR_CPU1_DG19
VDDCR_CPU1_DE54
VDDCR_CPU1_DE51
VDDCR_CPU1_DE48
VDDCR_CPU1_DE45
VDDCR_CPU1_DE42
VDDCR_CPU1_DE41
VDDCR_CPU1_DE35
VDDCR_CPU1_DE34
VDDCR_CPU1_DE31
VDDCR_CPU1_DE28
VDDCR_CPU1_DE25
VDDCR_CPU1_DE22
VDDCR_CPU1_DD54
VDDCR_CPU1_DD51
VDDCR_CPU1_DD48
VDDCR_CPU1_DD45
VDDCR_CPU1_DD42
VDDCR_CPU1_DD34
VDDCR_CPU1_DD31
VDDCR_CPU1_DD28
VDDCR_CPU1_DD25
VDDCR_CPU1_DD22
VDDCR_CPU1_DC41
VDDCR_CPU1_DC40
VDDCR_CPU1_DC36
VDDCR_CPU1_DC35
VDDCR_CPU1_DB53
VDDCR_CPU1_DB52
VDDCR_CPU1_DB50
VDDCR_CPU1_DB49
VDDCR_CPU1_DB47
VDDCR_CPU1_DB46
VDDCR_CPU1_DB44
VDDCR_CPU1_DB43
VDDCR_CPU1_DB33
VDDCR_CPU1_DB32
VDDCR_CPU1_DB30
VDDCR_CPU1_DB29
VDDCR_CPU1_DB27
VDDCR_CPU1_DB26
VDDCR_CPU1_DB24
VDDCR_CPU1_DB23
VDDCR_CPU1_DA41
VDDCR_CPU1_DA40
VDDCR_CPU1_DA36
VDDCR_CPU1_DA35
VDDCR_CPU1_CV53
VDDCR_CPU1_CV52
VDDCR_CPU1_CV50
VDDCR_CPU1_CV49
VDDCR_CPU1_CV47
VDDCR_CPU1_CV46
VDDCR_CPU1_CV44
VDDCR_CPU1_CV43
VDDCR_CPU1_CV33
VDDCR_CPU1_CV32
VDDCR_CPU1_CV30
VDDCR_CPU1_CV29
VDDCR_CPU1_CV27
VDDCR_CPU1_CV26
VDDCR_CPU1_CV24
VDDCR_CPU1_CV23
VDDCR_CPU1_CU41
VDDCR_CPU1_CU40
VDDCR_CPU1_CU36
VDDCR_CPU1_CU35
VDDCR_CPU1_CP53
VDDCR_CPU1_CP52
VDDCR_CPU1_CP50
VDDCR_CPU1_CP49
VDDCR_CPU1_CP47
VDDCR_CPU1_CP46
VDDCR_CPU1_CP44
VDDCR_CPU1_CP43
VDDCR_CPU1_CP33
VDDCR_CPU1_CP32
VDDCR_CPU1_CP30
VDDCR_CPU1_CP29
VDDCR_CPU1_CP27
VDDCR_CPU1_CP26
VDDCR_CPU1_CP24
VDDCR_CPU1_CP23
VDDCR_CPU1_CN41
VDDCR_CPU1_CN40
VDDCR_CPU1_CN36
VDDCR_CPU1_CN35
VDDCR_CPU1_CL47
VDDCR_CPU1_CL46
VDDCR_CPU1_CL44
VDDCR_CPU1_CL43
VDDCR_CPU1_CL33
VDDCR_CPU1_CL32
VDDCR_CPU1_CL30
VDDCR_CPU1_CL29
VDDCR_CPU1_CK41
VDDCR_CPU1_CK40
VDDCR_CPU1_CK36
VDDCR_CPU1_CK35
VDDCR_CPU1_CH53
VDDCR_CPU1_CH52
VDDCR_CPU1_CH50
VDDCR_CPU1_CH49
VDDCR_CPU1_CH47
VDDCR_CPU1_CH46
VDDCR_CPU1_CH44
VDDCR_CPU1_CH43
VDDCR_CPU1_CH33
VDDCR_CPU1_CH32
VDDCR_CPU1_CH30
VDDCR_CPU1_CH29
VDDCR_CPU1_CH27
VDDCR_CPU1_CH26
VDDCR_CPU1_CH24
VDDCR_CPU1_CH23
VDDCR_CPU1_CG41
VDDCR_CPU1_CG40
VDDCR_CPU1_CG36
VDDCR_CPU1_CG35
VDDCR_CPU1_CD53
VDDCR_CPU1_CD52
VDDCR_CPU1_CD50
VDDCR_CPU1_CD49
VDDCR_CPU1_CD47
VDDCR_CPU1_CD46
VDDCR_CPU1_CD44
VDDCR_CPU1_CD43
VDDCR_CPU1_CD33
VDDCR_CPU1_CD32
VDDCR_CPU1_CD30
VDDCR_CPU1_CD29
VDDCR_CPU1_CD27
VDDCR_CPU1_CD26
VDDCR_CPU1_CD24
VDDCR_CPU1_CD23
VDDCR_CPU1_CC41
VDDCR_CPU1_CC40
VDDCR_CPU1_CC36
VDDCR_CPU1_CC35
VDDCR_CPU1_BY53
VDDCR_CPU1_BY52
VDDCR_CPU1_BY50
VDDCR_CPU1_BY49
VDDCR_CPU1_BY47
VDDCR_CPU1_BY46
VDDCR_CPU1_BY44
VDDCR_CPU1_BY43
VDDCR_CPU1_BY33
VDDCR_CPU1_BY32
VDDCR_CPU1_BY30
VDDCR_CPU1_BY29
VDDCR_CPU1_BY27
VDDCR_CPU1_BY26
VDDCR_CPU1_BY24
VDDCR_CPU1_BY23
VDDCR_CPU1_BW41
VDDCR_CPU1_BW40
VDDCR_CPU1_BW36
VDDCR_CPU1_BW35
VDDCR_CPU1_BT53
VDDCR_CPU1_BT52
VDDCR_CPU1_BT50
VDDCR_CPU1_BT49
VDDCR_CPU1_BT47
VDDCR_CPU1_BT46
VDDCR_CPU1_BT44
VDDCR_CPU1_BT43
VDDCR_CPU1_BT33
VDDCR_CPU1_BT32
VDDCR_CPU1_BT30
VDDCR_CPU1_BT29
VDDCR_CPU1_BT27
VDDCR_CPU1_BT26
VDDCR_CPU1_BT24
VDDCR_CPU1_BT23
VDDCR_CPU1_BR52
VDDCR_CPU1_BR50
VDDCR_CPU1_BR48
VDDCR_CPU1_BR46
VDDCR_CPU1_BR44
VDDCR_CPU1_BR42
VDDCR_CPU1_BR40
VDDCR_CPU1_BR35
VDDCR_CPU1_BR33
VDDCR_CPU1_BR31
VDDCR_CPU1_BR29
VDDCR_CPU1_BR27
VDDCR_CPU1_BR25
VDDCR_CPU1_BR23
VDDCR_CPU1_BP49
VDDCR_CPU1_BP47
VDDCR_CPU1_BP45
VDDCR_CPU1_BP43
VDDCR_CPU1_BP41
VDDCR_CPU1_BP39
VDDCR_CPU1_BP36
VDDCR_CPU1_BP34
VDDCR_CPU1_BP30
VDDCR_CPU1_BP26
VDDCR_CPU1_BN50
VDDCR_CPU1_BN42
VDDCR_CPU1_BN31
24/40
VDDCR_CPU0_AU33
VDDCR_CPU0_AU25
VDDCR_CPU0_AU48
VDDCR_CPU0_AU44
VDDCR_CPU0_AU29
VDDCR_CPU0_AT49
VDDCR_CPU0_AU46
VDDCR_CPU0_AU42
VDDCR_CPU0_Y35
VDDCR_CPU0_Y36
VDDCR_CPU0_Y40
VDDCR_CPU0_Y41
VDDCR_CPU0_AB23
VDDCR_CPU0_AB24
VDDCR_CPU0_AB26
VDDCR_CPU0_AB27
VDDCR_CPU0_AB29
VDDCR_CPU0_AB30
VDDCR_CPU0_AB32
VDDCR_CPU0_AB33
VDDCR_CPU0_AB43
VDDCR_CPU0_AB44
VDDCR_CPU0_AB46
VDDCR_CPU0_AB47
VDDCR_CPU0_AB49
VDDCR_CPU0_AB50
VDDCR_CPU0_AB52
VDDCR_CPU0_AB53
VDDCR_CPU0_AC35
VDDCR_CPU0_AC36
VDDCR_CPU0_AC40
VDDCR_CPU0_AC41
VDDCR_CPU0_AF23
VDDCR_CPU0_AF24
VDDCR_CPU0_AF26
VDDCR_CPU0_AF27
VDDCR_CPU0_AF29
VDDCR_CPU0_AF30
VDDCR_CPU0_AF32
VDDCR_CPU0_AF33
VDDCR_CPU0_AF43
VDDCR_CPU0_AF44
VDDCR_CPU0_AF46
VDDCR_CPU0_AF47
VDDCR_CPU0_AF49
VDDCR_CPU0_AF50
VDDCR_CPU0_AF52
VDDCR_CPU0_AF53
VDDCR_CPU0_AG35
VDDCR_CPU0_AG36
VDDCR_CPU0_AG40
VDDCR_CPU0_AG41
VDDCR_CPU0_AK23
VDDCR_CPU0_AK24
VDDCR_CPU0_AK26
VDDCR_CPU0_AK27
VDDCR_CPU0_AK29
VDDCR_CPU0_AK30
VDDCR_CPU0_AK32
VDDCR_CPU0_AK33
VDDCR_CPU0_AK43
VDDCR_CPU0_AK44
VDDCR_CPU0_AK46
VDDCR_CPU0_AK47
VDDCR_CPU0_AK49
VDDCR_CPU0_AK50
VDDCR_CPU0_AK52
VDDCR_CPU0_AK53
VDDCR_CPU0_AL35
VDDCR_CPU0_AL36
VDDCR_CPU0_AL40
VDDCR_CPU0_AL41
VDDCR_CPU0_AP23
VDDCR_CPU0_AP24
VDDCR_CPU0_AP26
VDDCR_CPU0_AP27
VDDCR_CPU0_AP29
VDDCR_CPU0_AP30
VDDCR_CPU0_AP32
VDDCR_CPU0_AP33
VDDCR_CPU0_AP43
VDDCR_CPU0_AP44
VDDCR_CPU0_AP46
VDDCR_CPU0_AP47
VDDCR_CPU0_AP49
VDDCR_CPU0_AP50
VDDCR_CPU0_AP52
VDDCR_CPU0_AP53
VDDCR_CPU0_AR23
VDDCR_CPU0_AR25
VDDCR_CPU0_AR27
VDDCR_CPU0_AR29
VDDCR_CPU0_AR31
VDDCR_CPU0_AR33
VDDCR_CPU0_AR35
VDDCR_CPU0_AR40
VDDCR_CPU0_AR42
VDDCR_CPU0_AR44
VDDCR_CPU0_AR46
VDDCR_CPU0_AR48
VDDCR_CPU0_AR50
VDDCR_CPU0_AT24
VDDCR_CPU0_AT26
VDDCR_CPU0_AT28
VDDCR_CPU0_AT30
VDDCR_CPU0_AT32
VDDCR_CPU0_AT34
VDDCR_CPU0_AT36
VDDCR_CPU0_AT39
VDDCR_CPU0_AT41
VDDCR_CPU0_AT43
VDDCR_CPU0_AT45
VDDCR_CPU0_AT47
VDDCR_CPU0_B19
VDDCR_CPU0_B20
VDDCR_CPU0_B22
VDDCR_CPU0_B23
VDDCR_CPU0_B25
VDDCR_CPU0_B26
VDDCR_CPU0_B28
VDDCR_CPU0_B29
VDDCR_CPU0_B31
VDDCR_CPU0_B32
VDDCR_CPU0_B34
VDDCR_CPU0_B35
VDDCR_CPU0_B41
VDDCR_CPU0_B42
VDDCR_CPU0_B44
VDDCR_CPU0_B45
VDDCR_CPU0_B47
VDDCR_CPU0_B48
VDDCR_CPU0_B50
VDDCR_CPU0_B51
VDDCR_CPU0_B53
VDDCR_CPU0_B54
VDDCR_CPU0_B56
VDDCR_CPU0_B57
VDDCR_CPU0_C20
VDDCR_CPU0_D55
VDDCR_CPU0_D56
VDDCR_CPU0_E22
VDDCR_CPU0_E25
VDDCR_CPU0_E28
VDDCR_CPU0_E31
VDDCR_CPU0_E34
VDDCR_CPU0_E35
VDDCR_CPU0_E42
VDDCR_CPU0_E45
VDDCR_CPU0_E48
VDDCR_CPU0_E51
VDDCR_CPU0_E54
VDDCR_CPU0_F22
VDDCR_CPU0_F25
VDDCR_CPU0_F28
VDDCR_CPU0_F31
VDDCR_CPU0_F34
VDDCR_CPU0_F42
VDDCR_CPU0_F45
VDDCR_CPU0_F48
VDDCR_CPU0_F51
VDDCR_CPU0_F54
VDDCR_CPU0_G35
VDDCR_CPU0_G36
VDDCR_CPU0_G40
VDDCR_CPU0_G41
VDDCR_CPU0_H23
VDDCR_CPU0_H24
VDDCR_CPU0_H26
VDDCR_CPU0_H27
VDDCR_CPU0_H29
VDDCR_CPU0_H30
VDDCR_CPU0_H32
VDDCR_CPU0_H33
VDDCR_CPU0_H43
VDDCR_CPU0_H44
VDDCR_CPU0_H46
VDDCR_CPU0_H47
VDDCR_CPU0_H49
VDDCR_CPU0_H50
VDDCR_CPU0_H52
VDDCR_CPU0_H53
VDDCR_CPU0_J35
VDDCR_CPU0_J36
VDDCR_CPU0_J40
VDDCR_CPU0_J41
VDDCR_CPU0_M23
VDDCR_CPU0_M24
VDDCR_CPU0_M26
VDDCR_CPU0_M27
VDDCR_CPU0_M29
VDDCR_CPU0_M30
VDDCR_CPU0_M32
VDDCR_CPU0_M33
VDDCR_CPU0_M43
VDDCR_CPU0_M44
VDDCR_CPU0_M46
VDDCR_CPU0_M47
VDDCR_CPU0_M49
VDDCR_CPU0_M50
VDDCR_CPU0_M52
VDDCR_CPU0_M53
VDDCR_CPU0_N35
VDDCR_CPU0_N36
VDDCR_CPU0_N40
VDDCR_CPU0_N41
VDDCR_CPU0_T23
VDDCR_CPU0_T24
VDDCR_CPU0_T26
VDDCR_CPU0_T27
VDDCR_CPU0_T29
VDDCR_CPU0_T30
VDDCR_CPU0_T32
VDDCR_CPU0_T33
VDDCR_CPU0_T43
VDDCR_CPU0_T44
VDDCR_CPU0_T46
VDDCR_CPU0_T47
VDDCR_CPU0_T49
VDDCR_CPU0_T50
VDDCR_CPU0_T52
VDDCR_CPU0_T53
VDDCR_CPU0_U35
VDDCR_CPU0_U36
VDDCR_CPU0_U40
VDDCR_CPU0_U41
VDDCR_CPU0_W29
VDDCR_CPU0_W30
VDDCR_CPU0_W32
VDDCR_CPU0_W33
VDDCR_CPU0_W43
VDDCR_CPU0_W44
VDDCR_CPU0_W46
VDDCR_CPU0_W47
1
SHEETDATE
23
7 3 2 16 5 4
E
A
B
C
E
D
C
B
A
7 6 5 4
D
DEPARTMENT
SIZE
PROJECT DOCUMENT NUMBER REV
REVIEWER
DESIGNER
C



Thu Aug 24 14:08:47 2023<NAME_2>
<NAME_1>
MB FABCGTI V02
58 OF 365
S O CK E T6096_13568-001 S O CK E T6096_13568-001 S O CK E T6096_13568-001
S O CK E T6096_13568-001
S O CK E T6096_13568-001
S O CK E T6096_13568-001 IO IO IO
IO
IO
IO
CPU1 VSS 1/3
SMLF SMLF SMLFSMLF SMLFSMLF
T 64
T 61
T 59
T 57
T 54
T 51
T 48
T 45
T 42
T 39
T 37
T 34
T 31
T 28
T 25
T 22
T 19
T 17
T 15
T 12
T 10
T 8
T 5
T 3
R75
R72
R70
R68
R65
R63
R61
R58
R56
R54
R51
R48
R45
R42
R41
R40
R36
R35
R34
R31
R28
R25
R22
R20
R18
R15
R13
R11
R8
R6
R4
R1
P73
P66
P61
P59
P53
P52
P51
P50
P49
P48
P47
P46
P45
P44
P43
P42
P39
P37
P34
P33
P32
P31
P30
P29
P28
P27
P26
P24
P23
P17
P15
P10
P8
P3
N75
N72
N70
N68
N65
N63
N61
N58
N56
N54
N51
N48
N45
N42
N34
N31
N28
N25
N22
N20
N18
N15
N13
N11
N8
N6
N4
N1
M 73
M 71
M 68
M 66
M 64
M 61
M 59
M 57
M 54
M 51
M 48
M 45
M 42
M 39
M 37
M 34
M 31
M 28
M 25
M 22
M 19
M 17
M 15
M 12
M 10
M 8
M 5
M 3
L75
L70
L68
L63
L61
L56
L54
L51
L48
L45
L42
L41
L40
L36
L35
L34
L31
L28
L25
L22
L20
L15
L13
L8
L6
L1
K73
K71
K68
K66
K64
K61
K57
K53
K52
K51
K50
K49
K48
K47
K46
K45
K44
K43
K42
K39
K37
K34
K33
K32
K31
K30
K29
K28
K27
K26
K25
K24
K19
K17
K15
K12
K10
K8
K5
K3
J75
J72
J70
J68
J65
J63
J61
J58
J56
J54
J51
J48
J45
J42
J34
J31
J28
J25
J22
J20
J18
J15
U26
Y73
Y68
Y66
Y61
Y59
Y54
Y53
Y52
Y51
Y50
Y49
Y48
Y45
Y44
Y43
Y42
Y39
Y37
Y34
Y33
Y32
Y31
Y28
Y27
Y26
Y25
Y24
Y23
Y22
Y17
Y15
Y10
Y8
Y3
W75
W72
W70
W68
W65
W63
W61
W58
W56
W54
W51
W48
W45
W42
W41
W40
W36
W35
W34
W28
W25
W22
W20
W18
W15
W13
W11
W8
W6
W4
W1
V73
V71
V66
V64
V61
V59
V57
V53
V52
V51
V50
V49
V48
V47
V46
V45
V44
V43
V42
V39
V37
V34
V33
V32
V31
V30
V29
V28
V26
V25
V24
V23
V19
V17
V15
V12
V10
V8
V5
V3
U75
U70
U68
U63
U61
U56
U54
U51
U48
U45
U42
U34
U31
U28
U25
U22
U20
U15
U13
U8
U6
U1
T 73
T 71
T 68
T 66
AD48
AD47
AD46
AD45
AD44
AD43
AD42
AD39
AD37
AD34
AD33
AD32
AD30
AD29
AD28
AD27
AD26
AD25
AD24
AD23
AD19
AD17
AD15
AD12
AD10
AD8
AD5
AD3
AC75
AC70
AC68
AC63
AC61
AC56
AC54
AC51
AC48
AC45
AC42
AC34
AC31
AC28
AC25
AC22
AC20
AC15
AC13
AC8
AC6
AC1
AB73
AB71
AB68
AB66
AB64
AB61
AB59
AB57
AB54
AB51
AB48
AB45
AB42
AB39
AB37
AB34
AB31
AB28
AB25
AB22
AB19
AB17
AB15
AB12
AB10
AB8
AB5
AB3
AA75
AA70
AA68
AA65
AA63
AA61
AA58
AA56
AA45
AA41
AA40
AA36
AA35
AA34
AA31
AA20
AA18
AA15
AA13
AA11
AA8
AA6
AA4
AA1
U26
AM 39
AM 34
AM 33
AM 32
AM 31
AM 30
AM 29
AM 28
AM 27
AM 26
AM 25
AM 24
AM 23
AM 17
AM 15
AM 10
AM 8
AM 3
AL75
AL72
AL70
AL68
AL65
AL63
AL61
AL58
AL56
AL54
AL51
AL48
AL45
AL42
AL34
AL31
AL28
AL25
AL22
AL20
AL18
AL15
AL13
AL11
AL8
AL6
AL4
AL1
AK73
AK71
AK68
AK66
AK64
AK61
AK59
AK57
AK54
AK51
AK48
AK45
AK42
AK39
AK37
AK34
AK31
AK28
AK25
AK22
AK19
AK17
AK15
AK12
AK10
AK8
AK5
AK3
AJ75
AJ70
AJ68
AJ63
AJ61
AJ56
AJ54
AJ51
AJ48
AJ45
AJ42
AJ41
AJ40
AJ36
AJ35
AJ34
AJ31
AJ28
AJ25
AJ22
AJ20
AJ15
AJ8
AJ6
AJ1
AH73
AH71
AH68
AH66
AH64
AH61
AH59
AH57
AH53
AH52
AH51
AH50
AH49
AH48
AH47
AH46
AH45
AH44
AH43
AH42
AH39
AH37
AH34
AH32
AH31
AH30
AH29
AH28
AH27
AH26
AH25
AH24
AH23
AH19
AH17
AH15
AH12
AH10
AH8
AH5
AH3
AG75
AG72
AG70
AG68
AG65
AG63
AG61
AG58
AG56
AG54
AG51
AG48
AG45
AG42
AG34
AG31
AG28
AG25
AG22
AG20
AG18
AG15
AG13
AG11
AG8
AG6
AG4
AG1
AF73
AF68
AF66
AF61
AF59
AF54
AF51
AF48
AF45
AF42
AF39
AF37
AF34
AF31
AF28
AF25
AF22
AF17
AF15
AF10
AF8
AF3
AE75
AE72
AE70
AE68
AE65
AE63
AE61
AE58
AE56
AE54
AE51
AE48
AE45
AE42
AE41
AE40
AE36
AE35
AE34
AE31
AE28
AE25
AE22
AE20
AE18
AE15
AE13
AE11
AE8
AE6
AE1
AD73
AD71
AD68
AD66
AD64
AD61
AD59
AD57
AD53
AD52
AD51
AD50
AD49
U26
AW61
AW58
AW56
AW53
AW51
AW49
AW28
AW26
AW24
AW22
AW20
AW18
AW15
AW13
AW11
AW8
AW6
AW4
AW1
AV73
AV68
AV66
AV61
AV59
AV54
AV52
AV50
AV48
AV46
AV44
AV42
AV40
AV37
AV35
AV33
AV31
AV29
AV27
AV25
AV23
AV17
AV15
AV10
AV8
AV3
AU75
AU73
AU72
AU70
AU68
AU65
AU63
AU61
AU58
AU56
AU53
AU51
AU49
AU47
AU45
AU43
AU41
AU36
AU34
AU32
AU30
AU28
AU26
AU24
AU22
AU20
AU18
AU15
AU13
AU11
AU8
AU6
AU4
AU3
AU1
AT 73
AT 72
AT 71
AT 70
AT 68
AT 67
AT 66
AT 64
AT 63
AT 61
AT 60
AT 59
AT 57
AT 56
AT 54
AT 52
AT 50
AT 48
AT 46
AT 44
AT 42
AT 40
AT 37
AT 35
AT 33
AT 31
AT 29
AT 27
AT 25
AT 23
AT 20
AT 19
AT 17
AT 16
AT 15
AT 13
AT 12
AT 10
AT 9
AT 8
AT 6
AT 5
AT 4
AT 3
AR75
AR71
AR70
AR68
AR67
AR64
AR63
AR61
AR60
AR57
AR56
AR53
AR51
AR49
AR47
AR45
AR43
AR41
AR36
AR34
AR32
AR30
AR28
AR26
AR24
AR22
AR20
AR19
AR16
AR15
AR13
AR12
AR9
AR8
AR6
AR5
AR1
AP73
AP71
AP68
AP66
AP64
AP61
AP59
AP57
AP54
AP51
AP48
AP45
AP42
AP39
AP37
AP34
AP31
AP28
AP25
AP22
AP19
AP17
AP15
AP12
AP10
AP8
AP5
AP3
AN75
AN72
AN70
AN68
AN65
AN63
AN61
AN58
AN56
AN54
AN51
AN48
AN45
AN42
AN41
AN40
AN36
AN35
AN34
AN31
AN28
AN25
AN22
AN18
AN15
AN13
AN11
AN8
AN6
AN4
AN1
AM 73
AM 68
AM 66
AM 61
AM 59
AM 53
AM 52
AM 51
AM 50
AM 49
AM 48
AM 47
AM 46
AM 45
AM 44
AM 43
AM 42
U26
BL24
BL22
BL20
BL18
BL15
BL13
BL11
BL8
BL6
BL4
BL1
BK73
BK71
BK68
BK66
BK64
BK61
BK59
BK57
BK54
BK52
BK50
BK48
BK27
BK25
BK23
BK19
BK17
BK15
BK12
BK10
BK8
BK5
BK3
BJ75
BJ70
BJ68
BJ63
BJ61
BJ56
BJ53
BJ51
BJ49
BJ28
BJ26
BJ24
BJ22
BJ20
BJ15
BJ13
BJ8
BJ6
BJ1
BH73
BH71
BH68
BH66
BH64
BH61
BH59
BH57
BH54
BH52
BH50
BH49
BH28
BH26
BH24
BH22
BH19
BH17
BH15
BH12
BH10
BH8
BH5
BH3
BG75
BG72
BG70
BG68
BG65
BG63
BG61
BG58
BG56
BG53
BG51
BG49
BG27
BG25
BG23
BG20
BG18
BG15
BG13
BG11
BG8
BG6
BG4
BG1
BF73
BF68
BF66
BF61
BF59
BF54
BF52
BF50
BF49
BF28
BF26
BF24
BF22
BF19
BF17
BF15
BF12
BF10
BF8
BF5
BF3
BD73
BD71
BD68
BD66
BD64
BD61
BD59
BD57
BD53
BD51
BD49
BD27
BD25
BD23
BD17
BD15
BD10
BD8
BD3
BC75
BC72
BC70
BC68
BC65
BC63
BC61
BC58
BC56
BC53
BC51
BC50
BC49
BC28
BC26
BC24
BC22
BC20
BC18
BC15
BC13
BC11
BC8
BC6
BC4
BC1
BB73
BB71
BB68
BB66
BB64
BB61
BB59
BB57
BB54
BB52
BB50
BB48
BB27
BB25
BB23
BB19
BB17
BB15
BB12
BB10
BB8
BB5
BB3
BA75
BA70
BA68
BA63
BA61
BA56
BA53
BA51
BA49
BA28
BA26
BA24
BA22
BA20
BA15
BA13
BA8
BA6
BA1
AY73
AY71
AY68
AY66
AY64
AY61
AY59
AY57
AY54
AY52
AY50
AY48
AY27
AY25
AY23
AY19
AY17
AY15
AY12
AY10
AY8
AY5
AY3
AW75
AW72
AW70
AW68
AW65
AW63
U26
J13
J11
J8
J6
J4
J1
H73
H68
H66
H61
H59
H54
H51
H48
H45
H42
H39
H37
H34
H31
H28
H25
H22
H17
H15
H10
H8
H3
G75
G72
G70
G68
G65
G63
G61
G58
G56
G54
G51
G48
G45
G42
G34
G31
G28
G25
G22
G20
G18
G15
G13
G11
G8
G6
G4
G1
F73
F71
F68
F66
F64
F61
F59
F57
F53
F52
F50
F49
F47
F46
F44
F43
F41
F40
F39
F37
F36
F35
F33
F32
F30
F29
F27
F26
F24
F23
F19
F17
F15
F12
F10
F8
F5
F3
E75
E73
E72
E70
E69
E68
E66
E65
E63
E62
E61
E59
E58
E56
E55
E53
E52
E21
E20
E18
E17
E15
E14
E13
E10
E8
E7
E6
E3
E1
D74
D73
D71
D70
D67
D66
D64
D63
D61
D60
D59
D57
D54
D53
D52
D51
D50
D49
D48
D47
D46
D45
D44
D43
D42
D41
D40
D39
D37
D35
D31
D30
D29
D28
D27
D26
D25
D24
D21
D20
D19
D17
D16
D13
D12
D10
D9
D6
D5
D3
D2
C75
C73
C71
C69
C67
C64
C61
C57
C56
C55
C52
C49
C46
C43
C40
C36
C30
C27
C24
C21
C15
C13
C11
C10
C8
C5
C1
B70
B68
B65
B62
B59
B55
B52
B49
B46
B43
B39
B37
B33
B30
B27
B24
B18
B13
B11
B10
B8
B7
A73
A72
A67
A61
A53
A49
A47
A44
A43
A27
A21
A15
A9
A3
U26
31/40
VSS_AK8
VSS_AK5
VSS_AK3
VSS_AJ75
VSS_AJ70
VSS_AJ68
VSS_AJ63
VSS_AJ61
VSS_AJ56
VSS_AJ54
VSS_AJ51
VSS_AJ48
VSS_AJ45
VSS_AJ42
VSS_AJ41
VSS_AJ40
VSS_AJ36
VSS_AJ35
VSS_AJ34
VSS_AJ31
VSS_AJ28
VSS_AJ25
VSS_AJ22
VSS_AJ20
VSS_AJ15
VSS_AJ8
VSS_AJ6
VSS_AJ1
VSS_AH73
VSS_AH71
VSS_AH68
VSS_AH66
VSS_AH64
VSS_AH61
VSS_AH59
VSS_AH57
VSS_AH53
VSS_AH52
VSS_AH51
VSS_AH50
VSS_AH49
VSS_AH48
VSS_AH47
VSS_AH46
VSS_AH45
VSS_AH44
VSS_AH43
VSS_AH42
VSS_AH39
VSS_AH37
VSS_AH34
VSS_AH32
VSS_AH31
VSS_AH30
VSS_AH29
VSS_AH28
VSS_AH27
VSS_AH26
VSS_AH25
VSS_AH24
VSS_AH23
VSS_AH19
VSS_AH17
VSS_AH15
VSS_AH12
VSS_AH10
VSS_AH8
VSS_AH5
VSS_AH3
VSS_AG75
VSS_AG72
VSS_AG70
VSS_AG68
VSS_AG65
VSS_AG63
VSS_AG61
VSS_AG58
VSS_AG56
VSS_AG54
VSS_AG51
VSS_AG48
VSS_AG45
VSS_AG42
VSS_AG34
VSS_AG31
VSS_AG28
VSS_AG25
VSS_AG22
VSS_AG20
VSS_AG18
VSS_AG15
VSS_AG13
VSS_AG11
VSS_AG8
VSS_AG6
VSS_AG4
VSS_AG1
VSS_AF73
VSS_AF68
VSS_AF66
VSS_AF61
VSS_AF59
VSS_AF54
VSS_AF51
VSS_AF48
VSS_AF45
VSS_AF42
VSS_AF39
VSS_AF37
VSS_AF34
VSS_AF31
VSS_AF28
VSS_AF25
VSS_AF22
VSS_AF17
VSS_AF15
VSS_AF10
VSS_AF8
VSS_AF3
VSS_AE75
VSS_AE72
VSS_AE70
VSS_AE68
VSS_AE65
VSS_AE63
VSS_AE61
VSS_AE58
VSS_AE56
VSS_AE54
VSS_AE51
VSS_AE48
VSS_AE45
VSS_AE42
VSS_AE41
VSS_AE40
VSS_AE36
VSS_AE35
VSS_AE34
VSS_AE31
VSS_AE28
VSS_AE25
VSS_AE22
VSS_AE20
VSS_AE18
VSS_AE15
VSS_AE13
VSS_AE11
VSS_AE8
VSS_AE6
VSS_AE1
VSS_AD73
VSS_AD71
VSS_AD68
VSS_AD66
VSS_AD64
VSS_AD61
VSS_AD59
VSS_AD57
VSS_AD53
VSS_AD52
VSS_AD51
VSS_AD50
VSS_AD49
VSS_AM39
VSS_AM34
VSS_AM33
VSS_AM32
VSS_AM31
VSS_AM30
VSS_AM29
VSS_AM28
VSS_AM27
VSS_AM26
VSS_AM25
VSS_AM24
VSS_AM23
VSS_AM17
VSS_AM15
VSS_AM10
VSS_AM8
VSS_AM3
VSS_AL75
VSS_AL72
VSS_AL70
VSS_AL68
VSS_AL65
VSS_AL63
VSS_AL61
VSS_AL58
VSS_AL56
VSS_AL54
VSS_AL51
VSS_AL48
VSS_AL45
VSS_AL42
VSS_AL34
VSS_AL31
VSS_AL28
VSS_AL25
VSS_AL22
VSS_AL20
VSS_AL18
VSS_AL15
VSS_AL13
VSS_AL11
VSS_AL8
VSS_AL6
VSS_AL4
VSS_AL1
VSS_AK73
VSS_AK71
VSS_AK68
VSS_AK66
VSS_AK64
VSS_AK61
VSS_AK59
VSS_AK57
VSS_AK54
VSS_AK51
VSS_AK48
VSS_AK45
VSS_AK42
VSS_AK39
VSS_AK37
VSS_AK34
VSS_AK31
VSS_AK28
VSS_AK25
VSS_AK22
VSS_AK19
VSS_AK17
VSS_AK15
VSS_AK12
VSS_AK10
32/40
VSS_AW61
VSS_AW58
VSS_AW56
VSS_AW53
VSS_AW51
VSS_AW49
VSS_AW28
VSS_AW26
VSS_AW24
VSS_AW22
VSS_AW20
VSS_AW18
VSS_AW15
VSS_AW13
VSS_AW11
VSS_AW8
VSS_AW6
VSS_AW4
VSS_AW1
VSS_AV73
VSS_AV68
VSS_AV66
VSS_AV61
VSS_AV59
VSS_AV54
VSS_AV52
VSS_AV50
VSS_AV48
VSS_AV46
VSS_AV44
VSS_AV42
VSS_AV40
VSS_AV37
VSS_AV35
VSS_AV33
VSS_AV31
VSS_AV29
VSS_AV27
VSS_AV25
VSS_AV23
VSS_AV17
VSS_AV15
VSS_AV10
VSS_AV8
VSS_AV3
VSS_AU75
VSS_AU73
VSS_AU72
VSS_AU70
VSS_AU68
VSS_AU65
VSS_AU63
VSS_AU61
VSS_AU58
VSS_AU56
VSS_AU53
VSS_AU51
VSS_AU49
VSS_AU47
VSS_AU45
VSS_AU43
VSS_AU41
VSS_AU36
VSS_AU34
VSS_AU32
VSS_AU30
VSS_AU28
VSS_AU26
VSS_AU24
VSS_AU22
VSS_AU20
VSS_AU18
VSS_AU15
VSS_AU13
VSS_AU11
VSS_AU8
VSS_AU6
VSS_AU4
VSS_AU3
VSS_AU1
VSS_AT73
VSS_AT72
VSS_AT71
VSS_AT70
VSS_AT68
VSS_AT67
VSS_AT66
VSS_AT64
VSS_AT63
VSS_AT61
VSS_AT60
VSS_AT59
VSS_AT57
VSS_AT56
VSS_AT54
VSS_AT52
VSS_AT50
VSS_AT48
VSS_AT46
VSS_AT44
VSS_AT42
VSS_AT40
VSS_AT37
VSS_AT35
VSS_AT33
VSS_AT31
VSS_AT29
VSS_AT27
VSS_AT25
VSS_AT23
VSS_AT20
VSS_AT19
VSS_AT17
VSS_AT16
VSS_AT15
VSS_AT13
VSS_AT12
VSS_AT10
VSS_AT9
VSS_AT8
VSS_AT6
VSS_AT5
VSS_AT4
VSS_AT3
VSS_AR75
VSS_AR71
VSS_AR70
VSS_AR68
VSS_AR67
VSS_AR64
VSS_AR63
VSS_AR61
VSS_AR60
VSS_AR57
VSS_AR56
VSS_AR53
VSS_AR51
VSS_AR49
VSS_AR47
VSS_AR45
VSS_AR43
VSS_AR41
VSS_AR36
VSS_AR34
VSS_AR32
VSS_AR30
VSS_AR28
VSS_AR26
VSS_AR24
VSS_AR22
VSS_AR20
VSS_AR19
VSS_AR16
VSS_AR15
VSS_AR13
VSS_AR12
VSS_AR9
VSS_AR8
VSS_AR6
VSS_AR5
VSS_AR1
VSS_AP73
VSS_AP71
VSS_AP68
VSS_AP66
VSS_AP64
VSS_AP61
VSS_AP59
VSS_AP57
VSS_AP54
VSS_AP51
VSS_AP48
VSS_AP45
VSS_AP42
VSS_AP39
VSS_AP37
VSS_AP34
VSS_AP31
VSS_AP28
VSS_AP25
VSS_AP22
VSS_AP19
VSS_AP17
VSS_AP15
VSS_AP12
VSS_AP10
VSS_AP8
VSS_AP5
VSS_AP3
VSS_AN75
VSS_AN72
VSS_AN70
VSS_AN68
VSS_AN65
VSS_AN63
VSS_AN61
VSS_AN58
VSS_AN56
VSS_AN54
VSS_AN51
VSS_AN48
VSS_AN45
VSS_AN42
VSS_AN41
VSS_AN40
VSS_AN36
VSS_AN35
VSS_AN34
VSS_AN31
VSS_AN28
VSS_AN25
VSS_AN22
VSS_AN18
VSS_AN15
VSS_AN13
VSS_AN11
VSS_AN8
VSS_AN6
VSS_AN4
VSS_AN1
VSS_AM73
VSS_AM68
VSS_AM66
VSS_AM61
VSS_AM59
VSS_AM53
VSS_AM52
VSS_AM51
VSS_AM50
VSS_AM49
VSS_AM48
VSS_AM47
VSS_AM46
VSS_AM45
VSS_AM44
VSS_AM43
VSS_AM42
33/40
VSS_BL24
VSS_BL22
VSS_BL20
VSS_BL18
VSS_BL15
VSS_BL13
VSS_BL11
VSS_BL8
VSS_BL6
VSS_BL4
VSS_BL1
VSS_BK73
VSS_BK71
VSS_BK68
VSS_BK66
VSS_BK64
VSS_BK61
VSS_BK59
VSS_BK57
VSS_BK54
VSS_BK52
VSS_BK50
VSS_BK48
VSS_BK27
VSS_BK25
VSS_BK23
VSS_BK19
VSS_BK17
VSS_BK15
VSS_BK12
VSS_BK10
VSS_BK8
VSS_BK5
VSS_BK3
VSS_BJ75
VSS_BJ70
VSS_BJ68
VSS_BJ63
VSS_BJ61
VSS_BJ56
VSS_BJ53
VSS_BJ51
VSS_BJ49
VSS_BJ28
VSS_BJ26
VSS_BJ24
VSS_BJ22
VSS_BJ20
VSS_BJ15
VSS_BJ13
VSS_BJ8
VSS_BJ6
VSS_BJ1
VSS_BH73
VSS_BH71
VSS_BH68
VSS_BH66
VSS_BH64
VSS_BH61
VSS_BH59
VSS_BH57
VSS_BH54
VSS_BH52
VSS_BH50
VSS_BH49
VSS_BH28
VSS_BH26
VSS_BH24
VSS_BH22
VSS_BH19
VSS_BH17
VSS_BH15
VSS_BH12
VSS_BH10
VSS_BH8
VSS_BH5
VSS_BH3
VSS_BG75
VSS_BG72
VSS_BG70
VSS_BG68
VSS_BG65
VSS_BG63
VSS_BG61
VSS_BG58
VSS_BG56
VSS_BG53
VSS_BG51
VSS_BG49
VSS_BG27
VSS_BG25
VSS_BG23
VSS_BG20
VSS_BG18
VSS_BG15
VSS_BG13
VSS_BG11
VSS_BG8
VSS_BG6
VSS_BG4
VSS_BG1
VSS_BF73
VSS_BF68
VSS_BF66
VSS_BF61
VSS_BF59
VSS_BF54
VSS_BF52
VSS_BF50
VSS_BF49
VSS_BF28
VSS_BF26
VSS_BF24
VSS_BF22
VSS_BF19
VSS_BF17
VSS_BF15
VSS_BF12
VSS_BF10
VSS_BF8
VSS_BF5
VSS_BF3
VSS_BD73
VSS_BD71
VSS_BD68
VSS_BD66
VSS_BD64
VSS_BD61
VSS_BD59
VSS_BD57
VSS_BD53
VSS_BD51
VSS_BD49
VSS_BD27
VSS_BD25
VSS_BD23
VSS_BD17
VSS_BD15
VSS_BD10
VSS_BD8
VSS_BD3
VSS_BC75
VSS_BC72
VSS_BC70
VSS_BC68
VSS_BC65
VSS_BC63
VSS_BC61
VSS_BC58
VSS_BC56
VSS_BC53
VSS_BC51
VSS_BC50
VSS_BC49
VSS_BC28
VSS_BC26
VSS_BC24
VSS_BC22
VSS_BC20
VSS_BC18
VSS_BC15
VSS_BC13
VSS_BC11
VSS_BC8
VSS_BC6
VSS_BC4
VSS_BC1
VSS_BB73
VSS_BB71
VSS_BB68
VSS_BB66
VSS_BB64
VSS_BB61
VSS_BB59
VSS_BB57
VSS_BB54
VSS_BB52
VSS_BB50
VSS_BB48
VSS_BB27
VSS_BB25
VSS_BB23
VSS_BB19
VSS_BB17
VSS_BB15
VSS_BB12
VSS_BB10
VSS_BB8
VSS_BB5
VSS_BB3
VSS_BA75
VSS_BA70
VSS_BA68
VSS_BA63
VSS_BA61
VSS_BA56
VSS_BA53
VSS_BA51
VSS_BA49
VSS_BA28
VSS_BA26
VSS_BA24
VSS_BA22
VSS_BA20
VSS_BA15
VSS_BA13
VSS_BA8
VSS_BA6
VSS_BA1
VSS_AY73
VSS_AY71
VSS_AY68
VSS_AY66
VSS_AY64
VSS_AY61
VSS_AY59
VSS_AY57
VSS_AY54
VSS_AY52
VSS_AY50
VSS_AY48
VSS_AY27
VSS_AY25
VSS_AY23
VSS_AY19
VSS_AY17
VSS_AY15
VSS_AY12
VSS_AY10
VSS_AY8
VSS_AY5
VSS_AY3
VSS_AW75
VSS_AW72
VSS_AW70
VSS_AW68
VSS_AW65
VSS_AW6329/40
VSS_R45
VSS_R42
VSS_R41
VSS_R40
VSS_R36
VSS_R35
VSS_R34
VSS_R31
VSS_R28
VSS_R25
VSS_R22
VSS_R20
VSS_R18
VSS_R15
VSS_R13
VSS_R11
VSS_R8
VSS_R6
VSS_R4
VSS_R1
VSS_P73
VSS_P66
VSS_P61
VSS_P59
VSS_P53
VSS_P52
VSS_P51
VSS_P50
VSS_P49
VSS_P48
VSS_P47
VSS_P46
VSS_P45
VSS_P44
VSS_P43
VSS_P42
VSS_P39
VSS_P37
VSS_P34
VSS_P33
VSS_P32
VSS_P31
VSS_P30
VSS_P29
VSS_P28
VSS_P27
VSS_P26
VSS_P24
VSS_P23
VSS_P17
VSS_P15
VSS_P10
VSS_P8
VSS_P3
VSS_N75
VSS_N72
VSS_N70
VSS_N68
VSS_N65
VSS_N63
VSS_N61
VSS_N58
VSS_N56
VSS_N54
VSS_N51
VSS_N48
VSS_N45
VSS_N42
VSS_N34
VSS_N31
VSS_N28
VSS_N25
VSS_N22
VSS_N20
VSS_N18
VSS_N15
VSS_N13
VSS_N11
VSS_N8
VSS_N6
VSS_N4
VSS_N1
VSS_M73
VSS_M71
VSS_M68
VSS_M66
VSS_M64
VSS_M61
VSS_M59
VSS_M57
VSS_M54
VSS_M51
VSS_M48
VSS_M45
VSS_M42
VSS_M39
VSS_M37
VSS_M34
VSS_M31
VSS_M28
VSS_M25
VSS_M22
VSS_M19
VSS_M17
VSS_M15
VSS_M12
VSS_M10
VSS_M8
VSS_M5
VSS_M3
VSS_L75
VSS_L70
VSS_L68
VSS_L63
VSS_L61
VSS_L56
VSS_L54
VSS_L51
VSS_L48
VSS_L45
VSS_L42
VSS_L41
VSS_L40
VSS_L36
VSS_L35
VSS_L34
VSS_L31
VSS_L28
VSS_L25
VSS_L22
VSS_L20
VSS_L15
VSS_L13
VSS_L8
VSS_L6
VSS_L1
VSS_K73
VSS_K71
VSS_K68
VSS_K66
VSS_K64
VSS_K61
VSS_K57
VSS_K53
VSS_K52
VSS_K51
VSS_K50
VSS_K49
VSS_K48
VSS_K47
VSS_K46
VSS_K45
VSS_K44
VSS_K43
VSS_K42
VSS_K39
VSS_K37
VSS_K34
VSS_K33
VSS_K32
VSS_K31
VSS_K30
VSS_K29
VSS_K28
VSS_K27
VSS_K26
VSS_K25
VSS_K24
VSS_K19
VSS_K17
VSS_K15
VSS_K12
VSS_K10
VSS_K8
VSS_K5
VSS_K3
VSS_J75
VSS_J72
VSS_J70
VSS_J68
VSS_J65
VSS_J63
VSS_J61
VSS_J58
VSS_J56
VSS_J54
VSS_J51
VSS_J48
VSS_J45
VSS_J42
VSS_J34
VSS_J31
VSS_J28
VSS_J25
VSS_J22
VSS_J20
VSS_J18
VSS_J15
VSS_T64
VSS_T61
VSS_T59
VSS_T57
VSS_T54
VSS_T51
VSS_T48
VSS_T45
VSS_T42
VSS_T39
VSS_T37
VSS_T34
VSS_T31
VSS_T28
VSS_T25
VSS_T22
VSS_T19
VSS_T17
VSS_T15
VSS_T12
VSS_T10
VSS_T8
VSS_T5
VSS_T3
VSS_R75
VSS_R72
VSS_R70
VSS_R68
VSS_R65
VSS_R63
VSS_R61
VSS_R58
VSS_R56
VSS_R54
VSS_R51
VSS_R48
30/40
VSS_AB66
VSS_AB64
VSS_AB61
VSS_AB59
VSS_AB57
VSS_AB54
VSS_AB51
VSS_AB48
VSS_AB45
VSS_AB42
VSS_AB39
VSS_AB37
VSS_AB34
VSS_AB31
VSS_AB28
VSS_AB25
VSS_AB22
VSS_AB19
VSS_AB17
VSS_AB15
VSS_AB12
VSS_AB10
VSS_AB8
VSS_AB5
VSS_AB3
VSS_AA75
VSS_AA70
VSS_AA68
VSS_AA65
VSS_AA63
VSS_AA61
VSS_AA58
VSS_AA56
VSS_AA45
VSS_AA41
VSS_AA40
VSS_AA36
VSS_AA35
VSS_AA34
VSS_AA31
VSS_AA20
VSS_AA18
VSS_AA15
VSS_AA13
VSS_AA11
VSS_AA8
VSS_AA6
VSS_AA4
VSS_AA1
VSS_Y73
VSS_Y68
VSS_Y66
VSS_Y61
VSS_Y59
VSS_Y54
VSS_Y53
VSS_Y52
VSS_Y51
VSS_Y50
VSS_Y49
VSS_Y48
VSS_Y45
VSS_Y44
VSS_Y43
VSS_Y42
VSS_Y39
VSS_Y37
VSS_Y34
VSS_Y33
VSS_Y32
VSS_Y31
VSS_Y28
VSS_Y27
VSS_Y26
VSS_Y25
VSS_Y24
VSS_Y23
VSS_Y22
VSS_Y17
VSS_Y15
VSS_Y10
VSS_Y8
VSS_Y3
VSS_W75
VSS_W72
VSS_W70
VSS_W68
VSS_W65
VSS_W63
VSS_W61
VSS_W58
VSS_W56
VSS_W54
VSS_W51
VSS_W48
VSS_W45
VSS_W42
VSS_W41
VSS_W40
VSS_W36
VSS_W35
VSS_W34
VSS_W28
VSS_W25
VSS_W22
VSS_W20
VSS_W18
VSS_W15
VSS_W13
VSS_W11
VSS_W8
VSS_W6
VSS_W4
VSS_W1
VSS_V73
VSS_V71
VSS_V66
VSS_V64
VSS_V61
VSS_V59
VSS_V57
VSS_V53
VSS_V52
VSS_V51
VSS_V50
VSS_V49
VSS_V48
VSS_V47
VSS_V46
VSS_V45
VSS_V44
VSS_V43
VSS_V42
VSS_V39
VSS_V37
VSS_V34
VSS_V33
VSS_V32
VSS_V31
VSS_V30
VSS_V29
VSS_V28
VSS_V26
VSS_V25
VSS_V24
VSS_V23
VSS_V19
VSS_V17
VSS_V15
VSS_V12
VSS_V10
VSS_V8
VSS_V5
VSS_V3
VSS_U75
VSS_U70
VSS_U68
VSS_U63
VSS_U61
VSS_U56
VSS_U54
VSS_U51
VSS_U48
VSS_U45
VSS_U42
VSS_U34
VSS_U31
VSS_U28
VSS_U25
VSS_U22
VSS_U20
VSS_U15
VSS_U13
VSS_U8
VSS_U6
VSS_U1
VSS_T73
VSS_T71
VSS_T68
VSS_T66
VSS_AD48
VSS_AD47
VSS_AD46
VSS_AD45
VSS_AD44
VSS_AD43
VSS_AD42
VSS_AD39
VSS_AD37
VSS_AD34
VSS_AD33
VSS_AD32
VSS_AD30
VSS_AD29
VSS_AD28
VSS_AD27
VSS_AD26
VSS_AD25
VSS_AD24
VSS_AD23
VSS_AD19
VSS_AD17
VSS_AD15
VSS_AD12
VSS_AD10
VSS_AD8
VSS_AD5
VSS_AD3
VSS_AC75
VSS_AC70
VSS_AC68
VSS_AC63
VSS_AC61
VSS_AC56
VSS_AC54
VSS_AC51
VSS_AC48
VSS_AC45
VSS_AC42
VSS_AC34
VSS_AC31
VSS_AC28
VSS_AC25
VSS_AC22
VSS_AC20
VSS_AC15
VSS_AC13
VSS_AC8
VSS_AC6
VSS_AC1
VSS_AB73
VSS_AB71
VSS_AB68
28/40
VSS_H34
VSS_H31
VSS_H28
VSS_H25
VSS_H22
VSS_H17
VSS_H15
VSS_H10
VSS_H8
VSS_H3
VSS_G75
VSS_G72
VSS_G70
VSS_G68
VSS_G65
VSS_G63
VSS_G61
VSS_G58
VSS_G56
VSS_G54
VSS_G51
VSS_G48
VSS_G45
VSS_G42
VSS_G34
VSS_G31
VSS_G28
VSS_G25
VSS_G22
VSS_G20
VSS_G18
VSS_G15
VSS_G13
VSS_G11
VSS_G8
VSS_G6
VSS_G4
VSS_G1
VSS_F73
VSS_F71
VSS_F68
VSS_F66
VSS_F64
VSS_F61
VSS_F59
VSS_F57
VSS_F53
VSS_F52
VSS_F50
VSS_F49
VSS_F47
VSS_F46
VSS_F44
VSS_F43
VSS_F41
VSS_F40
VSS_F39
VSS_F37
VSS_F36
VSS_F35
VSS_F33
VSS_F32
VSS_F30
VSS_F29
VSS_F27
VSS_F26
VSS_F24
VSS_F23
VSS_F19
VSS_F17
VSS_F15
VSS_F12
VSS_F10
VSS_F8
VSS_F5
VSS_F3
VSS_E75
VSS_E73
VSS_E72
VSS_E70
VSS_E69
VSS_E68
VSS_E66
VSS_E65
VSS_E63
VSS_E62
VSS_E61
VSS_E59
VSS_E58
VSS_E56
VSS_E55
VSS_E53
VSS_E52
VSS_E21
VSS_E20
VSS_E18
VSS_E17
VSS_E15
VSS_E14
VSS_E13
VSS_E10
VSS_E8
VSS_E7
VSS_E6
VSS_E3
VSS_E1
VSS_D74
VSS_D73
VSS_D71
VSS_D70
VSS_D67
VSS_D66
VSS_D64
VSS_D63
VSS_D61
VSS_D60
VSS_D59
VSS_D57
VSS_D54
VSS_D53
VSS_D52
VSS_D51
VSS_D50
VSS_D49
VSS_D48
VSS_D47
VSS_D46
VSS_D45
VSS_D44
VSS_D43
VSS_D42
VSS_D41
VSS_D40
VSS_D39
VSS_D37
VSS_D35
VSS_D31
VSS_D30
VSS_D29
VSS_D28
VSS_D27
VSS_D26
VSS_D25
VSS_D24
VSS_D21
VSS_D20
VSS_D19
VSS_D17
VSS_D16
VSS_D13
VSS_D12
VSS_D10
VSS_D9
VSS_D6
VSS_D5
VSS_D3
VSS_D2
VSS_C75
VSS_C73
VSS_C71
VSS_C69
VSS_C67
VSS_C64
VSS_C61
VSS_C57
VSS_C56
VSS_C55
VSS_C52
VSS_C49
VSS_C46
VSS_C43
VSS_C40
VSS_C36
VSS_C30
VSS_C27
VSS_C24
VSS_C21
VSS_C15
VSS_C13
VSS_C11
VSS_C10
VSS_C8
VSS_C5
VSS_C1
VSS_B70
VSS_B68
VSS_B65
VSS_B62
VSS_B59
VSS_B55
VSS_B52
VSS_B49
VSS_B46
VSS_B43
VSS_B39
VSS_B37
VSS_B33
VSS_B30
VSS_B27
VSS_B24
VSS_B18
VSS_B13
VSS_B11
VSS_B10
VSS_B8
VSS_B7
VSS_A73
VSS_A72
VSS_A67
VSS_A61
VSS_A53
VSS_A49
VSS_A47
VSS_A44
VSS_A43
VSS_A27
VSS_A21
VSS_A15
VSS_A9
VSS_A3
VSS_J13
VSS_J11
VSS_J8
VSS_J6
VSS_J4
VSS_J1
VSS_H73
VSS_H68
VSS_H66
VSS_H61
VSS_H59
VSS_H54
VSS_H51
VSS_H48
VSS_H45
VSS_H42
VSS_H39
VSS_H37
1
SHEETDATE
23
7 3 2 16 5 4
E
A
B
C
E
D
C
B
A
7 6 5 4
D
DEPARTMENT
SIZE
PROJECT DOCUMENT NUMBER REV
REVIEWER
DESIGNER
C



Thu Aug 24 14:08:47 2023<NAME_2>
<NAME_1>
MB FABCGTI V02
59 OF 365
S O CK E T6096_13568-001
S O CK E T6096_13568-001
S O CK E T6096_13568-001S O CK E T6096_13568-001
IO
IO
IOIO
CPU1 VSS 2/3
SMLFSMLFSMLFSMLF
DA70
DA68
DA65
DA63
DA61
DA58
DA54
DA51
DA48
DA45
DA42
DA34
DA31
DA28
DA25
DA22
DA20
DA18
DA15
DA13
DA11
DA8
DA6
DA4
DA1
CY73
CY71
CY68
CY66
CY64
CY61
CY59
CY53
CY52
CY51
CY50
CY49
CY48
CY47
CY46
CY45
CY44
CY43
CY42
CY39
CY37
CY34
CY33
CY32
CY31
CY30
CY29
CY28
CY27
CY26
CY25
CY24
CY23
CY19
CY17
CY15
CY12
CY10
CY8
CY5
CY3
CW75
CW70
CW68
CW63
CW61
CW56
CW54
CW51
CW48
CW45
CW42
CW41
CW40
CW36
CW35
CW34
CW31
CW28
CW25
CW22
CW20
CW15
CW13
CW8
CW6
CW1
CV73
CV71
CV68
CV66
CV64
CV61
CV59
CV57
CV54
CV51
CV48
CV45
CV42
CV39
CV37
CV34
CV31
CV28
CV25
CV22
CV19
CV17
CV15
CV12
CV10
CV8
CV5
CV3
CU75
CU72
CU70
CU68
CU65
CU63
CU61
CU56
CU54
CU51
CU48
CU45
CU42
CU34
CU31
CU28
CU25
CU22
CU20
CU18
CU15
CU13
CU11
CU8
CU6
CU4
CU1
CT 73
CT 68
CT 66
CT 61
CT 59
CT 53
CT 51
CT 50
CT 49
CT 48
CT 47
CT 46
CT 45
CT 44
CT 43
CT 42
CT 39
CT 37
CT 34
CT 33
CT 32
CT 31
CT 30
CT 29
CT 28
CT 27
CT 26
CT 25
CT 24
CT 23
CT 17
CT 15
CT 10
CT 8
CT 3
CR75
CR72
CR70
CR68
CR65
CR63
CR61
CR58
CR56
CR54
CR51
CR48
CR45
CR42
CR41
CR40
CR36
CR35
CR34
CR31
CR28
CR25
CR22
CR20
CR18
CR15
CR13
CR11
CR8
CR6
CR4
CR1
CP73
CP71
CP68
CP66
CP64
CP61
CP59
CP57
CP54
CP51
CP48
CP45
CP42
CP39
CP37
CP34
CP31
CP28
CP25
CP22
U26
CP19
CP17
CP15
CP12
CP10
CP8
CP5
CP3
CN75
CN70
CN68
CN63
CN61
CN56
CN51
CN48
CN45
CN42
CN34
CN31
CN28
CN25
CN22
CN20
CN15
CN13
CN8
CN6
CN1
CM 73
CM 71
CM 68
CM 66
CM 64
CM 61
CM 59
CM 57
CM 53
CM 52
CM 51
CM 49
CM 48
CM 47
CM 46
CM 45
CM 44
CM 43
CM 42
CM 39
CM 37
CM 34
CM 33
CM 32
CM 31
CM 30
CM 29
CM 28
CM 27
CM 26
CM 25
CM 24
CM 23
CM 19
CM 17
CM 15
CM 12
CM 10
CM 8
CM 5
CM 3
CL75
CL72
CL70
CL68
CL65
CL63
CL61
CL58
CL56
CL54
CL51
CL48
CL45
CL42
CL41
CL40
CL36
CL35
CL34
CL31
CL28
CL25
CL22
CL20
CL18
CL15
CL13
CL11
CL8
CL6
CL4
CL1
CK73
CK68
CK66
CK61
CK59
CK54
CK53
CK52
CK51
CK50
CK49
CK48
CK45
CK44
CK43
CK42
CK39
CK37
CK34
CK33
CK32
CK28
CK27
CK26
CK25
CK24
CK23
CK22
CK17
CK15
CK8
CK3
CJ75
CJ72
CJ70
CJ68
CJ65
CJ63
CJ61
CJ58
CJ56
CJ45
CJ42
CJ41
CJ40
CJ36
CJ35
CJ34
CJ31
CJ23
CJ20
CJ18
CJ15
CJ13
CJ11
CJ8
CJ6
CJ4
CJ1
CH73
CH71
CH68
CH66
CH64
CH61
CH59
CH57
CH54
CH51
CH48
CH45
CH42
CH39
CH37
CH34
CH31
CH28
CH25
CH22
CH19
CH17
CH15
CH12
CH10
CH8
CH5
CH3
CG75
CG70
CG68
CG63
CG61
CG56
CG54
CG51
CG48
CG45
CG34
CG31
CG28
CG25
CG22
CG20
CG15
CG13
CG8
CG6
CG1
CF73
CF71
CF68
CF66
CF64
CF61
CF59
CF57
CF53
CF52
CF51
CF50
CF49
CF48
CF47
CF45
CF44
CF43
CF42
CF39
CF37
CF34
U26
CF33
CF32
CF31
CF30
CF29
CF28
CF27
CF26
CF25
CF24
CF23
CF19
CF17
CF15
CF12
CF10
CF8
CF5
CF3
CE75
CE72
CE70
CE68
CE65
CE63
CE61
CE58
CE56
CE54
CE51
CE48
CE45
CE42
CE41
CE40
CE36
CE35
CE34
CE31
CE28
CE25
CE22
CE20
CE18
CE15
CE13
CE11
CE8
CE6
CE4
CE1
CD73
CD68
CD66
CD61
CD59
CD54
CD51
CD48
CD45
CD42
CD39
CD37
CD34
CD31
CD28
CD25
CD22
CD17
CD15
CD10
CD8
CD3
CC75
CC72
CC70
CC68
CC65
CC63
CC61
CC58
CC56
CC54
CC51
CC48
CC45
CC42
CC34
CC31
CC28
CC25
CC20
CC18
CC15
CC13
CC11
CC8
CC6
CC4
CC1
CB73
CB71
CB68
CB66
CB64
CB61
CB59
CB57
CB53
CB52
CB51
CB50
CB49
CB48
CB47
CB46
CB45
CB43
CB42
CB39
CB37
CB34
CB33
CB32
CB31
CB30
CB29
CB28
CB27
CB26
CB25
CB24
CB23
CB19
CB17
CB15
CB12
CB10
CB8
CB5
CB3
CA75
CA70
CA68
CA63
CA61
CA56
CA54
CA51
CA48
CA45
CA42
CA41
CA40
CA36
CA35
CA34
CA31
CA28
CA25
CA22
CA20
CA15
CA13
CA8
CA6
CA1
BY73
BY71
BY68
BY66
BY64
BY61
BY59
BY57
BY54
BY51
BY48
BY45
BY42
BY39
BY37
BY34
BY31
BY28
BY25
BY22
BY19
BY17
BY15
BY12
BY10
BY8
BY5
BY3
BW75
BW72
BW70
BW68
BW65
BW63
BW61
BW58
BW56
BW54
BW51
BW48
BW45
BW42
BW34
BW31
BW28
BW22
BW20
BW18
BW15
BW13
BW11
BW8
BW6
BW4
BW1
BV73
BV68
BV66
BV61
BV59
BV53
BV52
BV51
BV50
BV49
BV48
BV47
BV46
U26
BV45
BV44
BV43
BV39
BV37
BV34
BV33
BV32
BV31
BV30
BV29
BV28
BV27
BV26
BV25
BV24
BV23
BV17
BV15
BV10
BV8
BV3
BU75
BU72
BU70
BU68
BU65
BU63
BU61
BU58
BU56
BU54
BU51
BU48
BU45
BU42
BU41
BU40
BU36
BU35
BU34
BU31
BU28
BU25
BU22
BU20
BU18
BU15
BU13
BU11
BU8
BU6
BU4
BU1
BT 73
BT 72
BT 71
BT 69
BT 68
BT 66
BT 65
BT 64
BT 62
BT 61
BT 59
BT 58
BT 57
BT 55
BT 54
BT 51
BT 48
BT 45
BT 42
BT 39
BT 37
BT 34
BT 31
BT 28
BT 25
BT 22
BT 21
BT 19
BT 18
BT 17
BT 15
BT 14
BT 12
BT 11
BT 10
BT 8
BT 7
BT 5
BT 4
BT 3
BR75
BR73
BR70
BR69
BR68
BR66
BR63
BR62
BR61
BR59
BR56
BR55
BR51
BR49
BR47
BR45
BR43
BR41
BR36
BR34
BR32
BR30
BR28
BR26
BR24
BR22
BR21
BR20
BR17
BR15
BR14
BR13
BR10
BR8
BR7
BR6
BR3
BR1
BP73
BP71
BP68
BP66
BP64
BP61
BP59
BP57
BP54
BP52
BP50
BP48
BP46
BP44
BP42
BP40
BP37
BP35
BP33
BP31
BP29
BP27
BP25
BP23
BP19
BP17
BP15
BP12
BP10
BP8
BP5
BP3
BN75
BN72
BN70
BN68
BN65
BN63
BN61
BN58
BN56
BN53
BN51
BN49
BN47
BN45
BN43
BN41
BN36
BN34
BN32
BN30
BN28
BN26
BN24
BN22
BN20
BN18
BN15
BN13
BN11
BN8
BN6
BN4
BN1
BM 73
BM 68
BM 66
BM 61
BM 59
BM 54
BM 52
BM 50
BM 48
BM 46
BM 44
BM 42
BM 40
BM 37
BM 35
BM 33
BM 31
BM 29
BM 27
BM 25
BM 23
BM 17
BM 15
BM 10
BM 8
BM 3
BL75
BL72
BL70
BL68
BL65
BL63
BL61
BL58
BL56
BL53
BL51
BL49
BL28
BL26
U26
39/40
VSS_DA70
VSS_DA68
VSS_DA65
VSS_DA63
VSS_DA61
VSS_DA58
VSS_DA42
VSS_DA34
VSS_DA31
VSS_DA28
VSS_DA25
VSS_DA22
VSS_DA11
VSS_DA8
VSS_DA6
VSS_DA4
VSS_DA1
VSS_CY73
VSS_CY71
VSS_CY61
VSS_CY59
VSS_CY53
VSS_CY52
VSS_CY51
VSS_CY50
VSS_CY49
VSS_CY46
VSS_CY45
VSS_CY44
VSS_CY43
VSS_CY42
VSS_CY39
VSS_CY37
VSS_CY34
VSS_CY33
VSS_CY31
VSS_CY30
VSS_CY29
VSS_CY28
VSS_CY27
VSS_CY26
VSS_CY25
VSS_CY24
VSS_CY23
VSS_CY19
VSS_CY17
VSS_CY15
VSS_CY12
VSS_CY10
VSS_CY8
VSS_CY5
VSS_CY3
VSS_CW75
VSS_CW70
VSS_CW68
VSS_CW63
VSS_CW61
VSS_CW56
VSS_CW54
VSS_CW51
VSS_CW48
VSS_CW45
VSS_CW42
VSS_CW41
VSS_CW40
VSS_CW36
VSS_CW35
VSS_CW20
VSS_CW15
VSS_CW13
VSS_CW8
VSS_CW6
VSS_CW1
VSS_CV61
VSS_CV59
VSS_CV57
VSS_CV54
VSS_CV51
VSS_CV48
VSS_CV31
VSS_CV28
VSS_CV25
VSS_CV22
VSS_CV19
VSS_CV17
VSS_CV3
VSS_CU75
VSS_CU72
VSS_CU70
VSS_CU68
VSS_CU65
VSS_CU54
VSS_CU51
VSS_CU48
VSS_CU45
VSS_CU42
VSS_CU34
VSS_CU31
VSS_CU20
VSS_CU18
VSS_CU15
VSS_CU13
VSS_CU11
VSS_CU8
VSS_CU6
VSS_CU4
VSS_CT68
VSS_CT66
VSS_CT61
VSS_CT59
VSS_CT53
VSS_CT51
VSS_CT50
VSS_CT49
VSS_CT47
VSS_CT46
VSS_CT45
VSS_CT44
VSS_CT43
VSS_CT42
VSS_CT39
VSS_CT37
VSS_CT34
VSS_CT33
VSS_CT32
VSS_CT31
VSS_CT30
VSS_CT29
VSS_CT28
VSS_CT27
VSS_CT26
VSS_CT25
VSS_CT24
VSS_CT23
VSS_CT17
VSS_CR72
VSS_CR70
VSS_CR68
VSS_CR65
VSS_CR63
VSS_CR61
VSS_CR45
VSS_CR42
VSS_CR41
VSS_CR40
VSS_CR36
VSS_CR35
VSS_CR20
VSS_CR18
VSS_CR15
VSS_CR13
VSS_CR11
VSS_CR8
VSS_CP68
VSS_CP66
VSS_CP64
VSS_CP61
VSS_CP59
VSS_CP57
VSS_CP39
VSS_CP37
VSS_CP34
VSS_CP31
VSS_CP28
VSS_CP25
VSS_DA54
VSS_DA51
VSS_DA48
VSS_DA45
VSS_DA20
VSS_DA18
VSS_DA15
VSS_DA13
VSS_CY68
VSS_CY66
VSS_CY64
VSS_CY48
VSS_CY47
VSS_CY32
VSS_CW34
VSS_CW31
VSS_CW28
VSS_CW25
VSS_CW22
VSS_CV73
VSS_CV71
VSS_CV68
VSS_CV66
VSS_CV64
VSS_CV45
VSS_CV42
VSS_CV39
VSS_CV37
VSS_CV34
VSS_CV15
VSS_CV12
VSS_CV10
VSS_CV8
VSS_CV5
VSS_CU63
VSS_CU61
VSS_CU56
VSS_CU28
VSS_CU25
VSS_CU22
VSS_CU1
VSS_CT73
VSS_CT48
VSS_CT15
VSS_CT10
VSS_CT8
VSS_CT3
VSS_CR75
VSS_CR58
VSS_CR56
VSS_CR54
VSS_CR51
VSS_CR48
VSS_CR34
VSS_CR31
VSS_CR28
VSS_CR25
VSS_CR22
VSS_CR6
VSS_CR4
VSS_CR1
VSS_CP73
VSS_CP71
VSS_CP54
VSS_CP51
VSS_CP48
VSS_CP45
VSS_CP42
VSS_CP22
38/40
VSS_CP19
VSS_CP17
VSS_CP15
VSS_CP12
VSS_CP10
VSS_CP8
VSS_CP5
VSS_CP3
VSS_CN75
VSS_CN70
VSS_CN68
VSS_CN63
VSS_CN61
VSS_CN51
VSS_CN48
VSS_CN45
VSS_CN42
VSS_CN34
VSS_CN31
VSS_CN28
VSS_CN25
VSS_CN15
VSS_CN13
VSS_CN8
VSS_CN6
VSS_CN1
VSS_CM73
VSS_CM71
VSS_CM68
VSS_CM59
VSS_CM57
VSS_CM53
VSS_CM52
VSS_CM51
VSS_CM49
VSS_CM48
VSS_CM47
VSS_CM46
VSS_CM45
VSS_CM44
VSS_CM33
VSS_CM32
VSS_CM31
VSS_CM30
VSS_CM29
VSS_CM28
VSS_CM23
VSS_CM19
VSS_CM17
VSS_CM15
VSS_CM12
VSS_CM10
VSS_CM8
VSS_CL72
VSS_CL70
VSS_CL68
VSS_CL65
VSS_CL63
VSS_CL61
VSS_CL58
VSS_CL56
VSS_CL48
VSS_CL45
VSS_CL42
VSS_CL41
VSS_CL40
VSS_CL36
VSS_CL35
VSS_CL34
VSS_CL31
VSS_CL25
VSS_CL22
VSS_CL20
VSS_CL18
VSS_CL15
VSS_CL13
VSS_CL11
VSS_CL8
VSS_CL6
VSS_CL4
VSS_CL1
VSS_CK73
VSS_CK68
VSS_CK66
VSS_CK61
VSS_CK59
VSS_CK54
VSS_CK53
VSS_CK52
VSS_CK51
VSS_CK50
VSS_CK49
VSS_CK48
VSS_CK45
VSS_CK44
VSS_CK43
VSS_CK42
VSS_CK39
VSS_CK37
VSS_CK34
VSS_CK32
VSS_CK28
VSS_CK27
VSS_CK26
VSS_CK25
VSS_CK24
VSS_CK23
VSS_CK22
VSS_CK8
VSS_CK3
VSS_CJ75
VSS_CJ72
VSS_CJ70
VSS_CJ68
VSS_CJ65
VSS_CJ56
VSS_CJ45
VSS_CJ42
VSS_CJ41
VSS_CJ40
VSS_CJ36
VSS_CJ35
VSS_CJ18
VSS_CJ15
VSS_CJ13
VSS_CJ11
VSS_CJ8
VSS_CJ6
VSS_CH66
VSS_CH64
VSS_CH61
VSS_CH59
VSS_CH57
VSS_CH54
VSS_CH37
VSS_CH34
VSS_CH31
VSS_CH28
VSS_CH25
VSS_CH22
VSS_CH8
VSS_CH5
VSS_CH3
VSS_CG75
VSS_CG70
VSS_CG68
VSS_CG63
VSS_CG61
VSS_CG56
VSS_CG54
VSS_CG51
VSS_CG48
VSS_CG45
VSS_CG34
VSS_CG31
VSS_CG28
VSS_CG25
VSS_CG22
VSS_CG20
VSS_CG15
VSS_CG13
VSS_CG8
VSS_CG6
VSS_CG1
VSS_CF73
VSS_CF71
VSS_CF68
VSS_CF66
VSS_CF64
VSS_CF61
VSS_CF59
VSS_CF57
VSS_CF53
VSS_CF52
VSS_CF51
VSS_CF50
VSS_CF49
VSS_CF48
VSS_CF47
VSS_CF45
VSS_CF44
VSS_CF43
VSS_CF42
VSS_CF39
VSS_CF37
VSS_CF34
VSS_CH19
VSS_CH51
VSS_CJ4
VSS_CL28
VSS_CL54
VSS_CM5
VSS_CM27
VSS_CM43
VSS_CH17
VSS_CH48
VSS_CJ1
VSS_CJ34
VSS_CL51
VSS_CM3
VSS_CM26
VSS_CM42
VSS_CH15
VSS_CH45
VSS_CH73
VSS_CJ31
VSS_CJ63
VSS_CL75
VSS_CM25
VSS_CM39
VSS_CM66
VSS_CH12
VSS_CH42
VSS_CH71
VSS_CJ23
VSS_CJ61
VSS_CK17
VSS_CM24
VSS_CM37
VSS_CM64
VSS_CN22
VSS_CH10
VSS_CH39
VSS_CH68
VSS_CJ20
VSS_CJ58
VSS_CK15
VSS_CK33
VSS_CM34
VSS_CM61
VSS_CN20
VSS_CN56
37/40
VSS_CF33
VSS_CF32
VSS_CF31
VSS_CF30
VSS_CF29
VSS_CF28
VSS_CF27
VSS_CF26
VSS_CF25
VSS_CF24
VSS_CF23
VSS_CF19
VSS_CF17
VSS_CF15
VSS_CF12
VSS_CF10
VSS_CF8
VSS_CF5
VSS_CF3
VSS_CE75
VSS_CE72
VSS_CE70
VSS_CE68
VSS_CE65
VSS_CE63
VSS_CE61
VSS_CE58
VSS_CE56
VSS_CE54
VSS_CE51
VSS_CE48
VSS_CE45
VSS_CE42
VSS_CE41
VSS_CE40
VSS_CE36
VSS_CE35
VSS_CE34
VSS_CE31
VSS_CE28
VSS_CE25
VSS_CE22
VSS_CE20
VSS_CE18
VSS_CE15
VSS_CE13
VSS_CE11
VSS_CE8
VSS_CE6
VSS_CE4
VSS_CE1
VSS_CD73
VSS_CD68
VSS_CD66
VSS_CD61
VSS_CD59
VSS_CD54
VSS_CD51
VSS_CD48
VSS_CD45
VSS_CD42
VSS_CD39
VSS_CD37
VSS_CD34
VSS_CD31
VSS_CD28
VSS_CD25
VSS_CD22
VSS_CD17
VSS_CD15
VSS_CD10
VSS_CD8
VSS_CD3
VSS_CC75
VSS_CC72
VSS_CC70
VSS_CC68
VSS_CC65
VSS_CC63
VSS_CC61
VSS_CC58
VSS_CC56
VSS_CC54
VSS_CC51
VSS_CC48
VSS_CC45
VSS_CC42
VSS_CC34
VSS_CC31
VSS_CC28
VSS_CC25
VSS_CC20
VSS_CC18
VSS_CC15
VSS_CC13
VSS_CC11
VSS_CC8
VSS_CC6
VSS_CC4
VSS_CC1
VSS_CB73
VSS_CB71
VSS_CB68
VSS_CB66
VSS_CB64
VSS_CB61
VSS_CB59
VSS_CB57
VSS_CB53
VSS_CB52
VSS_CB51
VSS_CB50
VSS_CB49
VSS_CB48
VSS_CB47
VSS_CB46
VSS_CB45
VSS_CB43
VSS_CB42
VSS_CB39
VSS_CB37
VSS_CB34
VSS_CB33
VSS_CB32
VSS_CB31
VSS_CB30
VSS_CB29
VSS_CB28
VSS_CB27
VSS_CB26
VSS_CB25
VSS_CB24
VSS_CB23
VSS_CB19
VSS_CB17
VSS_CB15
VSS_CB12
VSS_CB10
VSS_CB8
VSS_CB5
VSS_CB3
VSS_CA75
VSS_CA70
VSS_CA68
VSS_CA63
VSS_CA61
VSS_CA56
VSS_CA54
VSS_CA51
VSS_CA48
VSS_CA45
VSS_CA42
VSS_CA41
VSS_CA40
VSS_CA36
VSS_CA35
VSS_CA34
VSS_CA31
VSS_CA28
VSS_CA25
VSS_CA22
VSS_CA20
VSS_CA15
VSS_CA13
VSS_CA8
VSS_CA6
VSS_CA1
VSS_BY73
VSS_BY71
VSS_BY68
VSS_BY66
VSS_BY64
VSS_BY61
VSS_BY59
VSS_BY57
VSS_BY54
VSS_BY51
VSS_BY48
VSS_BY45
VSS_BY42
VSS_BY39
VSS_BY37
VSS_BY34
VSS_BY31
VSS_BY28
VSS_BY25
VSS_BY22
VSS_BY19
VSS_BY17
VSS_BY15
VSS_BY12
VSS_BY10
VSS_BY8
VSS_BY5
VSS_BY3
VSS_BW75
VSS_BW72
VSS_BW70
VSS_BW68
VSS_BW65
VSS_BW63
VSS_BW61
VSS_BW58
VSS_BW56
VSS_BW54
VSS_BW51
VSS_BW48
VSS_BW45
VSS_BW42
VSS_BW34
VSS_BW31
VSS_BW28
VSS_BW22
VSS_BW20
VSS_BW18
VSS_BW15
VSS_BW13
VSS_BW11
VSS_BW8
VSS_BW6
VSS_BW4
VSS_BW1
VSS_BV73
VSS_BV68
VSS_BV66
VSS_BV61
VSS_BV59
VSS_BV53
VSS_BV52
VSS_BV51
VSS_BV50
VSS_BV49
VSS_BV48
VSS_BV47
VSS_BV46
34/40
VSS_BV45
VSS_BV44
VSS_BV43
VSS_BV39
VSS_BV34
VSS_BV33
VSS_BV32
VSS_BV31
VSS_BV30
VSS_BV29
VSS_BV28
VSS_BV27
VSS_BV26
VSS_BV25
VSS_BV24
VSS_BV23
VSS_BV17
VSS_BV15
VSS_BV10
VSS_BV8
VSS_BV3
VSS_BU75
VSS_BU72
VSS_BU70
VSS_BU68
VSS_BU65
VSS_BU63
VSS_BU61
VSS_BU58
VSS_BU56
VSS_BU54
VSS_BU51
VSS_BU48
VSS_BU45
VSS_BU42
VSS_BU41
VSS_BU40
VSS_BU36
VSS_BU35
VSS_BU34
VSS_BU31
VSS_BU28
VSS_BU25
VSS_BU22
VSS_BU20
VSS_BU18
VSS_BU15
VSS_BU13
VSS_BU11
VSS_BU8
VSS_BU6
VSS_BU4
VSS_BU1
VSS_BT73
VSS_BT72
VSS_BT71
VSS_BT69
VSS_BT68
VSS_BT66
VSS_BT65
VSS_BT64
VSS_BT62
VSS_BT61
VSS_BT59
VSS_BT58
VSS_BT57
VSS_BT55
VSS_BT54
VSS_BT51
VSS_BT48
VSS_BT45
VSS_BT42
VSS_BT39
VSS_BT37
VSS_BT34
VSS_BT31
VSS_BT28
VSS_BT25
VSS_BT22
VSS_BT21
VSS_BT19
VSS_BT18
VSS_BT17
VSS_BT15
VSS_BT14
VSS_BT12
VSS_BT11
VSS_BT10
VSS_BT8
VSS_BT7
VSS_BT5
VSS_BT4
VSS_BT3
VSS_BR75
VSS_BR73
VSS_BR70
VSS_BR69
VSS_BR68
VSS_BR66
VSS_BR63
VSS_BR62
VSS_BR61
VSS_BR59
VSS_BR56
VSS_BR55
VSS_BR51
VSS_BR49
VSS_BR47
VSS_BR45
VSS_BR43
VSS_BR41
VSS_BR36
VSS_BR34
VSS_BR32
VSS_BR30
VSS_BR28
VSS_BR26
VSS_BR24
VSS_BR22
VSS_BR21
VSS_BR20
VSS_BR17
VSS_BR15
VSS_BR14
VSS_BR13
VSS_BR10
VSS_BR8
VSS_BR7
VSS_BR6
VSS_BR3
VSS_BR1
VSS_BP73
VSS_BP71
VSS_BP68
VSS_BP66
VSS_BP64
VSS_BP61
VSS_BP59
VSS_BP57
VSS_BP54
VSS_BP52
VSS_BP50
VSS_BP48
VSS_BP46
VSS_BP44
VSS_BP42
VSS_BP40
VSS_BP37
VSS_BP35
VSS_BP33
VSS_BP31
VSS_BP29
VSS_BP27
VSS_BP25
VSS_BP23
VSS_BP19
VSS_BP17
VSS_BP15
VSS_BP12
VSS_BP10
VSS_BP8
VSS_BP5
VSS_BP3
VSS_BN75
VSS_BN72
VSS_BN70
VSS_BN68
VSS_BN65
VSS_BN63
VSS_BN61
VSS_BN58
VSS_BN56
VSS_BN53
VSS_BN51
VSS_BN49
VSS_BN47
VSS_BN45
VSS_BN43
VSS_BN41
VSS_BN36
VSS_BN34
VSS_BN32
VSS_BN30
VSS_BN28
VSS_BN26
VSS_BN24
VSS_BN22
VSS_BN20
VSS_BN18
VSS_BN15
VSS_BN13
VSS_BN11
VSS_BN8
VSS_BN6
VSS_BN4
VSS_BN1
VSS_BM73
VSS_BM68
VSS_BM66
VSS_BM61
VSS_BM59
VSS_BM54
VSS_BM52
VSS_BM50
VSS_BM48
VSS_BM46
VSS_BM44
VSS_BM42
VSS_BM40
VSS_BM37
VSS_BM35
VSS_BM33
VSS_BM31
VSS_BM29
VSS_BM27
VSS_BM25
VSS_BM23
VSS_BM17
VSS_BM15
VSS_BM10
VSS_BM8
VSS_BM3
VSS_BL75
VSS_BL72
VSS_BL70
VSS_BL68
VSS_BL65
VSS_BL63
VSS_BL61
VSS_BL58
VSS_BL56
VSS_BL53
VSS_BL51
VSS_BL49
VSS_BL28
VSS_BL26
VSS_BV37
1
SHEETDATE
23
7 3 2 16 5 4
E
A
B
C
E
D
C
B
A
7 6 5 4
D
DEPARTMENT
SIZE
PROJECT DOCUMENT NUMBER REV
REVIEWER
DESIGNER
C



Thu Aug 24 14:08:48 2023<NAME_2>
<NAME_1>
MB FABCGTI V02
60 OF 365
SOCKET6096_13568-001
IO
CPU1 VSS 3/3
SMLF
V68
V27
P68
P25
K59
K23
DJ73
DJ68
DJ66
DJ63
DJ61
DJ59
DJ49
DJ43
DJ19
DJ15
DJ7
DH70
DH68
DH66
DH64
DH63
DH61
DH59
DH55
DH52
DH49
DH46
DH43
DH39
DH37
DH18
DH11
DH5
DG75
DG74
DG70
DG69
DG68
DG67
DG66
DG65
DG63
DG62
DG61
DG60
DG59
DG56
DG55
DG52
DG49
DG46
DG43
DG41
DG33
DG30
DG27
DG24
DG21
DG20
DG18
DG16
DG15
DG14
DG13
DG9
DG8
DG7
DG6
DG2
DG1
DF73
DF72
DF71
DF70
DF68
DF66
DF65
DF64
DF63
DF61
DF59
DF58
DF57
DF56
DF54
DF53
DF52
DF51
DF50
DF49
DF48
DF47
DF46
DF45
DF44
DF43
DF42
DF39
DF37
DF35
DF32
DF29
DF26
DF23
DF22
DF20
DF19
DF18
DF17
DF15
DF13
DF12
DF11
DF10
DF8
DF6
DF5
DF4
DF3
DE75
DE70
DE68
DE63
DE61
DE56
DE33
DE29
DE26
DE23
DE20
DE15
DE13
DE8
DE6
DE1
DD73
DD71
DD68
DD66
DD64
DD61
DD59
DD57
DD53
DD52
DD50
DD49
DD47
DD46
DD44
DD43
DD41
DD40
DD39
DD37
DD36
DD35
DD33
DD32
DD30
DD29
DD27
DD26
DD24
DD23
DD19
DD17
DD15
DD12
DD10
DD8
DD5
DD3
DC75
DC72
DC70
DC68
DC65
DC63
DC61
DC58
DC56
DC54
DC51
DC48
DC45
DC42
DC34
DC31
DC28
DC25
DC22
DC20
DC18
DC15
DC13
DC11
DC8
DC6
DC4
DC1
DB73
DB68
DB66
DB61
DB59
DB54
DB51
DB48
DB45
DB42
DB39
DB37
DB34
DB31
DB28
DB25
DB22
DB17
DB15
DB10
DB8
DB3
DA75
DA72
DA56
CY57
CU58
CT52
CN54
CM50
CK31
CK10
CG42
CF46
CC22
CB44
BW25
BV42
AN20
AM37
AJ13
AH33
AE4
AD31
AA72
AA42
U26
40/40
VSS_V68
VSS_BV42
VSS_CT52
VSS_CM50
VSS_K59
VSS_DA56
VSS_CG42
VSS_AE4
VSS_AH33
VSS_BW25
VSS_CU58
VSS_P25
VSS_P68
VSS_AN20
VSS_CC22
VSS_CF46
VSS_V27
VSS_AA42
VSS_AD31
VSS_AJ13
VSS_AA72
VSS_CK10
VSS_CN54
VSS_K23
VSS_AM37
VSS_CB44
VSS_CK31
VSS_CY57
VSS_DJ73
VSS_DJ68
VSS_DJ66
VSS_DJ63
VSS_DJ61
VSS_DJ59
VSS_DJ49
VSS_DJ43
VSS_DJ19
VSS_DJ15
VSS_DJ7
VSS_DH70
VSS_DH68
VSS_DH59
VSS_DH55
VSS_DH52
VSS_DH49
VSS_DH46
VSS_DH43
VSS_DH39
VSS_DG75
VSS_DG74
VSS_DG70
VSS_DG69
VSS_DG68
VSS_DG67
VSS_DG66
VSS_DG60
VSS_DG59
VSS_DG56
VSS_DG55
VSS_DG52
VSS_DG49
VSS_DG46
VSS_DG27
VSS_DG24
VSS_DG21
VSS_DG20
VSS_DG18
VSS_DG16
VSS_DG15
VSS_DG7
VSS_DG6
VSS_DG2
VSS_DG1
VSS_DF73
VSS_DF72
VSS_DF71
VSS_DF65
VSS_DF64
VSS_DF63
VSS_DF61
VSS_DF59
VSS_DF58
VSS_DF57
VSS_DF56
VSS_DF52
VSS_DF51
VSS_DF50
VSS_DF49
VSS_DF48
VSS_DF47
VSS_DF46
VSS_DF45
VSS_DF44
VSS_DF42
VSS_DF39
VSS_DF37
VSS_DF35
VSS_DF32
VSS_DF29
VSS_DF26
VSS_DF23
VSS_DF22
VSS_DF20
VSS_DF13
VSS_DF12
VSS_DF11
VSS_DF10
VSS_DF8
VSS_DF6
VSS_DF5
VSS_DE68
VSS_DE63
VSS_DE61
VSS_DE56
VSS_DE33
VSS_DE29
VSS_DE26
VSS_DE8
VSS_DE6
VSS_DE1
VSS_DD73
VSS_DD71
VSS_DD68
VSS_DD66
VSS_DD53
VSS_DD52
VSS_DD50
VSS_DD49
VSS_DD47
VSS_DD46
VSS_DD44
VSS_DD37
VSS_DD36
VSS_DD35
VSS_DD33
VSS_DD32
VSS_DD30
VSS_DD29
VSS_DD19
VSS_DD17
VSS_DD15
VSS_DD12
VSS_DD10
VSS_DD8
VSS_DD5
VSS_DC68
VSS_DC65
VSS_DC63
VSS_DC61
VSS_DC58
VSS_DC56
VSS_DC54
VSS_DC42
VSS_DC34
VSS_DC31
VSS_DC28
VSS_DC25
VSS_DC22
VSS_DC20
VSS_DC18
VSS_DC11
VSS_DC8
VSS_DC6
VSS_DC4
VSS_DC1
VSS_DB73
VSS_DB68
VSS_DB66
VSS_DB61
VSS_DB45
VSS_DB42
VSS_DB39
VSS_DB37
VSS_DB34
VSS_DB31
VSS_DB28
VSS_DB10
VSS_DB8
VSS_DB3
VSS_DA75
VSS_DA72
VSS_DH66
VSS_DH64
VSS_DH63
VSS_DH61
VSS_DH37
VSS_DH18
VSS_DH11
VSS_DH5
VSS_DG65
VSS_DG63
VSS_DG62
VSS_DG61
VSS_DG43
VSS_DG41
VSS_DG33
VSS_DG30
VSS_DG14
VSS_DG13
VSS_DG9
VSS_DG8
VSS_DF70
VSS_DF68
VSS_DF66
VSS_DF54
VSS_DF53
VSS_DF43
VSS_DF19
VSS_DF18
VSS_DF17
VSS_DF15
VSS_DF4
VSS_DF3
VSS_DE75
VSS_DE70
VSS_DE23
VSS_DE20
VSS_DE15
VSS_DE13
VSS_DD64
VSS_DD61
VSS_DD59
VSS_DD57
VSS_DD43
VSS_DD41
VSS_DD40
VSS_DD39
VSS_DD27
VSS_DD26
VSS_DD24
VSS_DD23
VSS_DD3
VSS_DC75
VSS_DC72
VSS_DC70
VSS_DC51
VSS_DC48
VSS_DC45
VSS_DC15
VSS_DC13
VSS_DB59
VSS_DB54
VSS_DB51
VSS_DB48
VSS_DB25
VSS_DB22
VSS_DB17
VSS_DB15
1
SHEETDATE
23
7 3 2 16 5 4
E
A
B
C
E
D
C
B
A
7 6 5 4
D
DEPARTMENT
SIZE
PROJECT DOCUMENT NUMBER REV
REVIEWER
DESIGNER
C



Thu Aug 24 10:13:55 2023<NAME_2>
<NAME_1>
MB FABCGTI V02
61 OF 365
CPU1 GLUE LOGIC
1
SHEETDATE
23
7 3 2 16 5 4
E
A
B
C
E
D
C
B
A
7 6 5 4
D
DEPARTMENT
SIZE
PROJECT DOCUMENT NUMBER REV
REVIEWER
DESIGNER
C



Thu Aug 24 10:13:55 2023<NAME_2>
<NAME_1>
MB FABCGTI V02
62 OF 365Blank
1
SHEETDATE
23
7 3 2 16 5 4
E
A
B
C
E
D
C
B
A
7 6 5 4
D
DEPARTMENT
SIZE
PROJECT DOCUMENT NUMBER REV
REVIEWER
DESIGNER
C



20210527 MODIFY FOR GT
CPU0 PCIE P0 TX CPU0 PCIE P1 TX
63 OF 365
V02GTI MB FABC
Thu Aug 24 14:09:14 2023<NAME_2>
<NAME_1>
D IFF BU S_0.22U F
284
284
284
284
24
24
24
24
24
24
24
273
273
273
273
24
D IFF BU S_0.22U F
D IFF BU S_0.22U F
D IFF BU S_0.22U F
D IFF BU S_0.22U F
D IFF BU S_0.22U F
D IFF BU S_0.22U F
D IFF BU S_0.22U F
D IFF BU S_0.22U F
D IFF BU S_0.22U F
D IFF BU S_0.22U F
D IFF BU S_0.22U F
D IFF BU S_0.22U F
D IFF BU S_0.22U F
D IFF BU S_0.22U F
D IFF BU S_0.22U F
D IFF BU S_0.22U F
D IFF BU S_0.22U F
D IFF BU S_0.22U F
D IFF BU S_0.22U F
D IFF BU S_0.22U F
D IFF BU S_0.22U F
D IFF BU S_0.22U F
D IFF BU S_0.22U F
D IFF BU S_0.22U F
D IFF BU S_0.22U F
D IFF BU S_0.22U F
D IFF BU S_0.22U F
D IFF BU S_0.22U F
D IFF BU S_0.22U F
D IFF BU S_0.22U F
C0201 6.3V
D IFF BU S_0.22U F
20%
X 6S
D IFF BU S_0.22U F
D IFF BU S_0.22U F
D IFF BU S_0.22U F
D IFF BU S_0.22U F
D IFF BU S_0.22U F
D IFF BU S_0.22U F
D IFF BU S_0.22U F
D IFF BU S_0.22U F
D IFF BU S_0.22U F
D IFF BU S_0.22U F
D IFF BU S_0.22U F
D IFF BU S_0.22U F
D IFF BU S_0.22U F
D IFF BU S_0.22U F
D IFF BU S_0.22U F
D IFF BU S_0.22U F
D IFF BU S_0.22U F
D IFF BU S_0.22U F
D IFF BU S_0.22U F
D IFF BU S_0.22U F
D IFF BU S_0.22U F
D IFF BU S_0.22U F
D IFF BU S_0.22U F
D IFF BU S_0.22U F
D IFF BU S_0.22U F
D IFF BU S_0.22U F
D IFF BU S_0.22U F
D IFF BU S_0.22U F
C0201 6.3V
X 6S
D IFF BU S_0.22U F
20%
D IFF BU S_0.22U F
D IFF BU S_0.22U F
D IFF BU S_0.22U F
P5E_CPU0_P1_TX_C_DP<7:0>
P5E_CPU0_P1_TX_C_DN<7:0>
P5E_CPU0_P1_TX_C_DN<15:8>
P5E_CPU0_P1_TX_C_DP<15:8>
P5E_CPU0_P1_TX_DN<15:8>
P5E_CPU0_P1_TX_DP<15:8>
P5E_CPU0_P1_TX_DP<7:0>
P5E_CPU0_P1_TX_DN<7:0>
P5E_CPU0_P0_TX_DP<15:8>
P5E_CPU0_P0_TX_DN<15:8>
P5E_CPU0_P0_TX_DN<7:0>
P5E_CPU0_P0_TX_C_DP<7:0>
P5E_CPU0_P0_TX_C_DN<7:0>
P5E_CPU0_P0_TX_C_DP<15:8>
P5E_CPU0_P0_TX_C_DN<15:8>
P5E_CPU0_P0_TX_DP<7:0>
CCBUPCIE AC-COUPLE CAPS 1/5
2 1
2 1
2 1
2 1
2 1
2 1
2 1
2 1
2 1
2 1
2 1
2 1
2 1
2 1
2 1
2 1
2 1
2 1
2 1
2 1
2 1
2 1
2 1
2 1
2 1
2 1
2 1
2 1
2 1
2 1
2 1
2 1
2 1
2 1
2 1
2 1
2 1
2 1
2 1
2 1
2 1
2 1
2 1
2 1
2 1
2 1
2 1
2 1
2 1
2 1
2 1
2 1
2 1
2 1
2 1
2 1
2 1
2 1
2 1
2 1
2 1
2 1
2 1
2 1
14
14
12
15
13
11
10
14
15
14
10
11
15
1010
9
10
10
11
12
15
9
14
8
0
2
5
8
0
1
2
0
1
0
1
2
3
4
2
3
6
4
5
6
7
7
8
9
8
11
12
10
13
15
13
14 14
11
13
12
9
7
5
6
3
4
2
1
0
15
1
3
4
5
6
7
11
12
13
14
15
1
3
2
6
5
4
7
0
1
3
5
4
6
7
9
8
12
11
13
15
8
9
10
11
12
13
1
2
3
0
2
3
4
5
4
6
7
5
6
7
8
9
8
9
12
13
0
C955
C956
C957
C934
C935
C936
C937
C938
C939
C940
C941
C942
C943
C944
C945
C946
C947
C948
C949
C950
C951
C952
C953
C954
C958
C959
C960
C961
C962
C963
C964
C965
C902
C903
C904
C905
C907
C906
C908
C909
C910
C911
C912
C913
C914
C915
C917
C916
C919
C918
C920
C921
C922
C923
C924
C925
C926
C927
C929
C928
C930
C931
C933
C932
2 1
2 1
2 1
2 1
2 1
2 1
2 1
2 1
2 1
2 1
2 1
2 1
2 1
2 1
2 1
2 1
2 1
2 1
2 1
2 1
2 1
2 1
2 1
2 1
2 1
2 1
2 1
2 1
2 1
2 1
2 1
2 1
2 1
2 1
2 1
2 1
2 1
2 1
2 1
2 1
2 1
2 1
2 1
2 1
2 1
2 1
2 1
2 1
2 1
2 1
2 1
2 1
2 1
2 1
2 1
2 1
2 1
2 1
2 1
2 1
2 1
2 1
2 1
2 1
1
SHEETDATE
23
7 3 2 16 5 4
E
A
B
C
E
D
C
B
A
7 6 5 4
D
DEPARTMENT
SIZE
PROJECT DOCUMENT NUMBER REV
REVIEWER
DESIGNER
IN
IN
OUT
OUT
IN
IN
OUT
OUT
IN OUT
OUT
IN
IN
OUT
OUT
IN
C



CPU0 PCIE P2 TX CPU0 PCIE P3 TX
20210527 MODIFY FOR GT
Thu Aug 24 14:09:14 2023
MB FABCGTI
64 OF 365
V02
<NAME_2>
<NAME_1>
D IFF BU S_0.22U F 306
306
306
306
25
25
25
25
295
295
25
25
25
25
295
295
D IFF BU S_0.22U F
D IFF BU S_0.22U F
D IFF BU S_0.22U F
D IFF BU S_0.22U F
D IFF BU S_0.22U F
D IFF BU S_0.22U F
D IFF BU S_0.22U F
D IFF BU S_0.22U F
D IFF BU S_0.22U F
D IFF BU S_0.22U F
D IFF BU S_0.22U F
D IFF BU S_0.22U F
D IFF BU S_0.22U F
D IFF BU S_0.22U F
D IFF BU S_0.22U F
D IFF BU S_0.22U F
D IFF BU S_0.22U F
D IFF BU S_0.22U F
D IFF BU S_0.22U F
D IFF BU S_0.22U F
D IFF BU S_0.22U F
D IFF BU S_0.22U F
D IFF BU S_0.22U F
D IFF BU S_0.22U F
D IFF BU S_0.22U F
D IFF BU S_0.22U F
D IFF BU S_0.22U F
D IFF BU S_0.22U F
D IFF BU S_0.22U F
6.3V
X 6S
20%C0201
D IFF BU S_0.22U F
D IFF BU S_0.22U F
D IFF BU S_0.22U F
D IFF BU S_0.22U F
D IFF BU S_0.22U F
D IFF BU S_0.22U F
D IFF BU S_0.22U F
D IFF BU S_0.22U F
D IFF BU S_0.22U F
D IFF BU S_0.22U F
D IFF BU S_0.22U F
D IFF BU S_0.22U F
D IFF BU S_0.22U F
D IFF BU S_0.22U F
D IFF BU S_0.22U F
D IFF BU S_0.22U F
D IFF BU S_0.22U F
D IFF BU S_0.22U F
D IFF BU S_0.22U F
D IFF BU S_0.22U F
D IFF BU S_0.22U F
D IFF BU S_0.22U F
D IFF BU S_0.22U F
D IFF BU S_0.22U F
D IFF BU S_0.22U F
D IFF BU S_0.22U F
D IFF BU S_0.22U F
D IFF BU S_0.22U F
D IFF BU S_0.22U F
D IFF BU S_0.22U F
D IFF BU S_0.22U F
D IFF BU S_0.22U F
C0201 20% 6.3V
D IFF BU S_0.22U F
X 6S
D IFF BU S_0.22U F
P5E_CPU0_P3_TX_C_DP<7:0>
P5E_CPU0_P3_TX_C_DN<7:0>
P5E_CPU0_P3_TX_C_DP<15:8>
P5E_CPU0_P3_TX_C_DN<15:8>
P5E_CPU0_P3_TX_DN<7:0>
P5E_CPU0_P3_TX_DP<7:0>
P5E_CPU0_P3_TX_DP<15:8>
P5E_CPU0_P3_TX_DN<15:8>
P5E_CPU0_P2_TX_C_DN<7:0>
P5E_CPU0_P2_TX_C_DP<7:0>
CCBUPCIE AC-COUPLE CAPS 2/5
P5E_CPU0_P2_TX_DN<7:0>
P5E_CPU0_P2_TX_DP<7:0>
P5E_CPU0_P2_TX_DN<15:8>
P5E_CPU0_P2_TX_DP<15:8>
P5E_CPU0_P2_TX_C_DN<15:8>
P5E_CPU0_P2_TX_C_DP<15:8>
2 1
2 1
2 1
2 1
2 1
2 1
2 1
2 1
2 1
2 1
2 1
2 1
2 1
2 1
2 1
2 1
2 1
2 1
2 1
2 1
2 1
2 1
2 1
2 1
2 1
2 1
2 1
2 1
2 1
2 1
2 1
2 1
2 1
2 1
2 1
2 1
2 1
2 1
2 1
2 1
2 1
2 1
2 1
2 1
2 1
2 1
2 1
2 1
2 1
2 1
2 1
2 1
2 1
2 1
2 1
2 1
2 1
2 1
2 1
2 1
2 1
2 1
2 1
2 1
8
12
7
7
5
4
15
14
13
14
15
13
11
10
9
8
12
11
10
9
8
7
6
5
7
6
5
4
3
2
1
0
3
4
2
1
0
15
14
13
12
11
10
9
15
14
13
12
11
10
9
8
7
6
5
3
2
1
0
7
6
4
3
2
1
0
15
14
13
11
10
9
8
6
3
2
1
0
13
14
15
11
10
9
8
15
14
13
13
14
15
12
11
10
8
12
11
10
9
8
6
4
3
2
1
0
7
6
5
7
6
5
4
3
2
1
0
4
3
2
1
0
5
5
12
12
4
9
C898
C870
C871
C872
C873
C874
C875
C876
C877
C879
C878
C880
C881
C882
C883
C885
C884
C886
C887
C888
C889
C890
C891
C893
C892
C894
C895
C896
C897
C899
C900
C901
C839
C838
C840
C841
C843
C842
C844
C845
C846
C847
C848
C849
C850
C851
C853
C852
C854
C855
C856
C857
C858
C859
C860
C861
C862
C863
C865
C864
C866
C867
C868
C869
2 1
2 1
2 1
2 1
2 1
2 1
2 1
2 1
2 1
2 1
2 1
2 1
2 1
2 1
2 1
2 1
2 1
2 1
2 1
2 1
2 1
2 1
2 1
2 1
2 1
2 1
2 1
2 1
2 1
2 1
2 1
2 1
2 1
2 1
2 1
2 1
2 1
2 1
2 1
2 1
2 1
2 1
2 1
2 1
2 1
2 1
2 1
2 1
2 1
2 1
2 1
2 1
2 1
2 1
2 1
2 1
2 1
2 1
2 1
2 1
2 1
2 1
2 1
2 1
1
SHEETDATE
23
7 3 2 16 5 4
E
A
B
C
E
D
C
B
A
7 6 5 4
D
DEPARTMENT
SIZE
PROJECT DOCUMENT NUMBER REV
REVIEWER
DESIGNER
IN
INOUT
OUT
IN
IN
OUT
OUT
IN
OUT
OUT
IN
IN
OUT
OUT
IN
C



CPU1 PCIE P0 TXCPU0 PCIE G3 TX
20210527 MODIFY FOR GT
Thu Aug 24 14:09:15 2023
MB FABC
<NAME_2>
<NAME_1>
GTI V02
65 OF 365
317
317
317
317
51
51
51
51
23
23
23
23
131
131
131
131
D IFF BU S_0.22U F
D IFF BU S_0.22U F
D IFF BU S_0.22U F
D IFF BU S_0.22U F
D IFF BU S_0.22U F
D IFF BU S_0.22U F
D IFF BU S_0.22U F
D IFF BU S_0.22U F
D IFF BU S_0.22U F
D IFF BU S_0.22U F
D IFF BU S_0.22U F
D IFF BU S_0.22U F
D IFF BU S_0.22U F
D IFF BU S_0.22U F
D IFF BU S_0.22U F
D IFF BU S_0.22U F
D IFF BU S_0.22U F
D IFF BU S_0.22U F
D IFF BU S_0.22U F
D IFF BU S_0.22U F
D IFF BU S_0.22U F
D IFF BU S_0.22U F
D IFF BU S_0.22U F
D IFF BU S_0.22U F
D IFF BU S_0.22U F
D IFF BU S_0.22U F
D IFF BU S_0.22U F
D IFF BU S_0.22U F
20% 6.3VC0201
X 6S
D IFF BU S_0.22U F
D IFF BU S_0.22U F
D IFF BU S_0.22U F
D IFF BU S_0.22U F
D IFF BU S_0.22U F
D IFF BU S_0.22U F
D IFF BU S_0.22U F
D IFF BU S_0.22U F
D IFF BU S_0.22U F
D IFF BU S_0.22U F
D IFF BU S_0.22U F
D IFF BU S_0.22U F
D IFF BU S_0.22U F
D IFF BU S_0.22U F
D IFF BU S_0.22U F
D IFF BU S_0.22U F
D IFF BU S_0.22U F
D IFF BU S_0.22U F
D IFF BU S_0.22U F
D IFF BU S_0.22U F
D IFF BU S_0.22U F
D IFF BU S_0.22U F
D IFF BU S_0.22U F
D IFF BU S_0.22U F
D IFF BU S_0.22U F
D IFF BU S_0.22U F
D IFF BU S_0.22U F
D IFF BU S_0.22U F
D IFF BU S_0.22U F
D IFF BU S_0.22U F
D IFF BU S_0.22U F
D IFF BU S_0.22U F
20%
X 6S
6.3V
D IFF BU S_0.22U F
C0201
D IFF BU S_0.22U F
D IFF BU S_0.22U F
D IFF BU S_0.22U F
P5E_CPU1_P0_TX_C_DP<7:0>
P5E_CPU1_P0_TX_C_DN<7:0>
P5E_CPU1_P0_TX_C_DP<15:8>
P5E_CPU1_P0_TX_C_DN<15:8>
P5E_CPU1_P0_TX_DP<7:0>
P5E_CPU1_P0_TX_DN<7:0>
P5E_CPU1_P0_TX_DP<15:8>
P5E_CPU1_P0_TX_DN<15:8>
P5E_CPU0_G3_TX_DN<7:0>
CCBUPCIE AC-COUPLE CAPS 3/5
P5E_CPU0_G3_TX_DN<15:8>
P5E_CPU0_G3_TX_DP<15:8>
P5E_CPU0_G3_TX_DP<7:0>
P5E_CPU0_G3_TX_C_DN<15:8>
P5E_CPU0_G3_TX_C_DP<15:8>
P5E_CPU0_G3_TX_C_DN<7:0>
P5E_CPU0_G3_TX_C_DP<7:0>
2 1
2 1
2 1
2 1
2 1
2 1
2 1
2 1
2 1
2 1
2 1
2 1
2 1
2 1
2 1
2 1
2 1
2 1
2 1
2 1
2 1
2 1
2 1
2 1
2 1
2 1
2 1
2 1
2 1
2 1
2 1
2 1
2 1
2 1
2 1
2 1
2 1
2 1
2 1
2 1
2 1
2 1
2 1
2 1
2 1
2 1
2 1
2 1
2 1
2 1
2 1
2 1
2 1
2 1
2 1
2 1
2 1
2 1
2 1
2 1
2 1
2 1
2 1
2 1
11
13
10
5
0
1
0
1
3
2
4
2
3
4
5
6
5
6
7
7
8
9
10
9
11
12
11
10
12
13
15
13
15
14
0
0
1
1
2
2
3
4
3
4
5
5
6
6
8
8
9
9
10
10
11
12
12
13
14
13
14
15
15
8
4
15
14
15
14
13
13
12
12
11
10
9
10
9
8
8
7
7
6
6
5
5
4
3
2
2
1
1
0
0
15
14
13
15
14
12
11
12
11
9
8
10
9
8
7
7
6
5
6
4
3
2
4
3
2
1
0
1
0
3
7
14
11
7
C824
C825
C807
C806
C808
C809
C810
C811
C813
C812
C814
C815
C816
C817
C819
C818
C821
C820
C823
C822
C826
C827
C829
C830
C828
C833
C832
C831
C835
C834
C837
C836
C1576
C1577
C1549
C1548
C1550
C1792
C1552
C1553
C41
C1555
C1557
C1556
C1558
C1559
C1560
C1793
C1794
C44
C46
C1565
C1566
C47
C1568
C1569
C1571
C1570
C1572
C1573
C1574
C1575
C1578
C1579
2 1
2 1
2 1
2 1
2 1
2 1
2 1
2 1
2 1
2 1
2 1
2 1
2 1
2 1
2 1
2 1
2 1
2 1
2 1
2 1
2 1
2 1
2 1
2 1
2 1
2 1
2 1
2 1
2 1
2 1
2 1
2 1
2 1
2 1
2 1
2 1
2 1
2 1
2 1
2 1
2 1
2 1
2 1
2 1
2 1
2 1
2 1
2 1
2 1
2 1
2 1
2 1
2 1
2 1
2 1
2 1
2 1
2 1
2 1
2 1
2 1
2 1
2 1
2 1
1
SHEETDATE
23
7 3 2 16 5 4
E
A
B
C
E
D
C
B
A
7 6 5 4
D
DEPARTMENT
SIZE
PROJECT DOCUMENT NUMBER REV
REVIEWER
DESIGNER
OUT
OUT
OUT
OUT
IN
IN
IN
IN
OUT
OUT
OUT
OUT
IN
IN
IN
IN
C



CPU1 PCIE P1 TX CPU1 PCIE P2 TX
20210527 MODIFY FOR GT
Thu Aug 24 14:09:15 2023
V02GTI MB FABC
66 OF 365<NAME_2>
<NAME_1>
D IFF BU S_0.22U F
339
339
339
339
52
52
52
52
328
328
328
32851
51
51
51
D IFF BU S_0.22U F
D IFF BU S_0.22U F
D IFF BU S_0.22U F
D IFF BU S_0.22U F
D IFF BU S_0.22U F
D IFF BU S_0.22U F
D IFF BU S_0.22U F
D IFF BU S_0.22U F
D IFF BU S_0.22U F
D IFF BU S_0.22U F
D IFF BU S_0.22U F
D IFF BU S_0.22U F
D IFF BU S_0.22U F
D IFF BU S_0.22U F
D IFF BU S_0.22U F
D IFF BU S_0.22U F
D IFF BU S_0.22U F
D IFF BU S_0.22U F
D IFF BU S_0.22U F
D IFF BU S_0.22U F
D IFF BU S_0.22U F
D IFF BU S_0.22U F
D IFF BU S_0.22U F
D IFF BU S_0.22U F
D IFF BU S_0.22U F
D IFF BU S_0.22U F
D IFF BU S_0.22U F
D IFF BU S_0.22U F
D IFF BU S_0.22U F
D IFF BU S_0.22U F
D IFF BU S_0.22U F
D IFF BU S_0.22U F
C0201
X 6S
20% 6.3V
D IFF BU S_0.22U F
D IFF BU S_0.22U F
D IFF BU S_0.22U F
D IFF BU S_0.22U F
D IFF BU S_0.22U F
D IFF BU S_0.22U F
D IFF BU S_0.22U F
D IFF BU S_0.22U F
D IFF BU S_0.22U F
D IFF BU S_0.22U F
D IFF BU S_0.22U F
D IFF BU S_0.22U F
D IFF BU S_0.22U F
D IFF BU S_0.22U F
D IFF BU S_0.22U F
D IFF BU S_0.22U F
D IFF BU S_0.22U F
D IFF BU S_0.22U F
D IFF BU S_0.22U F
D IFF BU S_0.22U F
D IFF BU S_0.22U F
D IFF BU S_0.22U F
D IFF BU S_0.22U F
D IFF BU S_0.22U F
D IFF BU S_0.22U F
D IFF BU S_0.22U F
D IFF BU S_0.22U F
D IFF BU S_0.22U F
D IFF BU S_0.22U F
X 6S
C0201
D IFF BU S_0.22U F
20% 6.3V
D IFF BU S_0.22U F P5E_CPU1_P2_TX_C_DP<7:0>
P5E_CPU1_P2_TX_C_DN<7:0>
P5E_CPU1_P2_TX_C_DP<15:8>
P5E_CPU1_P2_TX_C_DN<15:8>
P5E_CPU1_P2_TX_DN<7:0>
P5E_CPU1_P2_TX_DP<7:0>
P5E_CPU1_P2_TX_DP<15:8>
P5E_CPU1_P2_TX_DN<15:8>
P5E_CPU1_P1_TX_C_DP<7:0>
P5E_CPU1_P1_TX_C_DN<7:0>
P5E_CPU1_P1_TX_C_DP<15:8>
P5E_CPU1_P1_TX_C_DN<15:8>
PCIE AC-COUPLE CAPS 4/5 CCBU
P5E_CPU1_P1_TX_DN<15:8>
P5E_CPU1_P1_TX_DP<15:8>
P5E_CPU1_P1_TX_DN<7:0>
P5E_CPU1_P1_TX_DP<7:0>
 2 1
2 1
2 1
2 1
2 1
2 1
2 1
2 1
2 1
2 1
2 1
2 1
2 1
2 1
2 1
2 1
2 1
2 1
2 1
2 1
2 1
2 1
2 1
2 1
2 1
2 1
2 1
2 1
2 1
2 1
2 1
2 1
2 1
2 1
2 1
2 1
2 1
2 1
2 1
2 1
2 1
2 1
2 1
2 1
2 1
2 1
2 1
2 1
2 1
2 1
2 1
2 1
2 1
2 1
2 1
2 1
2 1
2 1
2 1
2 1
2 1
2 1
2 1
2 1
13
12
0 0
1
2
4
5
6
7
0
1
2
3
4
5
6
7
8
9
10
11
12
13
14
15
8
9
10
14
15
0
1
2
4
3
0
1
3
4
5
6
7
5
6
7
8
9
10
11
12
8
9
10
11
13
15
14
13
14
15
2
3
12
12
11
5
4
15
15
14
13
14
13
11
10
11
12
10
9
8
9
8
15
14
13
15
14
13
12
11
10
12
10
11
9
8
9
8
7
7
6
5
6
4
3
2
3
2
1
0
1
0
7
7
6
4
5
6
3
2
4
3
2
1
1
0
5
C726
C710
C711
C713
C712
C714
C715
C716
C717
C718
C719
C720
C721
C723
C722
C724
C725
C727
C728
C729
C730
C731
C732
C733
C735
C734
C736
C737
C738
C739
C741
C740
C742
C743
C744
C745
C746
C747
C748
C749
C751
C750
C752
C753
C754
C755
C757
C756
C758
C759
C760
C761
C762
C763
C765
C764
C766
C767
C768
C769
C770
C771
C772
C773
2 1
2 1
2 1
2 1
2 1
2 1
2 1
2 1
2 1
2 1
2 1
2 1
2 1
2 1
2 1
2 1
2 1
2 1
2 1
2 1
2 1
2 1
2 1
2 1
2 1
2 1
2 1
2 1
2 1
2 1
2 1
2 1
2 1
2 1
2 1
2 1
2 1
2 1
2 1
2 1
2 1
2 1
2 1
2 1
2 1
2 1
2 1
2 1
2 1
2 1
2 1
2 1
2 1
2 1
2 1
2 1
2 1
2 1
2 1
2 1
2 1
2 1
2 1
2 1
1
SHEETDATE
23
7 3 2 16 5 4
E
A
B
C
E
D
C
B
A
7 6 5 4
D
DEPARTMENT
SIZE
PROJECT DOCUMENT NUMBER REV
REVIEWER
DESIGNER
IN
IN
OUT
OUT
OUT
OUT
IN
IN
IN
IN
OUT
OUT
OUT
OUT
IN
IN
C



CPU1 PCIE G1 TX
CPU1 PCIE P4 TX
CPU1 PCIE P3 TX
CPU0 PCIE P4 TX
Thu Aug 24 14:09:21 2023
MB FABC
<NAME_2>
<NAME_1>
GTI V02
67 OF 365
26
26
52
52
52
52
350
350
350
350
145
145
49
49
53
53
49
49
137
137
144
144
137
137
D IFF BU S_0.22U F
D IFF BU S_0.22U F
D IFF BU S_0.22U F
D IFF BU S_0.22U F
D IFF BU S_0.22U F
D IFF BU S_0.22U F
D IFF BU S_0.22U F
D IFF BU S_0.22U F
D IFF BU S_0.22U F
D IFF BU S_0.22U F
D IFF BU S_0.22U F
D IFF BU S_0.22U F
D IFF BU S_0.22U F
D IFF BU S_0.22U F
D IFF BU S_0.22U F
D IFF BU S_0.22U F
D IFF BU S_0.22U F
D IFF BU S_0.22U F
D IFF BU S_0.22U F
D IFF BU S_0.22U F
D IFF BU S_0.22U F
D IFF BU S_0.22U F
D IFF BU S_0.22U F
D IFF BU S_0.22U F
D IFF BU S_0.22U F
D IFF BU S_0.22U F
D IFF BU S_0.22U F
D IFF BU S_0.22U F
D IFF BU S_0.22U F
D IFF BU S_0.22U F
20% 6.3VC0201
X 6S
D IFF BU S_0.22U F
D IFF BU S_0.22U F
D IFF BU S_0.22U F
D IFF BU S_0.22U F
D IFF BU S_0.22U F
D IFF BU S_0.22U F
D IFF BU S_0.22U F
D IFF BU S_0.22U F
D IFF BU S_0.22U F
D IFF BU S_0.22U F
D IFF BU S_0.22U F
D IFF BU S_0.22U F
D IFF BU S_0.22U F
D IFF BU S_0.22U F
D IFF BU S_0.22U F
D IFF BU S_0.22U F
D IFF BU S_0.22U F
D IFF BU S_0.22U F
D IFF BU S_0.22U F
D IFF BU S_0.22U F
D IFF BU S_0.22U F
D IFF BU S_0.22U F
D IFF BU S_0.22U F
D IFF BU S_0.22U F
D IFF BU S_0.22U F
D IFF BU S_0.22U F
D IFF BU S_0.22U F
D IFF BU S_0.22U F
D IFF BU S_0.22U F
D IFF BU S_0.22U F
D IFF BU S_0.22U F
D IFF BU S_0.22U F
C0201
X 6S
20% 6.3V
D IFF BU S_0.22U F
D IFF BU S_0.22U F
P3E_CPU0_P4_TX_DN<3:0>
P3E_CPU0_P4_TX_DP<3:0>
P5E_CPU1_P3_TX_DN<7:0>
P5E_CPU1_P3_TX_DP<7:0>
P5E_CPU1_P3_TX_DP<15:8>
P5E_CPU1_P3_TX_DN<15:8>
P5E_CPU1_P3_TX_C_DP<7:0>
P5E_CPU1_P3_TX_C_DN<7:0>
P5E_CPU1_P3_TX_C_DP<15:8>
P5E_CPU1_P3_TX_C_DN<15:8>
P3E_CPU0_P4_TX_C_DP<3:0>
P3E_CPU0_P4_TX_C_DN<3:0>
P5E_CPU1_G1_TX_DP<7:0>
P5E_CPU1_G1_TX_DN<7:0>
P3E_CPU1_P4_TX_DN<3:0>
P3E_CPU1_P4_TX_DP<3:0>
P5E_CPU1_G1_TX_DN<15:8>
P5E_CPU1_G1_TX_DP<15:8>
P5E_CPU1_G1_TX_C_DN<15:8>
P5E_CPU1_G1_TX_C_DP<15:8>
P3E_CPU1_P4_TX_C_DP<3:0>
P3E_CPU1_P4_TX_C_DN<3:0>
P5E_CPU1_G1_TX_C_DP<7:0>
P5E_CPU1_G1_TX_C_DN<7:0>
D IFF BU S_0.22U F
D IFF BU S_0.22U F
D IFF BU S_0.22U F
D IFF BU S_0.22U F
D IFF BU S_0.22U F
D IFF BU S_0.22U F
D IFF BU S_0.22U F
X 6S
20%C0201 6.3V
D IFF BU S_0.22U F
D IFF BU S_0.22U F
D IFF BU S_0.22U F
D IFF BU S_0.22U F
D IFF BU S_0.22U F
D IFF BU S_0.22U F
D IFF BU S_0.22U F
D IFF BU S_0.22U F
C0201 20%
X 6S
6.3V
D IFF BU S_0.22U F
CCBUPCIE AC-COUPLE CAPS 5/5
2 1
2 1
2 1
2 1
2 1
2 1
2 1
2 1
2 1
2 1
2 1
2 1
2 1
2 1
2 1
2 1
2 1
2 1
2 1
2 1
2 1
2 1
2 1
2 1
2 1
2 1
2 1
2 1
2 1
2 1
2 1
2 1
2 1
2 1
2 1
2 1
2 1
2 1
2 1
2 1
2 1
2 1
2 1
2 1
2 1
2 1
2 1
2 1
2 1
2 1
2 1
2 1
2 1
2 1
2 1
2 1
2 1
2 1
2 1
2 1
2 1
2 1
2 1
2 1
2 1
2 1
2 1
2 1
2 1
2 1
2 1
2 1
2 1
2 1
2 1
2 1
2 1
2 1
2 1
2 1
2 1
2 1
2 1
2 1
2 1
2 1
2 1
2 1
2 1
2 1
2 1
2 1
2 1
2 1
2 1
2 1
0
3
1
2
3
2
1
3
2
1
3
2
1
0
0
0
1
2
1
2
3
4
5
3
4
5
6
7
6
7
8
9
10
8
9
10
11
12
11
12
0
0
0
0
1
2
1
2
3
5
4
3
4
5
6
7
6
7
8
10
9
8
9
10
11
12
11
12
14
13
15
13
15
14
13
15
14
13
14
15
3
2
1
3
2
1
3
3
2
1
2
1
0
0
0
1
2
0
1
2
0
0
0
0
1
2
1
2
3
5
4
3
4
6
7
6
5
7
8
9
10
8
9
10
11
12
11
12
3
4
4
5
6
5
7
6
7
8
9
10
9
8
10
11
12
11
12
14
13
15
13
15
14
13
15
14
14
13
15
3
C678
C679
C680
C681
C682
C683
C684
C685
C686
C687
C689
C688
C690
C691
C692
C56
C694
C695
C696
C697
C699
C698
C700
C701
C703
C702
C704
C705
C707
C706
C708
C709
C9104
C9105
C9102
C9103
C1100
C1101
C1098
C1099
C49
C48
C50
C51
C52
C53
C54
C55
C1524
C1525
C1527
C1526
C1528
C1529
C1530
C1531
C1532
C1533
C1534
C1535
C1536
C1537
C1538
C1539
C1540
C1541
C1542
C1543
C1545
C1544
C1546
C1547
C1995
C1996
C1993
C1994
C1991
C1992
C1989
C1990
2 1
2 1
2 1
2 1
2 1
2 1
2 1
2 1
2 1
2 1
2 1
2 1
2 1
2 1
2 1
2 1
2 1
2 1
2 1
2 1
2 1
2 1
2 1
2 1
2 1
2 1
2 1
2 1
2 1
2 1
2 1
2 1
2 1
2 1
2 1
2 1
2 1
2 1
2 1
2 1
2 1
2 1
2 1
2 1
2 1
2 1
2 1
2 1
2 1
2 1
2 1
2 1
2 1
2 1
2 1
2 1
2 1
2 1
2 1
2 1
2 1
2 1
2 1
2 1
1
SHEETDATE
23
7 3 2 16 5 4
E
A
B
C
E
D
C
B
A
7 6 5 4
D
DEPARTMENT
SIZE
PROJECT DOCUMENT NUMBER REV
REVIEWER
DESIGNER
IN
IN
OUT
OUT
OUT
OUT
OUT
OUT
IN
IN
OUT
OUT
IN
IN
IN
INOUT
OUT
IN
IN
OUT
OUT
IN
IN
C



5
105
5
10
10
5
5
PVDDCR_SOC_P0: 22PCS 22UF ON TOP PVDDIO_P0: 7PCS 22UF ON TOP
PVDD18_S5_P0: 3PCS 22UF ON TOP
PVDD11_S3_P0: 16PCS 22UF ON TOP
Thu Aug 24 14:08:48 2023<NAME_2>
<NAME_1>
MB FABCGTI V02
68 OF 365
P V DDCR_S O C_P 0
P V DDCR_S O C_P 0
P V DDCR_S O C_P 0
P V DDIO _P 0
P V DD18_S 5_P 0
P V DD11_S 3_P 0
P V DD11_S 3_P 0
C0402
C0402C0402
C0402C0402
C0402C0402C0402
C0402C0402
C0402
C0402
C0402
C0402
C0402C0402C0402C0402C0402C0402C0402
C0402C0402C0402
C0402C0402C0402C0402C0402C0402C0402C0402
C0402C0402C0402C0402
C0402C0402
C0402C0402
C0402 C0402
C0402
C0402C0402
C0402C0402
C0402
4V
4V4V
4V4V
4V4V4V
4V4V
4V
4V
4V
4V
4V4V4V4V4V4V4V
4V4V4V
4V4V4V4V4V4V4V4V
4V4V4V4V
4V4V
4V4V
4V 4V
4V
4V4V
4V4V
4V
22UF
22UF22UF
22UF22UF
22UF22UF22UF
22UF22UF
22UF
22UF
22UF
22UF
22UF22UF22UF22UF22UF22UF22UF
22UF22UF22UF
22UF22UF22UF22UF22UF22UF22UF22UF
22UF22UF22UF22UF
22UF22UF
22UF22UF
22UF 22UF
22UF
22UF22UF
22UF22UF
22UF
20%
20%20%
20%20%
20%20%20%
20%20%
20%
20%
20%
20%
20%20%20%20%20%20%20%
20%20%20%
20%20%20%20%20%20%20%20%
20%20%20%20%
20%20%
20%20%
20% 20%
20%
20%20%
20%20%
20%
X 6S
X 6SX 6S
X 6SX 6S
X 6SX 6SX 6S
X 6SX 6S
X 6S
X 6S
X 6S
X 6S
X 6SX 6SX 6SX 6SX 6SX 6SX 6S
X 6SX 6SX 6S
X 6SX 6SX 6SX 6SX 6SX 6SX 6SX 6S
X 6SX 6SX 6SX 6S
X 6SX 6S
X 6SX 6S
X 6S X 6S
X 6S
X 6SX 6S
X 6SX 6S
X 6S
CPU0 CAVITY TOP DECOUPLING CAPS
2
1 C3899
2
1 C3898
2
1 C2149
2
1 C2145
2
1 C2141
2
1 C2136
2
1 C2131
2
1 C3897
2
1 C2164
2
1 C2163
2
1 C2162
2
1 C2160
2
1 C2158
2
1 C2156
2
1 C2153
2
1 C2150
2
1 C2146
2
1 C2142
2
1 C3893
2
1 C3892
2
1 C3891
2
1 C3890
2
1 C2137
2
1 C2132
2
1 C2138
2
1 C2133
2
1 C2147
2
1 C2161
2
1 C3896
2
1 C2159
2
1 C2157
2
1 C3895
2
1 C3894
2
1 C2154
2
1 C2151
2
1 C2155
2
1 C2152
2
1 C2143
2
1 C2139
2
1 C2148
2
1 C2144
2
1 C2140
2
1 C2134
2
1 C2129
2
1 C2135
2
1 C3889
2
1 C2130
2
1 C3888
1
SHEETDATE
23
7 3 2 16 5 4
E
A
B
C
E
D
C
B
A
7 6 5 4
D
DEPARTMENT
SIZE
PROJECT DOCUMENT NUMBER REV
REVIEWER
DESIGNER
C



PVDDCR_CPU1_P0: 45PCS 22UF ON BOTPVDDCR_CPU0_P0: 45PCS 22UF ON BOT
5
5
5 1010
Thu Aug 24 14:08:48 2023<NAME_2>
<NAME_1>
MB FABCGTI V02
69 OF 365
P V DDCR_CP U0_P 0
P V DDCR_CP U1_P 0
P V DDCR_CP U1_P 0
P V DDCR_CP U0_P 0
P V DDCR_CP U1_P 0
P V DDCR_CP U1_P 0
P V DDCR_CP U1_P 0P V DDCR_CP U0_P 0
P V DDCR_CP U0_P 0
P V DDCR_CP U0_P 0
X 6S X 6S
20%
C0402C0402
C0402C0402C0402
C0402C0402
C0402C0402
C0402 C0402C0402
C0402C0402
C0402C0402
C0402C0402
C0402C0402C0402
C0402C0402C0402
C0402C0402
C0402C0402
C0402
C0402C0402C0402C0402
C0402C0402
C0402C0402
C0402C0402
C0402C0402
C0402
C0402C0402
C0402
C0402
C0402
C0402C0402
C0402C0402
C0402C0402
C0402 C0402C0402
C0402C0402
C0402C0402
C0402
C0402C0402
C0402C0402
C0402
C0402
C0402C0402
C0402C0402
C0402 C0402C0402C0402
C0402C0402
C0402
C0402 C0402C0402
C0402C0402
C0402C0402
C0402C0402
C0402
C0402
C0402
4V4V
4V4V4V
4V4V
4V4V
4V 4V4V
4V4V
4V4V
4V4V
4V4V4V
4V4V4V
4V4V
4V4V
4V
4V4V4V4V
4V4V
4V4V
4V4V
4V4V
4V
4V4V
4V
4V
4V
4V4V
4V4V
4V4V
4V 4V4V
4V4V
4V4V
4V
4V4V
4V4V
4V
4V
4V4V
4V4V
4V 4V4V4V
4V4V
4V
4V 4V4V
4V4V
4V4V
4V4V
4V
4V
4V
22UF22UF
22UF22UF22UF
22UF22UF
22UF22UF
22UF 22UF22UF
22UF22UF
22UF22UF
22UF22UF
22UF22UF22UF
22UF22UF22UF
22UF22UF
22UF22UF
22UF
22UF22UF22UF22UF
22UF22UF
22UF22UF
22UF22UF
22UF22UF
22UF
22UF22UF
22UF
22UF
22UF
22UF22UF
22UF22UF
22UF22UF
22UF 22UF22UF
22UF22UF
22UF22UF
22UF
22UF22UF
22UF22UF
22UF
22UF
22UF22UF
22UF22UF
22UF 22UF22UF22UF
22UF22UF
22UF
22UF 22UF22UF
22UF22UF
22UF22UF
22UF22UF
22UF
22UF
22UF
20%20%
20%20%20%
20%20%
20%20%
20% 20%20%
20%20%
20%20%
20%20%
20%20%20%
20%20%20%
20%20%
20%20%
20%
20%20%20%20%
20%20%
20%20%
20%20%
20%20%
20%
20%20%
20%
20%
20%
20%20%
20%20%
20%20%
20% 20%20%
20%20%
20%20%
20%
20%20%
20%20%
20%
20%
20%20%
20%20%
20% 20%20%20%
20%20%
20%
20% 20%20%
20%20%
20%20%
20%20%
20%
20%
X 6SX 6S
X 6SX 6SX 6S
X 6SX 6S
X 6SX 6S
X 6S X 6SX 6S
X 6SX 6S
X 6SX 6S
X 6SX 6S
X 6SX 6SX 6S
X 6SX 6SX 6S
X 6SX 6S
X 6SX 6S
X 6S
X 6SX 6SX 6SX 6S
X 6SX 6S
X 6SX 6S
X 6SX 6S
X 6SX 6S
X 6S
X 6SX 6S
X 6S
X 6S
X 6S
X 6SX 6S
X 6SX 6S
X 6SX 6S
X 6S X 6SX 6S
X 6SX 6S
X 6SX 6S
X 6S
X 6SX 6S
X 6SX 6S
X 6S
X 6S
X 6SX 6S
X 6SX 6S
X 6S X 6SX 6S
X 6SX 6S
X 6S
X 6S X 6SX 6S
X 6SX 6S
X 6SX 6S
X 6SX 6S
X 6S
X 6S
CPU0 CAVITY BOT DECOUPLING CAPS 1/3
2
1 C272
2
1 C2253
2
1 C2248
2
1 C2254
2
1 C2249
2
1 C2243
2
1 C2237
2
1 C2244
2
1 C2238
2
1 C2231
2
1 C2225
2
1 C2219
2
1 C2232
2
1 C2226
2
1 C2220
2
1 C2213
2
1 C2207
2
1 C2214
2
1 C2208
2
1 C2255
2
1 C2250
2
1 C2256
2
1 C2251
2
1 C2245
2
1 C2239
2
1 C2246
2
1 C2240
2
1 C2233
2
1 C2227
2
1 C2221
2
1 C2234
2
1 C2228
2
1 C2222
2
1 C2215
2
1 C2209
2
1 C2216
2
1 C2210
2
1 C2229
2
1 C2223
2
1 C2217
2
1 C2211
2
1 C2201
2
1 C278
2
1 C2202
2
1 C279
2
1 C276
2
1 C274
2
1 C277
2
1 C275
2
1 C270
2
1 C273
2
1 C271
2
1 C267
2
1 C268
2
1 C4179
2
1 C4178
2
1 C263
2
1 C1922
2
1 C2203
2
1 C2198
2
1 C2204
2
1 C2199
2
1 C2195
2
1 C2192
2
1 C2196
2
1 C2193
2
1 C2205
2
1 C2189
2
1 C2185
2
1 C2190
2
1 C2186
2
1 C2181
2
1 C2182
2
1 C2177
2
1 C2173
2
1 C2178
2
1 C2174
2
1 C2183
2
1 C10179
2
1 C2175
2
1 C251
2
1 C245
2
1 C252
2
1 C246
2
1 C2169
2
1 C2165
2
1 C2170
2
1 C2166
2
1 C2171
2
1 C2167
1
SHEETDATE
23
7 3 2 16 5 4
E
A
B
C
E
D
C
B
A
7 6 5 4
D
DEPARTMENT
SIZE
PROJECT DOCUMENT NUMBER REV
REVIEWER
DESIGNER
C



5 10 10
105
5
10
10
10
10
5
5
5
PVDDIO_P0: 24PCS 22UF ON BOT
10
10
5
5
10
10
10
10
5
5
5
5
5
PVDDCR_SOC_P0: 77PCS 22UF ON BOT
5
PVDD11_S3_P0: 42PCS 22UF ON BOT
Thu Aug 24 14:08:49 2023<NAME_2>
<NAME_1>
MB FABCGTI V02
70 OF 365
P V DDCR_S O C_P 0
P V DD11_S 3_P 0
P V DD11_S 3_P 0
P V DD11_S 3_P 0
P V DD11_S 3_P 0
P V DD11_S 3_P 0
P V DDCR_S O C_P 0
P V DDCR_S O C_P 0
P V DDCR_S O C_P 0
P V DDCR_S O C_P 0
P V DDCR_S O C_P 0
P V DDCR_S O C_P 0
P V DDCR_S O C_P 0
P V DDIO _P 0
P V DDIO _P 0
P V DDIO _P 0
C0402
C0402C0402
C0402
C0402
C0402
C0402
C0402C0402
C0402
C0402
C0402
C0402
C0402
C0402C0402C0402
C0402
C0402
C0402
C0402
C0402
C0402
C0402
C0402
C0402
C0402
C0402
C0402
C0402C0402
C0402
C0402
C0402
C0402
C0402
C0402
C0402
C0402
C0402
C0402C0402
C0402C0402
C0402
C0402
C0402
C0402
C0402C0402C0402
C0402C0402
C0402
C0402C0402
C0402
C0402
C0402C0402
C0402C0402
C0402
C0402
C0402C0402
C0402C0402C0402
C0402C0402
C0402
C0402
C0402
C0402C0402
C0402C0402
C0402C0402
C0402C0402
C0402C0402
C0402C0402
C0402
C0402
C0402
C0402C0402
C0402C0402
C0402
C0402
C0402
C0402C0402
C0402
C0402C0402
C0402C0402
C0402C0402
C0402
C0402
C0402
C0402
C0402
C0402
C0402
C0402
C0402C0402
C0402
C0402
C0402
C0402
C0402
C0402C0402
C0402C0402
C0402
C0402
C0402
C0402
C0402
C0402
C0402
C0402
C0402
C0402
C0402
C0402
C0402C0402
C0402
C0402
C0402
C0402
C0402
4V
4V4V
4V
4V
4V
4V
4V4V
4V
4V
4V
4V
4V
4V4V4V
4V
4V
4V
4V
4V
4V
4V
4V
4V
4V
4V
4V
4V4V
4V
4V
4V
4V
4V
4V
4V
4V
4V
4V4V
4V4V
4V
4V
4V
4V
4V4V4V
4V4V
4V
4V4V
4V
4V
4V4V
4V4V
4V
4V
4V4V
4V4V4V
4V4V
4V
4V
4V
4V4V
4V4V
4V4V
4V4V
4V4V
4V4V
4V
4V
4V
4V4V
4V4V
4V
4V
4V
4V4V
4V
4V4V
4V4V
4V4V
4V
4V
4V
4V
4V
4V
4V
4V
4V4V
4V
4V
4V
4V
4V
4V4V
4V4V
4V
4V
4V
4V
4V
4V
4V
4V
4V
4V
4V
4V
4V4V
4V
4V
4V
4V
4V
22UF
22UF22UF
22UF
22UF
22UF
22UF
22UF22UF
22UF
22UF
22UF
22UF
22UF
22UF22UF22UF
22UF
22UF
22UF
22UF
22UF
22UF
22UF
22UF
22UF
22UF
22UF
22UF
22UF22UF
22UF
22UF
22UF
22UF
22UF
22UF
22UF
22UF
22UF
22UF22UF
22UF22UF
22UF
22UF
22UF
22UF
22UF22UF22UF
22UF22UF
22UF
22UF22UF
22UF
22UF
22UF22UF
22UF22UF
22UF
22UF
22UF22UF
22UF22UF22UF
22UF22UF
22UF
22UF
22UF
22UF22UF
22UF22UF
22UF22UF
22UF22UF
22UF22UF
22UF22UF
22UF
22UF
22UF
22UF22UF
22UF22UF
22UF
22UF
22UF
22UF22UF
22UF
22UF22UF
22UF22UF
22UF22UF
22UF
22UF
22UF
22UF
22UF
22UF
22UF
22UF
22UF22UF
22UF
22UF
22UF
22UF
22UF
22UF22UF
22UF22UF
22UF
22UF
22UF
22UF
22UF
22UF
22UF
22UF
22UF
22UF
22UF
22UF
22UF22UF
22UF
22UF
22UF
22UF
22UF
20%
20%20%
20%
20%
20%
20%
20%20%
20%
20%
20%
20%
20%
20%20%20%
20%
20%
20%
20%
20%
20%
20%
20%
20%
20%
20%
20%
20%20%
20%
20%
20%
20%
20%
20%
20%
20%
20%
20%20%
20%20%
20%
20%
20%
20%
20%20%20%
20%20%
20%
20%20%
20%
20%
20%20%
20%20%
20%
20%
20%20%
20%20%20%
20%20%
20%
20%
20%
20%20%
20%20%
20%20%
20%20%
20%20%
20%20%
20%
20%
20%
20%20%
20%20%
20%
20%
20%
20%20%
20%
20%20%
20%20%
20%20%
20%
20%
20%
20%
20%
20%
20%
20%
20%20%
20%
20%
20%
20%
20%
20%20%
20%20%
20%
20%
20%
20%
20%
20%
20%
20%
20%
20%
20%
20%
20%20%
20%
20%
20%
20%
20%
X 6S
X 6SX 6S
X 6S
X 6S
X 6S
X 6S
X 6SX 6S
X 6S
X 6S
X 6S
X 6S
X 6S
X 6SX 6SX 6S
X 6S
X 6S
X 6S
X 6S
X 6S
X 6S
X 6S
X 6S
X 6S
X 6S
X 6S
X 6S
X 6SX 6S
X 6S
X 6S
X 6S
X 6S
X 6S
X 6S
X 6S
X 6S
X 6S
X 6SX 6S
X 6SX 6S
X 6S
X 6S
X 6S
X 6S
X 6SX 6SX 6S
X 6SX 6S
X 6S
X 6SX 6S
X 6S
X 6S
X 6SX 6S
X 6SX 6S
X 6S
X 6S
X 6SX 6S
X 6SX 6SX 6S
X 6SX 6S
X 6S
X 6S
X 6S
X 6SX 6S
X 6SX 6S
X 6SX 6S
X 6SX 6S
X 6SX 6S
X 6SX 6S
X 6S
X 6S
X 6S
X 6SX 6S
X 6SX 6S
X 6S
X 6S
X 6S
X 6SX 6S
X 6S
X 6SX 6S
X 6SX 6S
X 6SX 6S
X 6S
X 6S
X 6S
X 6S
X 6S
X 6S
X 6S
X 6S
X 6SX 6S
X 6S
X 6S
X 6S
X 6S
X 6S
X 6SX 6S
X 6SX 6S
X 6S
X 6S
X 6S
X 6S
X 6S
X 6S
X 6S
X 6S
X 6S
X 6S
X 6S
X 6S
X 6SX 6S
X 6S
X 6S
X 6S
X 6S
X 6S
CPU0 CAVITY BOT DECOUPLING CAPS 2/3
2
1 C2654
2
1 C2649
2
1 C2655
2
1 C2650
2
1 C2643
2
1 C2637
2
1 C2644
2
1 C2638
2
1 C2631
2
1 C2625
2
1 C2632
2
1 C2626
2
1 C2620
2
1 C2618
2
1 C2611
2
1 C2604
2
1 C2619
2
1 C2612
2
1 C2613
2
1 C2605
2
1 C2606
2
1 C2656
2
1 C2651
2
1 C2657
2
1 C2652
2
1 C2645
2
1 C2639
2
1 C2646
2
1 C2640
2
1 C2658
2
1 C3935
2
1 C2653
2
1 C3934
2
1 C2647
2
1 C2648
2
1 C2641
2
1 C2642
2
1 C2633
2
1 C2627
2
1 C2634
2
1 C2628
2
1 C2621
2
1 C2622
2
1 C2614
2
1 C2607
2
1 C2615
2
1 C2608
2
1 C2635
2
1 C2636
2
1 C2629
2
1 C2630
2
1 C2623
2
1 C2624
2
1 C2616
2
1 C2617
2
1 C2609
2
1 C2610
2
1 C3933
2
1 C2597
2
1 C2590
2
1 C2598
2
1 C2599
2
1 C2591
2
1 C2592
2
1 C2583
2
1 C2576
2
1 C2584
2
1 C2585
2
1 C2577
2
1 C2578
2
1 C2569
2
1 C2562
2
1 C2570
2
1 C2571
2
1 C2563
2
1 C2564
2
1 C2555
2
1 C2548
2
1 C2541
2
1 C2556
2
1 C2557
2
1 C2549
2
1 C2550
2
1 C2542
2
1 C2543
2
1 C2600
2
1 C2593
2
1 C2601
2
1 C2594
2
1 C2595
2
1 C2586
2
1 C2579
2
1 C2587
2
1 C2588
2
1 C2580
2
1 C2581
2
1 C2602
2
1 C2603
2
1 C2596
2
1 C3932
2
1 C2589
2
1 C2582
2
1 C2572
2
1 C2565
2
1 C2573
2
1 C2574
2
1 C2566
2
1 C2567
2
1 C2558
2
1 C2551
2
1 C2544
2
1 C2559
2
1 C2552
2
1 C2560
2
1 C2553
2
1 C2545
2
1 C2546
2
1 C2575
2
1 C2568
2
1 C3931
2
1 C3930
2
1 C2561
2
1 C2554
2
1 C2547
2
1 C3929
2
1 C3928
2
1 C3927
2
1 C2534
2
1 C2527
2
1 C2535
2
1 C2536
2
1 C2528
2
1 C2529
2
1 C2537
2
1 C2530
2
1 C2538
2
1 C2539
2
1 C2531
2
1 C2532
2
1 C2540
2
1 C2533
2
1 C3926
2
1 C3925
1
SHEETDATE
23
7 3 2 16 5 4
E
A
B
C
E
D
C
B
A
7 6 5 4
D
DEPARTMENT
SIZE
PROJECT DOCUMENT NUMBER REV
REVIEWER
DESIGNER
C



5 10
PVDD33_S5: 2PCS 22UF ON BOT
PVDD18_S5_P0: 12PCS 22UF ON BOT
Thu Aug 24 14:08:49 2023<NAME_2>
<NAME_1>
MB FABCGTI V02
71 OF 365
P V DD_33_S 5
P V DD18_S 5_P 0
P V DD18_S 5_P 0
X6S
6.3V
10UF
C0402
20%
X6S
6.3V
10UF
20%
C0402
CPU0 CAVITY BOT DECOUPLING CAPS 3/3
X 6S
X 6S X 6S X 6S X 6S X 6S X 6S X 6S X 6SX 6S
X 6S
X 6S
20%
20% 20% 20% 20% 20% 20% 20% 20%20%
20%
20%
22UF
22UF 22UF 22UF 22UF 22UF 22UF 22UF 22UF22UF
22UF
22UF
4V
4V 4V 4V 4V 4V 4V 4V 4V4V
4V
4V
C0402
C0402 C0402 C0402 C0402 C0402 C0402 C0402 C0402C0402
C0402
C0402
2
1 C2526
2
1 C2525
2
1 C2524
2
1 C2523
2
1 C2522
2
1 C2521
2
1 C2520
2
1 C2518
2
1 C2516
2
1 C2517
2
1 C2513
2
1 C2514
C2512 C2515
2
1
2
1
1
SHEETDATE
23
7 3 2 16 5 4
E
A
B
C
E
D
C
B
A
7 6 5 4
D
DEPARTMENT
SIZE
PROJECT DOCUMENT NUMBER REV
REVIEWER
DESIGNER
C



PVDDIO_P1: 7PCS 22UF ON TOP
5
PVDD18_S5_P1: 3PCS 22UF ON TOP
10
10
5
5
105
5
PVDDCR_SOC_P1: 22PCS 22UF ON TOP
PVDD11_S3_P1: 16PCS 22UF ON TOP
Thu Aug 24 14:08:49 2023<NAME_2>
<NAME_1>
MB FABCGTI V02
72 OF 365
P V DDCR_S O C_P 1
P V DDCR_S O C_P 1
P V DDIO _P 1
P V DD18_S 5_P 1
P V DD11_S 3_P 1
P V DD11_S 3_P 1
P V DDCR_S O C_P 1
C0402
C0402
C0402
C0402C0402C0402C0402C0402C0402C0402
C0402C0402C0402 C0402
C0402
C0402
C0402
C0402
C0402
C0402
C0402
C0402
C0402
C0402C0402C0402
C0402C0402
C0402
C0402
C0402
C0402 C0402C0402C0402C0402
C0402
C0402C0402C0402
C0402C0402C0402
C0402C0402
C0402C0402C0402
4V
4V
4V
4V4V4V4V4V4V4V
4V4V4V 4V
4V
4V
4V
4V
4V
4V
4V
4V
4V
4V4V4V
4V4V
4V
4V
4V
4V 4V4V4V4V
4V
4V4V4V
4V4V4V
4V4V
4V4V4V
22UF
22UF
22UF
22UF22UF22UF22UF22UF22UF22UF
22UF22UF22UF 22UF
22UF
22UF
22UF
22UF
22UF
22UF
22UF
22UF
22UF
22UF22UF22UF
22UF22UF
22UF
22UF
22UF
22UF 22UF22UF22UF22UF
22UF
22UF22UF22UF
22UF22UF22UF
22UF22UF
22UF22UF22UF
20%
20%
20%
20%20%20%20%20%20%20%
20%20%20% 20%
20%
20%
20%
20%
20%
20%
20%
20%
20%
20%20%20%
20%20%
20%
20%
20%
20% 20%20%20%20%
20%
20%20%20%
20%20%20%
20%20%
20%20%20%
X 6S
X 6S
X 6S
X 6SX 6SX 6SX 6SX 6SX 6SX 6S
X 6SX 6SX 6S X 6S
X 6S
X 6S
X 6S
X 6S
X 6S
X 6S
X 6S
X 6S
X 6S
X 6SX 6SX 6S
X 6SX 6S
X 6S
X 6S
X 6S
X 6S X 6SX 6SX 6SX 6S
X 6S
X 6SX 6SX 6S
X 6SX 6SX 6S
X 6SX 6S
X 6SX 6SX 6S
CPU1 CAVITY TOP DECOUPLING CAPS
2
1 C2276
2
1 C3911
2
1 C3910
2
1 C2278
2
1 C2274
2
1 C2270
2
1 C2265
2
1 C2260
2
1 C3909
2
1 C2293
2
1 C2292
2
1 C2290
2
1 C3908
2
1 C2288
2
1 C3907
2
1 C2286
2
1 C3906
2
1 C2283
2
1 C2284
2
1 C2280
2
1 C2281
2
1 C2277
2
1 C2273
2
1 C2272
2
1 C2268
2
1 C2269
2
1 C2263
2
1 C2264
2
1 C2291
2
1 C2289
2
1 C2287
2
1 C2285
2
1 C3901
2
1 C2282
2
1 C2279
2
1 C2275
2
1 C3905
2
1 C3904
2
1 C3903
2
1 C2271
2
1 C2266
2
1 C3902
2
1 C2267
2
1 C2258
2
1 C2259
2
1 C3900
2
1 C2261
2
1 C2262
1
SHEETDATE
23
7 3 2 16 5 4
E
A
B
C
E
D
C
B
A
7 6 5 4
D
DEPARTMENT
SIZE
PROJECT DOCUMENT NUMBER REV
REVIEWER
DESIGNER
C



PVDDCR_CPU1_P1: 45PCS 22UF ON BOT
105
5
105
5
PVDDCR_CPU0_P1: 45PCS 22UF ON BOT
Thu Aug 24 14:08:49 2023<NAME_2>
<NAME_1>
MB FABCGTI V02
73 OF 365
C0402
P V DDCR_CP U0_P 1
P V DDCR_CP U1_P 1
P V DDCR_CP U1_P 1
P V DDCR_CP U0_P 1
P V DDCR_CP U1_P 1
P V DDCR_CP U1_P 1
P V DDCR_CP U1_P 1P V DDCR_CP U0_P 1
P V DDCR_CP U0_P 1
P V DDCR_CP U0_P 1
C0402
C0402
C0402
C0402
C0402
C0402
C0402
C0402
C0402
C0402
C0402
C0402C0402
C0402
C0402C0402C0402
C0402
C0402
C0402
C0402
C0402
C0402C0402
C0402C0402C0402
C0402
C0402C0402C0402C0402C0402C0402C0402C0402
C0402
C0402
C0402
C0402
C0402C0402
C0402
C0402
C0402
C0402
C0402
C0402C0402
C0402C0402C0402
C0402
C0402
C0402
C0402
C0402C0402
C0402C0402
C0402
C0402
C0402
C0402
C0402C0402C0402
C0402C0402
C0402C0402C0402
C0402
C0402
C0402
C0402
C0402
C0402
C0402C0402C0402C0402C0402C0402C0402C0402
C0402
C0402
C0402
4V
4V
4V
4V
4V
4V
4V
4V
4V
4V
4V
4V4V
4V
4V4V4V
4V
4V
4V
4V
4V
4V4V
4V4V4V
4V
4V4V4V4V4V4V4V4V
4V
4V
4V
4V
4V4V
4V
4V
4V
4V
4V
4V4V
4V4V4V
4V
4V
4V
4V
4V4V
4V4V
4V
4V
4V
4V
4V
4V4V4V
4V4V
4V4V4V
4V
4V
4V
4V
4V
4V
4V4V4V4V4V4V4V4V
4V
4V
4V
22UF
22UF
22UF
22UF
22UF
22UF
22UF
22UF
22UF
22UF
22UF
22UF22UF
22UF
22UF22UF22UF
22UF
22UF
22UF
22UF
22UF
22UF22UF
22UF22UF22UF
22UF
22UF22UF22UF22UF22UF22UF22UF22UF
22UF
22UF
22UF
22UF
22UF22UF
22UF
22UF
22UF
22UF
22UF
22UF22UF
22UF22UF22UF
22UF
22UF
22UF
22UF
22UF22UF
22UF22UF
22UF
22UF
22UF
22UF
22UF
22UF22UF22UF
22UF22UF
22UF22UF22UF
22UF
22UF
22UF
22UF
22UF
22UF
22UF22UF22UF22UF22UF22UF22UF22UF
22UF
22UF
22UF
20%
20%
20%
20%
20%
20%
20%
20%
20%
20%
20%
20%20%
20%
20%20%20%
20%
20%
20%
20%
20%
20%20%
20%20%20%
20%
20%20%20%20%20%20%20%20%
20%
20%
20%
20%
20%20%
20%
20%
20%
20%
20%
20%20%
20%20%20%
20%
20%
20%
20%
20%20%
20%20%
20%
20%
20%
20%
20%
20%20%20%
20%20%
20%20%20%
20%
20%
20%
20%
20%
20%
20%20%20%20%20%20%20%20%
20%
20%
20%
X 6S
X 6S
X 6S
X 6S
X 6S
X 6S
X 6S
X 6S
X 6S
X 6S
X 6S
X 6SX 6S
X 6S
X 6SX 6SX 6S
X 6S
X 6S
X 6S
X 6S
X 6S
X 6SX 6S
X 6SX 6SX 6S
X 6S
X 6SX 6SX 6SX 6SX 6SX 6SX 6SX 6S
X 6S
X 6S
X 6S
X 6S
X 6SX 6S
X 6S
X 6S
X 6S
X 6S
X 6S
X 6SX 6S
X 6SX 6SX 6S
X 6S
X 6S
X 6S
X 6S
X 6SX 6S
X 6SX 6S
X 6S
X 6S
X 6S
X 6S
X 6S
X 6SX 6SX 6S
X 6SX 6S
X 6SX 6SX 6S
X 6S
X 6S
X 6S
X 6S
X 6S
X 6S
X 6SX 6SX 6SX 6SX 6SX 6SX 6SX 6S
X 6S
X 6S
X 6S
CPU1 CAVITY BOT DECOUPLING CAPS 1/3
2
1 C2350
2
1 C2402
2
1 C2397
2
1 C2392
2
1 C2386
2
1 C2380
2
1 C2374
2
1 C2368
2
1 C2362
2
1 C2403
2
1 C2404
2
1 C2405
2
1 C2398
2
1 C2399
2
1 C2393
2
1 C2394
2
1 C2400
2
1 C2395
2
1 C2387
2
1 C2388
2
1 C2381
2
1 C2375
2
1 C2382
2
1 C2389
2
1 C2383
2
1 C2377
2
1 C2376
2
1 C2369
2
1 C2370
2
1 C2363
2
1 C2364
2
1 C2371
2
1 C2365
2
1 C2378
2
1 C2372
2
1 C2366
2
1 C2356
2
1 C2345
2
1 C2340
2
1 C2335
2
1 C2330
2
1 C2324
2
1 C2318
2
1 C2312
2
1 C2357
2
1 C2358
2
1 C2351
2
1 C2352
2
1 C2359
2
1 C2353
2
1 C2346
2
1 C2347
2
1 C2341
2
1 C2342
2
1 C2348
2
1 C2343
2
1 C2360
2
1 C2354
2
1 C2336
2
1 C2337
2
1 C2331
2
1 C2332
2
1 C2338
2
1 C2333
2
1 C2325
2
1 C2319
2
1 C2326
2
1 C2320
2
1 C2313
2
1 C2314
2
1 C2327
2
1 C2321
2
1 C2315
2
1 C2322
2
1 C2316
2
1 C2306
2
1 C2300
2
1 C2294
2
1 C2307
2
1 C2308
2
1 C2301
2
1 C2302
2
1 C2309
2
1 C2303
2
1 C2295
2
1 C2296
2
1 C2297
2
1 C2310
2
1 C2304
2
1 C2298
1
SHEETDATE
23
7 3 2 16 5 4
E
A
B
C
E
D
C
B
A
7 6 5 4
D
DEPARTMENT
SIZE
PROJECT DOCUMENT NUMBER REV
REVIEWER
DESIGNER
C



PVDDIO_P1: 24PCS 22UF ON BOT
10
10
10
10
10
PVDD11_S3_P1: 42PCS 22UF ON BOT
5
5
10
10
10
10
5
5
5
5
10
10
10
5
5
5
5
5
5
5
5
PVDDCR_SOC_P1: 77PCS 22UF ON BOT
Thu Aug 24 14:08:50 2023<NAME_2>
<NAME_1>
MB FABCGTI V02
74 OF 365
P V DD11_S 3_P 1
P V DD11_S 3_P 1
P V DD11_S 3_P 1
P V DD11_S 3_P 1
P V DD11_S 3_P 1
P V DDCR_S O C_P 1
P V DDCR_S O C_P 1
P V DDCR_S O C_P 1
P V DDCR_S O C_P 1
P V DDCR_S O C_P 1
P V DDCR_S O C_P 1
P V DDIO _P 1
P V DDIO _P 1
P V DDIO _P 1
P V DDCR_S O C_P 1
P V DDCR_S O C_P 1
C0402
C0402
C0402
C0402
C0402
C0402
C0402
C0402
C0402C0402
C0402
C0402
C0402
C0402
C0402
C0402
C0402
C0402
C0402
C0402C0402C0402
C0402
C0402
C0402
C0402C0402
C0402C0402
C0402
C0402
C0402
C0402
C0402C0402
C0402
C0402
C0402
C0402
C0402C0402
C0402
C0402
C0402
C0402
C0402
C0402C0402C0402
C0402
C0402
C0402
C0402
C0402
C0402
C0402
C0402C0402
C0402C0402
C0402
C0402 C0402C0402
C0402
C0402
C0402
C0402
C0402
C0402
C0402
C0402C0402
C0402
C0402 C0402 C0402 C0402
C0402
C0402
C0402
C0402
C0402C0402
C0402
C0402
C0402
C0402
C0402
C0402C0402
C0402
C0402
C0402C0402
C0402C0402
C0402
C0402
C0402
C0402
C0402
C0402
C0402
C0402
C0402
C0402
C0402C0402
C0402
C0402
C0402
C0402
C0402
C0402
C0402
C0402C0402C0402
C0402
C0402C0402
C0402C0402
C0402
C0402C0402
C0402
C0402
C0402
C0402
C0402
C0402C0402C0402C0402C0402
C0402C0402
C0402
C0402
C0402
C0402
4V
4V
4V
4V
4V
4V
4V
4V
4V4V
4V
4V
4V
4V
4V
4V
4V
4V
4V
4V4V4V
4V
4V
4V
4V4V
4V4V
4V
4V
4V
4V
4V4V
4V
4V
4V
4V
4V4V
4V
4V
4V
4V
4V
4V4V4V
4V
4V
4V
4V
4V
4V
4V
4V4V
4V4V
4V
4V 4V4V
4V
4V
4V
4V
4V
4V
4V
4V4V
4V
4V 4V 4V 4V
4V
4V
4V
4V
4V4V
4V
4V
4V
4V
4V
4V4V
4V
4V
4V4V
4V4V
4V
4V
4V
4V
4V
4V
4V
4V
4V
4V
4V4V
4V
4V
4V
4V
4V
4V
4V
4V4V4V
4V
4V4V
4V4V
4V
4V4V
4V
4V
4V
4V
4V
4V4V4V4V4V
4V4V
4V
4V
4V
4V
22UF
22UF
22UF
22UF
22UF
22UF
22UF
22UF
22UF22UF
22UF
22UF
22UF
22UF
22UF
22UF
22UF
22UF
22UF
22UF22UF22UF
22UF
22UF
22UF
22UF22UF
22UF22UF
22UF
22UF
22UF
22UF
22UF22UF
22UF
22UF
22UF
22UF
22UF22UF
22UF
22UF
22UF
22UF
22UF
22UF22UF22UF
22UF
22UF
22UF
22UF
22UF
22UF
22UF
22UF22UF
22UF22UF
22UF
22UF 22UF22UF
22UF
22UF
22UF
22UF
22UF
22UF
22UF
22UF22UF
22UF
22UF 22UF 22UF 22UF
22UF
22UF
22UF
22UF
22UF22UF
22UF
22UF
22UF
22UF
22UF
22UF22UF
22UF
22UF
22UF22UF
22UF22UF
22UF
22UF
22UF
22UF
22UF
22UF
22UF
22UF
22UF
22UF
22UF22UF
22UF
22UF
22UF
22UF
22UF
22UF
22UF
22UF22UF22UF
22UF
22UF22UF
22UF22UF
22UF
22UF22UF
22UF
22UF
22UF
22UF
22UF
22UF22UF22UF22UF22UF
22UF22UF
22UF
22UF
22UF
22UF
20%
20%
20%
20%
20%
20%
20%
20%
20%20%
20%
20%
20%
20%
20%
20%
20%
20%
20%
20%20%20%
20%
20%
20%
20%20%
20%20%
20%
20%
20%
20%
20%20%
20%
20%
20%
20%
20%20%
20%
20%
20%
20%
20%
20%20%20%
20%
20%
20%
20%
20%
20%
20%
20%20%
20%20%
20%
20% 20%20%
20%
20%
20%
20%
20%
20%
20%
20%20%
20%
20% 20% 20% 20%
20%
20%
20%
20%
20%20%
20%
20%
20%
20%
20%
20%20%
20%
20%
20%20%
20%20%
20%
20%
20%
20%
20%
20%
20%
20%
20%
20%
20%20%
20%
20%
20%
20%
20%
20%
20%
20%20%20%
20%
20%20%
20%20%
20%
20%20%
20%
20%
20%
20%
20%
20%20%20%20%20%
20%20%
20%
20%
20%
20%
X 6S
X 6S
X 6S
X 6S
X 6S
X 6S
X 6S
X 6S
X 6SX 6S
X 6S
X 6S
X 6S
X 6S
X 6S
X 6S
X 6S
X 6S
X 6S
X 6SX 6SX 6S
X 6S
X 6S
X 6S
X 6SX 6S
X 6SX 6S
X 6S
X 6S
X 6S
X 6S
X 6SX 6S
X 6S
X 6S
X 6S
X 6S
X 6SX 6S
X 6S
X 6S
X 6S
X 6S
X 6S
X 6SX 6SX 6S
X 6S
X 6S
X 6S
X 6S
X 6S
X 6S
X 6S
X 6SX 6S
X 6SX 6S
X 6S
X 6S X 6SX 6S
X 6S
X 6S
X 6S
X 6S
X 6S
X 6S
X 6S
X 6SX 6S
X 6S
X 6S X 6S X 6S X 6S
X 6S
X 6S
X 6S
X 6S
X 6SX 6S
X 6S
X 6S
X 6S
X 6S
X 6S
X 6SX 6S
X 6S
X 6S
X 6SX 6S
X 6SX 6S
X 6S
X 6S
X 6S
X 6S
X 6S
X 6S
X 6S
X 6S
X 6S
X 6S
X 6SX 6S
X 6S
X 6S
X 6S
X 6S
X 6S
X 6S
X 6S
X 6SX 6SX 6S
X 6S
X 6SX 6S
X 6SX 6S
X 6S
X 6SX 6S
X 6S
X 6S
X 6S
X 6S
X 6S
X 6SX 6SX 6SX 6SX 6S
X 6SX 6S
X 6S
X 6S
X 6S
X 6S
CPU1 CAVITY BOT DECOUPLING CAPS 2/3
2
1 C2428
2
1 C2435
2
1 C2442
2
1 C2127
2
1 C2509
2
1 C2122
2
1 C2123
2
1 C2128
2
1 C2124
2
1 C2510
2
1 C2511
2
1 C2125
2
1 C2126
2
1 C3922
2
1 C3921
2
1 C2116
2
1 C2117
2
1 C2507
2
1 C2110
2
1 C2112
2
1 C2111
2
1 C2109
2
1 C2498
2
1 C2493
2
1 C2107
2
1 C2108
2
1 C2104
2
1 C2105
2
1 C2102
2
1 C2484
2
1 C2106
2
1 C2103
2
1 C2477
2
1 C2478
2
1 C2470
2
1 C2471
2
1 C2479
2
1 C2472
2
1 C2118
2
1 C2508
2
1 C2503
2
1 C2119
2
1 C2120
2
1 C2114
2
1 C2113
2
1 C2504
2
1 C2505
2
1 C2499
2
1 C2494
2
1 C2500
2
1 C2501
2
1 C2495
2
1 C2496
2
1 C2121
2
1 C2115
2
1 C2506
2
1 C2502
2
1 C2497
2
1 C2489
2
1 C2485
2
1 C2490
2
1 C2491
2
1 C2486
2
1 C2487
2
1 C2480
2
1 C2473
2
1 C2474
2
1 C2481
2
1 C2482
2
1 C2475
2
1 C2492
2
1 C2488
2
1 C3920
2
1 C2483
2
1 C2476
2
1 C3919
2
1 C2463
2
1 C2464
2
1 C2456
2
1 C2457
2
1 C2465
2
1 C2458
2
1 C2451
2
1 C2450
2
1 C2449
2
1 C2443
2
1 C2436
2
1 C2444
2
1 C2437
2
1 C2429
2
1 C2421
2
1 C2422
2
1 C2430
2
1 C2423
2
1 C2414
2
1 C2415
2
1 C2407
2
1 C2408
2
1 C2416
2
1 C2409
2
1 C2466
2
1 C2467
2
1 C2459
2
1 C2460
2
1 C2468
2
1 C2461
2
1 C2454
2
1 C2453
2
1 C2452
2
1 C2445
2
1 C2446
2
1 C2438
2
1 C2439
2
1 C2447
2
1 C2440
2
1 C2469
2
1 C2462
2
1 C3918
2
1 C2455
2
1 C2448
2
1 C3917
2
1 C2441
2
1 C3916
2
1 C2431
2
1 C2432
2
1 C2424
2
1 C2425
2
1 C2433
2
1 C2426
2
1 C2417
2
1 C2418
2
1 C2410
2
1 C2411
2
1 C2419
2
1 C2412
2
1 C2434
2
1 C3915
2
1 C2427
2
1 C3914
2
1 C2420
2
1 C3913
2
1 C2413
2
1 C3912
1
SHEETDATE
23
7 3 2 16 5 4
E
A
B
C
E
D
C
B
A
7 6 5 4
D
DEPARTMENT
SIZE
PROJECT DOCUMENT NUMBER REV
REVIEWER
DESIGNER
C



5 10
PVDD18_S5_P1: 12PCS 22UF ON BOT
PVDD33_S5: 2PCS 22UF ON BOT
Thu Aug 24 14:08:50 2023<NAME_2>
<NAME_1>
MB FABCGTI V02
75 OF 365
P V DD_33_S 5
P V DD18_S 5_P 1
P V DD18_S 5_P 1
X6S
6.3V
10UF
20%
C0402
X6S
6.3V
10UF
20%
C0402
CPU1 CAVITY BOT DECOUPLING CAPS 3/3
X 6S
X 6S X 6S X 6S X 6S X 6S X 6S X 6S X 6SX 6S
X 6S
X 6S
20%
20% 20% 20% 20% 20% 20% 20% 20%20%
20%
20%
22UF
22UF 22UF 22UF 22UF 22UF 22UF 22UF 22UF22UF
22UF
22UF
4V
4V 4V 4V 4V 4V 4V 4V 4V4V
4V
4V
C0402
C0402 C0402 C0402 C0402 C0402 C0402 C0402 C0402C0402
C0402
C0402
2
1 C2673
2
1 C2672
2
1 C2671
2
1 C2670
2
1 C2669
2
1 C2668
2
1 C2667
2
1 C2665
2
1 C2663
2
1 C2664
2
1 C2660
2
1 C2661
C2659 C2662
2
1
2
1
1
SHEETDATE
23
7 3 2 16 5 4
E
A
B
C
E
D
C
B
A
7 6 5 4
D
DEPARTMENT
SIZE
PROJECT DOCUMENT NUMBER REV
REVIEWER
DESIGNER
C



UART_CPU0_SCM_UART1_TX
CLK_CPU1_RTCCLK 0: NORMAL MODE, 32KHZ XTAL AS SOURCE
BYPASS RTC
1: RTCCLK IS INPUT & USED AS BYPASS CLK
1: TOP HALF 64MB ROM
0: BOTTOM HALF 64MB ROM
ALTERNATE IMAGE
01: SPI ROM(DEFAULT)
1: INTERNAL CLKGEN MODE
0: EXTERNAL CLKGEN MODE
CLKGEN SELECTION
CPU1 NET NAME
SPI_CPU0_CLK
0
PD_ESPI_CPU1_CLK2
0
00: RSVD
ROMTYPE
CPU0_ROM_TYPE_SELECT
0
RTCCLK
1
CPU0 NET NAMEPU/PD (DEFAULT)
CPU0
ESPI_CLK2||AGPIO74
ESPI_CLK1
50K PD
AGPIO109
UART1_TXD||AGPIO142
CPUX PIN NAME
0
DESCRIPTION
1
(DEFAULT)
SPI_CPU1_CLK
1X: ESPI
0PD
PD
50K PU
1
CPU1 STRAP
50K PD
50K PU
ESPI_CLK0
CPU0 STRAP
INTERNAL
PD_ESPI_CPU0_CLK2 RSVD0
CLK_ESPI_CPU0_CLK1
CLK_CPU0_RTCCLK
CPU1
Thu Aug 24 14:08:50 2023<NAME_2>
<NAME_1>
MB FABCGTI V02
76 OF 365
P V DD18_S 5_P 1
P V DD18_S 5_P 0
56 76
76 56
76 56
55 76
29 76 81 150
76 29
76 28
27 76 164
28 76 55
29 76 77
28 76 55
76 28
76 29
29 76 77
56 76
29 76 81 150
27 76 164
55 76
S P I_CP U1_CLK
P D_E S P I_CP U1_CLK 2
P D_E S P I_CP U1_CLK 2
CLK _CP U1_RTCCLK
E MP TY
CPU HW STRAP PIN
E MP TY5%10K CLK _E S P I_CP U0_CLK 1
E MP TY5%10K P D_E S P I_CP U0_CLK 2
E MP TY CP U0_RO M_TY P E _S E LE CT
E MP TY5%10K UA RT_CP U0_S CM_UA RT1_TX
E MP TY5%10K CLK _CP U0_RTCCLK
5%10K E MP TY
E MP TY5%10K
0402LF
10K
1/16W
E MP TY5%10K S P I_CP U0_CLK
CHIP5% CLK _CP U0_RTCCLK
10K 5% CHIP CP U0_RO M_TY P E _S E LE CT
5% CHIP10K P D_E S P I_CP U0_CLK 2
10K CHIP5% S P I_CP U0_CLK
CHIP5%10K
5%10K CHIP S P I_CP U1_CLK
CHIP5%10K
CHIP1K 1%
10K
CLK _E S P I_CP U0_CLK 1CHIP1%30K
UA RT_CP U0_S CM_UA RT1_TX
5%10K
5%
CLK _CP U1_RTCCLK
21R6098
21R743
21R1502
21R760
21R754
21R1501
21R736
21
R730
21R753
21R750
21R742
21R739
21R740
21R737
21R729
21R751
21R748
21R747
1
SHEETDATE
23
7 3 2 16 5 4
E
A
B
C
E
D
C
B
A
7 6 5 4
D
DEPARTMENT
SIZE
PROJECT DOCUMENT NUMBER REV
REVIEWER
DESIGNER
OUT
OUT
OUT
OUT
OUT
OUT
OUT
OUT
OUT
OUT
OUT
OUT
OUT
OUT
OUT
OUT
OUT
OUT
C



CPU0 QSPI0 TO SCM QSPI0
Thu Aug 24 14:08:50 2023<NAME_2>
<NAME_1>
MB FABCGTI V02
77 OF 365
P V DD18_S 5_P 0
P V DD18_S 5_P 0
P V DD18_S 5_P 0
P 3V 3_A UX
P 3V 3_A UX
P 3V 3_A UXP V DD18_S 5_P 0
77 150
77
29 77
29 77
29 77
29 77
29 77
29 77
81 77
29 77
77150
77150
77
2977
2977
2977
2976
77150
77150
77150
77150
77150
77 150
77 150
77 150
77 150
77 150
77 150
81
7781
2977
2977
2977
2977
S P I_CP U0_LV C3_TP M_CS _N
S P I_CP U0_LV C3_S CM_CS 1_N
1/16W
E MP TY
10%
25V
SMLF
0402
25V
IC
S P I_CP U0_D3
S P I_CP U0_D2
S P I_CP U0_D1
10%
X 7R
S P I_CP U0_CS 1_N
S P I_CP U0_TP M_CS _N
S P I_CP U0_CS 0_N
0402
X 7R X 7R
10K
1%
CHIP
ROM_LS_EN
S P I_CP U0_D0
CPU SPI LEVEL SHIFT
X 7R
0.1UF
25V
10%
S P I_CP U0_LV C3_S CM_D3
SPI_CPU0_LVC3_TPM_CS_N
SPI_CPU0_LVC3_SCM_CS1_N
S P I_CP U0_CS 1_N
0.1UF
S P I_CP U0_TP M_CS _N
S P I_CP U0_CS 0_N
S P I_CP U0_CLK
0.1UF
S P I_CP U0_LV C3_S CM_D2
S P I_CP U0_LV C3_S CM_D1
S P I_CP U0_LV C3_S CM_D0
S P I_CP U0_LV C3_S CM_CLK
S P I_CP U0_LV C3_S CM_CS 0_N
S P I_CP U0_LV C3_S CM_D1
33.2 S P I_CP U0_LV C3_S CM_D0
10%
25V
49.9
4.7K
5%
1/16W
CHIP
4.7K
5%
CHIP
0 S P I_CP U0_LV C3_S CM_D3
0S P I_CP U0_LV C3_CS 0_N S P I_CP U0_LV C3_S CM_CS 0_N
S P I_CP U0_LV C3_CS 1_N
0 S P I_CP U0_LV C3_S CM_D2
E MP TY
1K
1%
E MP TY
1K
1%
E MP TY
1K
1/16W
1%
1K
1%
E MP TY
1/16W
1K
1%
1K
E MP TY
1/16W
1%
E MP TY
1K
1%
E MP TY
1K
1%
E MP TY
1K
1%
1K
E MP TY
1%
1K
1/16W
CHIP
1%
1K
CHIP
1/16W
1%
1K
1/16W
CHIP
1%
S P I_CP U0_LV C3_CLK S P I_CP U0_LV C3_S CM_CLK
0.1UF
0402
S P I_CP U0_LV C3_D1
S P I_CP U0_LV C3_D0
S P I_CP U0_LV C3_D2
S P I_CP U0_LV C3_D3
P I4ULS 3V 304A ZMA E X
IC
ROM_SD_LS_OE
SMLF
5%
1/16W
33
0402LF
33
33
SPI_C PU 0_R 1_D 1
SPI_C PU 0_R 1_D 3
SPI_C PU 0_R 1_D 2
SPI_C PU 0_R 1_D 0
33
RO M_LS _E N
CHIP
S P I_CP U0_D1
S P I_CP U0_D0
S P I_CP U0_D2
S P I_CP U0_D3
0
S N74A V C4T774P W R
33
S P I_CP U0_LV C3_R_TP M_CS _N 33
0402
U54
R608
21 R602
21 R603
21 R604
21 R605
21 R607
21 R606
R1655
21 R600
R1547
2
1
R1529
2
1
R1530
2
1
R1531
2
1
R1532
2
1
R129
2
1
R128
2
1
R127
2
1
R21
2
1
R20
2
1
R601
2
1
R659
2
1
R811
2
1
R610
2
1C1103
2
1 C1105
2
1C1102
2
1 C1104
U53
R1567
111
612
7
8
9
10
5
4
3
2
1516
9
10
8
7
2
1
11
12
13
14
6
5
4
3
GND
B4
B3
B2
B1
VCCA
A4
EN
VCCB
A3
A2
A1
VCCA VCCB
B1
B2
B3
B4
GND
OE
DIR4
DIR3
A4
A3
A2
A1
DIR2
DIR1
21
21R8008
21R8007
21R8006
21R8005
2
1
2
1
2
1
1
SHEETDATE
23
7 3 2 16 5 4
E
A
B
C
E
D
C
B
A
7 6 5 4
D
DEPARTMENT
SIZE
PROJECT DOCUMENT NUMBER REV
REVIEWER
DESIGNER
OUT
BI
BI
BI
BI
IN
IN
OUT
OUT
BI
BI
BI
BI
OUT
IN
IN
OUT
OUT
IN
OUT
OUT
IN
OUT
OUT
OUT
OUT
OUT
OUT
OUT
BI
BI
OUT
OUT
OUT
C



PWROK TO VR RST
VID:VDDCR_CPU*/VDDCR_SOC/VDDIO
Thu Aug 24 14:08:50 2023<NAME_2>
<NAME_1>
MB FABCGTI V02
78 OF 365
P 1V 8_A UX
P 1V 8_A UX
558185
288185
200
193
210
217
P W RG D_CP U1_P W RO K
1/16W
E MP TY
5%
10K
0402LF
P W RG D_CP U0_P W RO K
1/16W
E MP TY
5%
10K
0402LF
P V DDCR_CP U1_P 0_RE S E T_N
P V DDCR_CP U0_P 0_RE S E T_N
0.1UF
25V
0402
S MLF
0402
S MLF
25V
S N74LV C2G 07DCK R
0.1UF
S N74LV C2G 07DCK R
10%
10%
IC
X 7R
IC
X 7R
P V DDCR_CP U0_P 1_RE S E T_N
P V DDCR_CP U1_P 1_RE S E T_N
CPU PWROK
52
43
61
U40
2
1
C224
52
43
61
U29
2
1
C223
2
1
R703
2
1
R702
VCCGND
2Y
1Y
2A
1A
VCCGND
2Y
1Y
2A
1A
1
SHEETDATE
23
7 3 2 16 5 4
E
A
B
C
E
D
C
B
A
7 6 5 4
D
DEPARTMENT
SIZE
PROJECT DOCUMENT NUMBER REV
REVIEWER
DESIGNER
IN
IN
OUT
OUT
OUT
OUT
C



Thu Aug 24 10:14:00 2023<NAME_2>
<NAME_1>
MB FABCGTI V02
79 OF 365
Blank
1
SHEETDATE
23
7 3 2 16 5 4
E
A
B
C
E
D
C
B
A
7 6 5 4
D
DEPARTMENT
SIZE
PROJECT DOCUMENT NUMBER REV
REVIEWER
DESIGNER
C



BANK0 P3V3_AUX
TBC
TBC
TBC
Thu Aug 24 14:09:23 2023<NAME_2>
<NAME_1>
MB FABCGTI V02
80 OF 365
FM_BOAR D _BMC _SKU _ID 1
150 151
142
142
150
150
257
193
150
257
257
210
257
257
132 139 241 246 251 253
234
150
151
151
361
137
137
151
151
137
137
150 151
150
125
125 246
142
362
140
263 268
188
150
249
159
83159
254
150151
171
159
83159
151150
151150
150151
150151
159
84
84
83133139
152
234
83159
159
83159
171
145
83
145
82
137 138
83
85 171
85 171
150
83
85 171
85 171
172
241
151
151
83 150
85150151
84
150151
269
83134135248
269
263268
34
34
84
84
145
83134135136
151150
85
136
137
131
131
131
131
144
150151
210
33
33
33
33
33
0
0
0
0
0
0
0
0
0
0
0
0
CHIP
E MP TY
0
33
33
33
33
33
33
33
33
33
33
33
33
33
33
33
33
0
0
100
0
0
CLK _G E N2_B MC_RC_O E _R_N
P 1V 8_RE TIME R_CP U1_R_E N
S G P IO _S CM_CLK _<1>
FM_OC P_V3_2_AU X_PW R _R _ENFM_O CP _V 3_2_A UX _P W R_E N
O CP _V 3_2_P 3V 3_P LD_R_P W RG D
CLK _G E N2_G P U_FP G A _O E _R_N
FM_S O L_UA RT_CH_S E L
FM_UA RTS W _LS B _N
FM_LE D_P W RG D_P V DD18_S 5_P 1
P V DDCR_CP U0_P 0_E N
FPGA_IO3V3_RSVD_1
FM_LE D_P W RG D_P V DDCR_CP U1_P 1
FM_LE D_P W RG D_P V DD11_S 3_P 1
P W RG D_P V DDCR_S O C_P 1
FM_LE D_P W RG D_P V DDCR_S O C_P 1
FM_LE D_P W RG D_P V DDIO _P 1
RS T_S MB _S W ITCH_N
CLK _G E N2_B MC_RC_O E _N
SMB_1_PLD _3V3AU X_SD A_R 2
PR SN T_C ABLE_GPU _B3_ISO_R _N
FM_UA RTS W _MS B _N
SMB_2_PLD _3V3AU X_SC L_R 1
SMB_2_PLD _3V3AU X_SD A_R 1
P1V8_R ETIMER _C PU 0_ENP 1V 8_RE TIME R_CP U0_R_E N
S G P IO _O CP _V 3_2_LD_N
S G P IO _O CP _V 3_2_CLK
S CM_S P A RE _0
S CM_S P A RE _1
S G P IO _O CP _V 3_2_DA TA O UT
S G P IO _O CP _V 3_2_DA TA IN
RS T_MB _S TB Y _N
S CM_RO T_CP U_RS T_R_N
GPU _3V3IO_R SVD 3_FFU _ISO
PR SN T_C ABLE_GPU _B3_ISO_N
P 12V _O CP _V 3_2_P LD_P W RG D
P1V8_R ETIMER _C PU 1_EN
H P_LVC 3_OC P_V3_2_PR SN T2_PLD _N
IRQ _S ML1_P MB US _A LE RT_N
PW R GD _P5V_R 2
RST_SRST_PLD_BMC_NRST_SRST_PLD_BMC_R_N
PR SN T_OC P_V3_2_N
P W RG D_P 5V
S CM_S Y S _P W RO K
SMB_BMC _SW B_EN
SMB_2_PLD _3V3AU X_SC L_R 2
FM_I3C_CP U0_MUX 1_S E L
FM_I3C_CP U1_MUX 0_O E _N
PW R GD _PS_PW R OK_PLD _ISO_R
FM_U V_AD R _TR IGGER _R _N
FM_I3C_CP U0_MUX 0_O E _R_N
FM_I3C_CP U1_MUX 0_R_S E L
FM_I3C_CP U1_MUX 1_O E _R_N
FM_I3C_CP U0_MUX 1_R_S E L
S CM_JTA G _MUX _R_S 1
FM_I3C_CP U0_MUX 1_O E _R_N
S CM_JTA G _MUX _R_S 0
S G P IO _S CM_DI_R<0>
S G P IO _S CM_INTR_R_N
FM_I3C_CP U1_MUX 1_R_S E L
S G P IO _S CM_LD_<1>
S CM_JTA G _MUX _S 1
FM_I3C_CP U0_MUX 0_S E L
FM_I3C_CP U0_MUX 1_O E _N
S G P IO _S CM_DI_<0>
S G P IO _S CM_INTR_N
S G P IO _S CM_DO _<1>
S G P IO _S CM_RE S E T_N
FM_I3C_CP U1_MUX 1_S E L
FM_BOAR D _BMC _SKU _ID 3
FM_BOAR D _BMC _SKU _ID 4
FM_S Y S _THRO TTLE _N
FM_I3C_CP U0_MUX 0_R_S E L
V IRTUA L_RE S E A T_FP G A _R_N V IRTUA L_RE S E A T_FP G A _N
CLK _G E N2_G P U_FP G A _O E _N
FM_I3C_CP U0_MUX 0_O E _N
FM_I3C_CP U1_MUX 0_S E L
FM_I3C_CP U1_MUX 1_O E _N
FM_I3C_CP U1_MUX 0_O E _R_N
S CM_JTA G _MUX _S 0
E1S_0_PERST1_CLKREQ_N
E1S_0_PRSNT_N
FM_OC P_V3_2_PW R _GOOD
CP LD_JTA G _E N
JTA G _S CM_P LD_TDO
JTA G _S CM_P LD_TDI
LCMX O 3LF-9400C-5B G 484C
IC
SMLF
IC
FPGA 1/6
V IRTUA L_RE S E A T
CP LD_P RO G RA MN
JTA G _S CM_P LD_TMS
JTA G _S CM_P LD_TCK
LCMX O 3LF-9400C-5B G 484C
SMLF
JTA G _S CM_TRS T_N JTA G _S CM_TRS T_R_N
33.2
FM_FAN _PW R _EN
33.2
SMB_1_PLD _3V3AU X_SC L_R 1
SMB_1_PLD _3V3AU X_SD A_R 1
S CM_S Y S _P W RB TN_N
HP _LV C3_O CP _V 3_2_P 12V _P W RG D_R
GPU _3V3IO_R SVD 3_FFU _ISO_R
SMB_2_PLD _3V3AU X_SD A_R 2
SMB_1_PLD _3V3AU X_SC L_R 2
S CM_S Y S _P W RO K _RS G P IO _S CM_CLK _<0>
FM_BOAR D _BMC _SKU _ID 0
S G P IO _S CM_DO _<0>
FM_U V_AD R _TR IGGER _N
S G P IO _S CM_DI_R<1>
S MB _CP U0_4_X LTR_R_S DA
FM_S Y S _THRO TTLE _R_N
S MB _CP U0_4_X LTR_R_S CL
OC_A LE RT_N
UV _A LE RT_N
IR Q_H SC _FAU LT_BU F_R _N
P 3V 3_O CP _S FF_E N_R
IRQ _UV _DE TE CT_N
HS C_D_OC
S MB _CP U0_4_X LTR_S DA
S MB _CP U0_4_X LTR_S CL
FM_BOAR D _BMC _SKU _ID 2
FM_LE D_A CTIV E _E 1S _0
P 3V 3_O CP _S FF_E N
P 12V _O CP _S FF_E N_R P 12V _O CP _S FF_E N
S G P IO _S CM_DI_<1>
IR Q_H SC _FAU LT_BU F_N
E1S_0_PER ST1_C LKR EQ_R _N
OC P_V3_1_P3V3_PLD _R _PW R GD
O CP _V 3_2_MA IN_P W R_E N
S G P IO _O CP _S FF_CLK
S G P IO _O CP _S FF_DA TA O UT
S G P IO _O CP _S FF_DA TA IN
S G P IO _O CP _S FF_LD_N
P CIE _M2_S S D0_P RS NT_N
S G P IO _S CM_LD_<0>
0
P V DDCR_S O C_P 1_E N
R1179
R152
R6851
R6850
R419
R407
2 1R6117
2 1
R6116
2 1
R6094
21R4146
21R4145
2 1R6096
2 1R6095
2 1R51
R6029
R6031
2 1R56
2 1R210
2 1R211
2 1R63
R6030
2 1R163
2 1R170
2 1R171
2 1R166
2 1R164
2 1R50
2 1R169
2 1R165
2 1R49
2 1R167
2 1R58
2 1R172
2 1R168
2 1R23
2 1R6038
2 1R6039
2 1R70
2 1R493
2 1R992
2 1R160
21R439
B22
A21
C20
C19
B21
A20
G15
F15
B20
A19
D18
C18
B19
A18
D17
E16
B18
A17
D16
C17
B17
A16
D15
C15
B15
A15
F14
G14
D14
C14
B14
A14
D13
C13
B13
A13
F13
E13
F12
G12
A12
B12
E12
D12
D11
E11
A11
B11
F11
G11
A10
B10
E10
F10
G9
F9
A9
B9
D9
C9
A8
B8
D8
C8
D7
C6
A7
B6
E7
D6
A6
B5
C5
D5
A5
B4
G8
F8
A4
B3
C4
C3
A3
B2
F7
E6
A2
B1
E17
F16
E15
E14
C10
D10
E9
E8
U18
U18
3/7
BANK 0
PT43D
PT43C
PT42D
PT42C
PT42B
PT42A
PT41D
PT41C
PT40D
PT40C
PT40B
PT40A
PT39D
PT39C
PT39B
PT39A
PT38D
PT38C
PT38B
PT38A
PT30D
PT30C
PT30B
PT30A
PT29D
PT29C
PT29B
PT29A
PT28D
PT28C
PT27B
PT27A
PT24D
PT24C
PT24B
PT24A
PT23D
PT23C
PT21D
PT21C
PT21B
PT21A
PT20D
PT20C
PT20B
PT20A
PT14D
PT14C
PT14B
PT14A
PT13D
PT13C
PT13B
PT13A
PT12D
PT12C
PT12B
PT12A
PT10D
PT10C
PT10B
PT10A
PT11D
PT11C
PT22B
PT22A
PT11B
PT11A
PT15A
PT9A||L_GPLLT
PT9C
PT9B||L_GPLLC
PT9D
PT15B
PT23A||PCLKT0_1
PT23B||PCLKC0_1
PT44A||R_GPLLT
PT44B||R_GPLLC
PT27C||SCL||PCLKT0_0
PT27D||SDA||PCLKC0_0
PT28A
PT28B
PT31A
PT31B
PT41A
PT41B
PT43A||R_GPLLT
PT43B||R_GPLLC
4/7
BANK 0
PT31C||JTAGENB
PT44D||DONE
PT44C||INITN
PT31D||PROGRAMN
PT22D||TMS
PT22C||TCK
PT15D||TDI
PT15C||TDO
2 1
2 1
2 1
2 1
2 1
2 1
2 1
2 1
2 1
1
SHEETDATE
23
7 3 2 16 5 4
E
A
B
C
E
D
C
B
A
7 6 5 4
D
DEPARTMENT
SIZE
PROJECT DOCUMENT NUMBER REV
REVIEWER
DESIGNER
IN
OUT
IN
IN
BI
OUT
OUT
BI
IN
IN
IN
OUT
OUT
OUT
OUT
IN
OUT
IN
OUT
IN
IN
IN
OUT
OUT
OUT
IN
OUT
IN
IN
IN
OUT
IN
IN
IN
OUT
IN
OUT
OUT
OUT
IN
OUT
OUT
OUT
OUT
OUT
OUT
OUT
IN
OUT
IN
BI
IN
IN
OUT
IN
OUT
OUT
IN
OUT
OUT
IN
IN
OUT
IN
IN
IN
IN
IN
IN
IN
BI
OUT
IN
IN
IN
OUT
IN
OUT
OUT
OUT
OUT
IN
IN
IN
IN
IN
IN
OUT
OUT
OUT
OUT
IN
OUT
OUT
OUT
IN
OUT
C



BANK1 P1V8_AUX
BANK2 P3V3_AUX
TBC
Thu Aug 24 14:09:19 2023<NAME_2>
<NAME_1>
MB FABCGTI V02
81 OF 365
P 3V 3_A UX
363
256
256
256
242
85
85
83 140 141 248
83 140 141
142
138
128
127
127
134
217
164
123246
83193
207
152
129
200
200
210
83146147
8385
146147
188
365
192
19085270
127
83 144
127
127
28
55
55
55
363
365
321
321
5583
55
28
151
288
5555
354
354
277
277
288
332
2885
5585
28
167
558578
8354
27
129
130
125
125 246
125
125 246
125
126
126
126
126
126
126 246
126
125
83 145
343
8354
54
8329
173
287885
55
224
28
28
28 55
243
127
127
128
83 85
83 172
142
136
83 85
188
83146147
132
271255
124
124
124
124
124
150
217
28
257
210
128
185 186
184
55
167
207
343
8327
8327
28
83 153
167 28 165
29 150
166
29 150
29 150
55
172
29 150
29 150
29 76 150
151
188
260
166
310
77
167
77
167
174
173
83 29
299
28
174
84
310
34
172
153
29 150
167
172
362
129
226
192
130
130
224
224
226
167
361
167 27
55
299
270148255271
209
209
217
242
146147
28
28
2883
28255
5583
332
2883
256
127
P0V9_RETIMER_CPU0_EN
FM_LE D_P W RG D_P V DD33_S 5
FM_LE D_P W RG D_P V DD18_S 5_P 0
FM_LE D_P W RG D_P V DD11_S 3_P 0
H PD B_H SC _PW R GD _ISO
P 3V 3_E 1S _0_E N_R
H PD B_H SC _PW R GD _ISO_R
P 12V _E 1S _0_E N
B MC_FP G A _LE D1
P 0V 9_RE TIME R_CP U0_E N_R2
B MC_FP G A _LE D2
FM_P LD_O CP _S FF_P W R_G O O D_R
P 12V _E 1S _0_P W RG D
FM_GPU _H SC _EN _R
FM_P W RG D_P V DDIO _P 1
FM_P V DDIO _P 1_E N
FM_CP U0_P W R_G O O D
FM_P V DD33_S 5_E N
FM_FPGA_DEBUG_SW_SPARE
GPU _FPGA_R ST_N
FM_GPU _PW R _EN
P 12V _S CM_P W RG D_R
FM_P W RG D_P V DDCR_CP U0_P 1
GPU _FPGA_ER OT_R EC OV_R _N
FM_P W RG D_P V DDCR_CP U1_P 1
P RS NT_S W B _IS O _R_N
GPU _FPGA_ER OT_R ST_R _N
FM_P V DDCR_CP U0_P 1_R_E N
FM_P W RG D_P V DD11_S 3_P 0
33.2
0
0
0
0
0
0
0
0
0
0
0
0
0
0
0
100
0
0
33
33
33
33
33
33
33
33
33
33
33
33
33
33
33
33
33
33
33
33
33
33
33
33
33
33
33
33
33
33
33
33
33
33
33
33
33
33
33
33
33
33
E MP TY 0
0
0
0
0
0
0
0
0
0
0
0
0
0
0
0
0
0
0
0
0
0
0
0
0
0
33
33
0
0
0
0
0
0
0
0
0
0
0
33
33
33
CHIP
CHIP
CHIP1%
33.2
33.2
P U_S P I_P LD_CS _N
P3V3_OC P_V3_2_EN _R
P12V_OC P_V3_2_EN _R
FM_N C SI_OC P_V3_2_R _OE
GPU _FPGA_BOOT_EN
P 0V 9_RE TIME R_CP U1_E N_R2
FM_SMB_2_ALER T_GPU _ISO_N
GPU _FPGA_R EAD Y_ISO
HP_LVC3_OCP_SFF_PRSNT2_PLD_N
P W RG D_P V DDCR_CP U1_P 1
UART_LS_EN
PRSNT_SWB_ISO_N
P V DDCR_CP U0_P 0_P MA LE RT
P W RG D_P V DD11_S 3_P 0
H P_LVC 3_SC M_H SC _PW R GD
GPU _FPGA_ER OT_R ST_N
P V DDIO _P 0_E N
P W RG D_P V DDIO _P 0
P V DDCR_CP U0_P 1_E N
1%
1%
GPU _BASE_STBY_EN _R
E 1S _0_P 3V 3_E N
RS T_P E RS T_CP U1_S W B _1_N
P 3V 3_E 1S _P W RG D_0_R
FM_SMB_2_ALER T_GPU _ISO_R _N
FM_P 5V _E N
33.2
1%
33.2
33.2
GPU _FPGA_ER OT_FATALER R _ISO_R _N
GPU _3V3IO_R SVD 1_FFU _ISO_R
GPU _3V3IO_R SVD 0_FFU _ISO_R
33.2
33.2
1%
1%
1%
CHIP
CHIP
CHIP
CHIP
CHIP
CHIP
CHIP
CHIP
CHIP
P0V9_R ETIMER _C PU 1_EN
PR SN T_C ABLE_GPU _A2_ISO_R _N
P V DD33_S 5_E N
PWRGD_P3V3_AUX
FM_SW B_PW R GD _ISO
RS T_P E RS T_M2_0_N
FM_SMB_1_ALER T_GPU _ISO_N
FM_SW B_BIC _R EAD Y_ISO_N
FM_UART_LS_EN
CHIP
1%
P V DD18_S 5_P 1_R_E N
FM_P W RG D_P V DD11_S 3_P 1
FM_P V DD11_S 3_P 1_E N
GPU _3V3IO_R SVD 5_FFU _ISO_R
PR SN T_C ABLE_GPU _A1_ISO_R _N
33.2
33.2
33.2
33.2
33.2
33.2
33.2
33.2
33.2
P W RG D_P 0V 9_RE TIME R_CP U1_R2
FM_CP U0_RS MRS T_N
FM_CP U1_RS MRS T_N
RS T_CP U1_P E RS T0_R_N
P W RG D_P 0V 9_RE TIME R_CP U0_R2
RST_RT_CPU1_P0_RESET_R2_N
RS T_RT_CP U1_P 0_P E RS T_R2_N
TP _S LO T1_CLK RE Q _0_R_N
RS T_CP U0_S Y S _N
RS T_CP U1_S Y S _N
FM_CP U1_S LP _S 5_N
FM_CP U1_S LP _S 3_N
PW R GD _P0V9_R ETIMER _C PU 0
PW R GD _P0V9_R ETIMER _C PU 1
RST_RT_CPU1_P0_PERST_R_N
RST_RT_CPU1_P0_RESET_R_N
RS T_CP U1_P E RS T0_N
RS T_CP U1_RS MRS T_N
CP U0_NV _S A V E _N
RS T_CP U0_P E RS T1_R_N
RS T_CP U1_P E RS T1_R_N
RS T_CP U0_P E RS T0_R_N
LCMX O 3LF-9400C-5B G 484C
P 12V _A LL_P W RO K _R
CP U0_S P D_HO S T_CTRL_R1_N
FM_ROM_LS_EN
33
RS T_RT_CP U0_P 1_RE S E T_R2_N
RS T_RT_CP U1_P 3_P E RS T_R2_N
S MB _CP U_5_R1_S CL
R ST_R T_C PU 0_P1_R ESET_R _N
RS T_RT_CP U1_P 3_RE S E T_R2_N
RS T_S MB _RT_RO M_R2_N
TP _FM_CLK _B UFFE R_E N_R
CPU1_PWRGD_OUTCP U1_S P D_HO S T_CTRL_N
R ST_R T_C PU 1_P3_PER ST_R _N
R ST_R T_C PU 1_P3_R ESET_R _N
R ST_R T_C PU 0_P0_PER ST_R _N
R ST_R T_C PU 0_P0_R ESET_R _N
R ST_R T_C PU 0_P1_PER ST_R _N
FM_P 0_P CC0_R_N
FM_P 0_P CC1_R_N
RS T_RT_CP U1_P 2_RE S E T_R2_N
R ST_R T_C PU 1_P1_R ESET_R _N
RS T_CP U0_RE S E TL_N
RS T_CP U1_RE S E TL_N
33
CP U0_NMI_S Y NC_FLO O D_N
FP G A _DE B UG _LE D_CTRL
P W RG D_CP U1_P W RO K
FM_P 1_P CC1_N
A P ML_CP U0_A LE RT_R_N
GPU _N VS_PW R _BR AKE_N
BMC _MON ITER _R
GPU _BASE_H MC _R EAD Y_ISO_R
GPU _FPGA_TH ER M_OVER T_ISO_R _N
1%
SW B_H SC _PW R GD _ISO
PR SN T_C ABLE_GPU _A1_ISO_N
GPU _3V3IO_R SVD 5_FFU _ISO
PR SN T_C ABLE_GPU _A2_ISO_N
GPU _3V3IO_R SVD 1_FFU _ISO
GPU _FPGA_OVER T_ISO_R _N
1%
CHIP1%
CHIP
CHIP1%
GPU _FPGA_TH ER M_OVER T_ISO_N
GPU _BASE_H MC _R EAD Y_ISO
GPU _H MC _PR SN T_ISO_N
GPU _FPGA_OVER T_ISO_N
GPU _W P_H W _C TR L_N
GPU _PR SN T_N _ISO
GPU _FPGA_ER OT_FATALER R _ISO_N
CHIP1%
1%33.2
33.2
SW B_H SC _PW R GD _ISO_R
1%
33.2
GPU _3V3IO_R SVD 0_FFU _ISO
RST_PERST_E1S_0_N
1%
33.2
CHIP
CHIP
1%
33.2
1%
R ST_R T_C PU 1_P2_PER ST_R _N
TP _S LO T2_CLK RE Q _0_R_N
FM_P 1_P CC0_N
A P ML_CP U1_A LE RT_R_N
FM_FP G A _DE B UG _LE D_CTRL
RS T_CP U0_K B RS T_R_N
CPU0_JTAG_BUF_OE
P W RG D_CP U0_P W RO K
CP U1_NV _S A V E _N
P V DD11_S 3_P 1_RE S E T_N
CP U0_P W R_B TN_N
RS T_CP U0_K B RS T_N
FM_P 1_P CC1_R_N
CP U0_FO RCE _S E LFRE FRE S H
CPU1_PWR_GD_IN
FM_AC _PW R _BTN _PLD _ISO_N
0402LF
1%
R ST_BMC _FR OM_SW B_ISO_N
BIC _MON ITER _ISO
GPU _BASE_STBY_EN
SW B_H SC _EN _R
R ST_PER ST_C PU 0_SW B_N
1%
P RS NT_HDT_N
R ST_PER ST_OC P_V3_2_N
R ST_PER ST_OC P_SFF_N
FM_GPU _PW R GD _ISO_R
RST_PERST_M2_0_R_N
R ST_PER ST_C PU 1_SW B_N
GPU _3V3IO_R SVD 4_ISO_R
GPU _H MC _PR SN T_ISO_R _N
R ST_BMC _FR OM_SW B_ISO_R _N
FM_SMB_1_ALER T_GPU _ISO_R _N
FM_SW B_BIC _R EAD Y_ISO_R _N
BIC _MON ITER _ISO_R
GPU _PR SN T_N _ISO_R
FM_RS T_P E RS T_S CM_R_N
33.2
1%
SW_P3V3_EN
CHIP
E 1S _0_P 12V _E N
FM_NCS I_O CP _S FF_R_O E
P W RG D_P 1V 2_A UX _R
33.2
33.2
1%33.2
1%
1%
CHIP
CHIP
1%
33.2
1%
1%
FPGA 2/6
IC
SMLF
1%
33.2
33.2
1%
33.2
10K
1%
CHIP
1/16W
1%
33.2
33.2
FM_CPU1_PWR_GD_IN
SW B_H SC _EN
CHIP
GPU _3V3IO_R SVD 4_ISO
GPU _3V3IO_R SVD 3_ISO
GPU _3V3IO_R SVD 1_ISO
H GX_D ETEC T_N
FM_RST_PERST_SCM_N
1%
CHIP
CHIP
CHIP
1%
P V DDIO _P 1_E N
CP U0_P W R_G O O D
GPU _FPGA_BOOT_EN _R
FM_SW B_PW R GD _ISO_R
H GX_D ETEC T_N _R
GPU _FPGA_R EAD Y_ISO_R
IC
SMLF
FM_LE D_P W RG D_P V DDCR_CP U0_P 1
1%
CHIP
1%
33.2
CHIP
GPU _N VS_PW R _BR AKE_R _N
CHIP
1%
P W RG D_P V DDCR_CP U0_P 1
FM_SW B_PW R _EN _R
FM_P V DDIO _P 0_E N
33.2 FM_SW B_PW R _EN
R ST_SMB_R T_R OM_R 1_N
R ST_SMB_R T_R 1_N
CP U1_FO RCE _S E LFRE FRE S H
FM_FO RCE _A LL_P W RO N
P V DD11_S 3_P 0_RE S E T_N
RS T_RT_CP U1_P 2_P E RS T_R2_N
R ST_R T_C PU 1_P2_R ESET_R _N
FM_P 0_P CC1_N
FM_P 0_P CC0_N
33
33
FM_S ME RR_LE D_R_N
FM_CP U0_S ME RR_N CP U0_S ME RR_N
FM_ESPI_C PU 0_ALER T_R _SEL
B IO S _DE B UG _MO DE
ESPI_CPU0_D0
RST_ESPI_CPU0_RSTOUT_R_N
FM_S ME RR_LE D_N
B IO S _DE B UG _MO DE _R
ESPI_CPU0_R1_D1
RST_ESPI_CPU0_RSTOUT_N
ESPI_CPU0_D1
FM_P LD_CP U1_P RS NT_HDT
CP U1_JTA G _B UF_R_O E
B MC_JTA G _S E L_R
S CM_IRQ _1V 8_R_N
S CM_US B _O C_R_N
CP U1_NMI_S Y NC_FLO O D_N
HDT_HDR_P W RO K
ESPI_CPU0_D3
ESPI_CPU0_D2
CLK_ESPI_CPU0_CLK1
S MB _CP U_5_R1_S DA
P W RG D_P 3V 3_R2
FM_CP U1_S ME RR_N
ESPI_CPU0_ALERT_R_N
ESPI_CPU0_R1_D0
ESPI_CPU0_R1_D2
ESPI_CPU0_R1_D3
FM_HDT_HDR_P W RO K
RS T_RT_CP U0_P 1_P E RS T_R2_N
RS T_RT_CP U0_P 0_RE S E T_R2_N
RS T_RT_CP U0_P 0_P E RS T_R2_N
CP U1_S P D_HO S T_CTRL_R1_N
ESPI_CPU0_CS1_R_N
P W RG D_P 12V _ME M_R
P 12V _A LL_P W RO K
R ST_R T_C PU 0_P3_PER ST_R _N
ROM_LS_EN
B MC_JTA G _S E L
ROM_SD_LS_OE
FM_S P D_CP U0_S W ITCH_CTRL_N
CP U0_HDT_B Y P A S S _S E L
CP U1_JTA G _B UF_O E
S CM_US B _O C_N
R ST_R T_C PU 0_P2_R ESET_R _N
CP U0_S P D_HO S T_CTRL_N
CP U1_HDT_B Y P A S S _S E L
S CM_IRQ _1V 8_N
R ST_R T_C PU 0_P3_R ESET_R _N
FM_B IO S _P O S T_CMP LT_B UF_N
HDT_HDR_RE S E T_N
ESPI_CPU0_ALERT_PLD_N
ESPI_CPU0_CS1_N
FM_JTAG_BMC _R _OE
CP U0_HDT_CO NN_TE S TE N
FM_JTA G _B MC_O E
CLK_ESPI_CPU0_R1_CLK1
FM_RS T_CP U0_RE S E TL_N
RS T_RT_CP U1_P 1_RE S E T_R2_N
RS T_RT_CP U1_P 1_P E RS T_R2_N
FM_CP U0_NV _S A V E _N
FM_CP U1_S Y S _RE S E T_N
FM_RS T_CP U1_RE S E TL_N
CPU0_JTAG_BUF_R_OE
FM_P W RG D_CP U0_P W RO K
FM_CP U1_NV _S A V E _N
FM_CP U0_NMI_S Y NC_FLO O D_N
FM_P W RG D_CP U1_P W RO K
FM_P 1_P CC0_R_N
FM_CP U0_P W R_B TN_N
FM_ROM_SD_LS_OE
RS T_RT_CP U0_P 3_RE S E T_R2_N
FM_S P D_CP U0_S W ITCH_CTRL_R_N
FM_P LD_CP U0_P RS NT_HDT
FM_CPU1_PWRGD_OUT
FM_CP U0_FO RCE _S E LFRE FRE S H
FM_FO RCE _A LL_P W RO N_R
RS T_S MB _RT_R2_N
RS T_P E RS T_E 1S _0_R_N
LCMX O 3LF-9400C-5B G 484C
GPU _3V3IO_R SVD 3_ISO_R
GPU _3V3IO_R SVD 1_ISO_R
CHIP
CHIP
GPU _W P_H W _C TR L_R _N
FM_P V DD18_S 5_P 0_E N
CHIP
33.2
CHIP
BMC _MON ITER
33.2
FM_P W RG D_P 1V 8_RE TIME R_CP U1
GPU _FPGA_ER OT_R EC OV_N
P W RG D_P V DD18_S 5_R_P 1
FM_P W RG D_P V DD33_S 5
FM_GPU _PW R _EN _R
GPU _FPGA_R ST_R _N
P V DD11_S 3_P 1_E N
P W RG D_P V DD11_S 3_P 1
P V DD18_S 5_P 1_E N
FPGA_DEBUG_SW_SPARE
FM_P W RG D_P 1V 8_RE TIME R_CP U0
FM_CP U1_FO RCE _S E LFRE FRE S H
RS T_RT_CP U0_P 3_P E RS T_R2_N
FM_B IO S _US B _RE CO V E RY
FM_B IO S _P O S T_CMP LT_B UF_R_N
FM_HDT_HDR_RE S E T_N
FM_E S P I_CP U0_A LE RT_S E L
CP U1_S ME RR_N
R ST_R T_C PU 0_P2_PER ST_R _NRST_RT_CPU0_P2_PERST_R2_N
FM_CP U0_HDT_CO NN_TE S TE N
TP _P W RG D_P 12V _FA N_DR_R
33
FM_CP U1_NMI_S Y NC_FLO O D_N
RS T_RT_CP U0_P 2_RE S E T_R2_N
FM_P W RG D_P V DDIO _P 0
1%
1%
CHIP
CHIP
P RS NT_O CP _S FF_N
P W RG D_P 1V 8_A UX _R
FM_P W RG D_P V DD18_S 5_P 0
P V DD18_S 5_P 0_E N
P W RG D_P V DDIO _P 1
FM_GPU _H SC _EN
HP_LVC3_E1S_0_HSC_PWRGD
33.2
33.2
FM_CP U0_S LP _S 5_N
FM_CP U0_S LP _S 3_N
RS T_CP U0_P E RS T0_N
RS T_CP U0_RS MRS T_N
RS T_CP U1_P E RS T1_N
FM_CP U0_S Y S _RE S E T_N
R ST_R T_C PU 1_P1_PER ST_R _N
RS T_CP U0_P E RS T1_N
1%
P W RG D_P 3V 3_A UX _R
CHIP
FM_LE D_P W RG D_P V DDIO _P 0
FM_GPU _PW R GD _ISOCHIP
1
R6855
R6854
R6853
R6852
R6826
R6825
R6824
R6823
R6807
R6806
R6805
R6804
R6799
R6798
R6793
R6792
R6781
R6777
R6741
R6740
R6711
R6710
R8032
R8021
R8000
R2939
21 R195
R4557
R4608
R2262
R2845
R3483
R3478
R3477
R2261
21 R933
21 R250
21 R193
21 R1203
21 R258
R1556
R1557
21 R685
21 R254
21 R229
21 R230
21 R198
21 R255
21 R197
21 R273
21 R217
21 R216
21 R253
21 R272
21 R241
21 R57
21 R463
21 R159
21 R242
21 R196
21 R219
21 R371
21 R203
21 R1278
21 R215
21 R1279
21 R1280
21 R1281
21 R194
21 R228
21 R208
21 R6046
R1563
21 R286
21 R209
21 R6055
21 R280
21 R279
21 R289
21 R1282
21 R6048
21 R648
21 R199
21 R1553
2 R1549
R1558
21 R1550
21 R1552
21 R1551
21 R708
21 R856
21 R937
21 R277
21 R588
21 R173
21 R251
21 R161
21 R174
21 R372
21 R1359
R1616
R1564
21 R395
21 R158
21 R957
21 R186
R252
21 R1202
21 R265
21 R798
21 R224
21 R5099
21 R6047
21 R176
21 R218
21 R282
21 R283
21
21
R6085
21
21
21
21
21
21
21
PR30D
PR30C
PR28D
PR28C
PR28B
PR28A
PR27D
PR27C
PR27B
PR27A
PR26D
PR26C
PR26B
PR26A
PR25D
PR25C
PR24D
PR24C
PR24B
PR24A
PR21D
PR21C
PR21B
PR21A
PR20D
PR20C
PR19D
PR19C
PR18D
PR18C
PR18B
PR18A
PR17D
PR17C
PR16D
PR16C
PR14D
PR14C
PR13D
PR13C
PR13B
PR13A
PR12D
PR12C
PR12B
PR12A
PR11D
PR11C
PR11B
PR11A
PR10D
PR10C
PR10B
PR10A
PR7D
PR7C
PR6D
PR6C
PR6B
PR6A
PR5D
PR5C
PR5B
PR5A
PR4B
PR4A
PR4D
PR4C
PR3D
PR3C
PR2D
PR2C
PR2A ||R_GPLLT_FB
PR2B||R_GPLLC_FB
PR3A ||R_GPLLT_IN
PR3B||R_GPLLC_IN
PR7A
PR7B
PR14A
PR14B
PR16A
PR16B
PR17A ||PCLKT1_0
PR17B||PCLKC1_0
PR19A
PR19B
PR20A
PR20B
PR25A
PR25B
PR29A
PR29C
PR29B
PR29D
PR30A
PR30B
Y20
W19
W20
V18
V19
U17
Y21
AA22
U18
U19
W21
Y22
U20
T17
T18
T19
T20
R16
R17
R18
R19
R20
W22
V22
U21
U22
P16
P17
P18
P19
T21
T22
P20
P22
R21
R22
N19
N20
P21
N22
N18
N17
N16
M16
M19
M20
M21
M22
M17
L22
L21
K22
L20
L19
L16
L17
K16
K17
K18
K19
K20
J20
J22
J21
J19
J18
J17
J16
H16
H17
H18
H19
H20
G17
H21
H22
G18
G19
G20
G21
F19
F18
G22
F22
E20
E19
E21
E22
D20
D19
D21
D22
G16
F17
C22
C21
T16
V17
AA21
AB21
W18
Y19
AA20
AB20
U16
T15
AA19
AB19
W17
Y18
AA18
AB18
V16
Y17
AA17
AB17
U15
V15
AA16
AB16
W15
Y15
AA15
AB15
W14
Y14
AA14
AB14
V14
U14
T14
T13
W13
Y13
AA13
AB13
U13
V13
AA12
AB12
V12
U12
T12
Y12
Y11
V11
AB11
AA11
U11
T11
AB10
AA10
Y10
Y9
W10
V10
U10
T10
AB9
AA9
W9
Y8
AB8
AA8
W8
V9
U9
T9
U8
V8
AB7
AA7
V7
W6
AB6
AA6
Y6
Y5
AB5
AA5
T8
U7
AB4
AA4
W5
Y4
AB3
AA3
U6
V6
AB2
AA2
U18
U18
7/7
BANK 1
2/7
BANK 2
PB21D
PB21C
PB46D
PB46C
PB44D
PB44C
PB43D
PB43C
PB41D
PB41C
PB41B
PB41A
PB40D
PB40C
PB40B
PB40A
PB38D
PB38C
PB38B
PB38A
PB35D
PB35C
PB32D
PB32C
PB32B
PB32A
PB33D
PB33C
PB30D
PB30C
PB29D
PB29C
PB27D
PB27C
PB27B
PB27A
PB22D
PB22C
PB19D
PB19C
PB19B
PB19A
PB18D
PB18C
PB16D
PB16C
PB13B
PB13A
PB11D
PB11C
PB11B
PB11A
PB35B
PB35A
PB46B||SI||SISPI
PB46A||SN
PB44B
PB44A
PB43B
PB43A
PB33B
PB33A
PB30B
PB30A
PB29B||PCLKC2_1
PB29A||PCLKT2_1
PB24D
PB24C
PB24B
PB24A
PB22B||PCLKC2_0
PB22A||PCLKT2_0
PB21B
PB21A
PB18B
PB18A
PB16B||SO||SPISO
PB16A||MCLK||CCLK
PB13D
PB13C
PB10D
PB10C
PB10B
PB10A
PB8B
PB8A
PB8D
PB8C
PB7D
PB7C
PB7B
PB7A||CSSPIN
PB5D
PB5C
PB5B
PB5A
21
21
21
21
21
21
21
21
21
21
21
21
21
21
21
21
21
21
21
21
21
21
21
21
21
2
1
21R3479
21R3482
21R3324
21R11667
21R2664
21R2663
21R3066
21R2847
21R2844
21R2846
21R3505
21R3486
21R3485
21R3484
21R3481
21R3476
21R3480
21R4157
21R4563
21R4148
21R4147
21R4144
21R4143
21R4558
21R4556
21R4172
21R4171
21R4170
21
21
21
21
21
21
21
1
SHEETDATE
23
7 3 2 16 5 4
E
A
B
C
E
D
C
B
A
7 6 5 4
D
DEPARTMENT
SIZE
PROJECT DOCUMENT NUMBER REV
REVIEWER
DESIGNER
IN
IN
IN
IN
IN
IN
IN
OUT
OUT
OUT
IN
IN
OUT
BI
BI
OUT
OUT
IN
BI
OUT
OUT
OUT
BI
IN
OUT
OUT
OUT
OUT
OUT
IN
IN
IN
IN
OUT
OUT
OUT
IN
IN
IN
OUT
IN
IN
OUT
IN
IN
IN
IN
IN
OUT
OUT
IN
IN
IN
IN
OUT
OUT
OUT
OUT
OUT
OUT
OUT
OUT
OUT
OUT
OUT
OUT
OUT
OUT
OUT
OUT
OUT
OUT
IN
OUT
OUT
IN
OUT
IN
OUT
OUT
OUT
OUT
OUT
OUT
OUT
IN
OUT
OUT
OUT
OUT
OUT
OUT
OUT
OUT
OUT
IN
IN
IN
IN
IN
IN
IN
IN
IN
OUT
IN
IN
IN
IN
IN
IN
IN
IN
IN
OUT
IN
OUT
IN
OUT
IN
IN
IN
IN
OUT
OUT
IN
IN
BI
IN
OUT
IN
IN
OUT
IN
IN
IN
IN
BI
OUT
OUT
BI
BI
BI
OUT
OUT
IN
IN
OUT
OUT
IN
OUT
OUT
OUT
OUT
OUT
IN
OUT
OUT
IN
OUT
OUT
IN
OUT
OUT
OUT
IN
OUT
OUT
OUT
OUT
OUT
IN
OUT
IN
OUT
IN
IN
OUT
OUT
IN
IN
IN
OUT
OUT
OUT
IN
C



TBC
BANK3 P3V3_AUX
BANK5 P1V8_AUX
TBC
BANK4 P3V3_AUX
Thu Aug 24 14:09:25 2023<NAME_2>
<NAME_1>
MB FABCGTI V02
82 OF 365
P 3V 3_A UX
P 3V 3_A UX
P 3V 3_A UX
P 1V 8_A UX
P 1V 8_A UX
28
2754
55
27172
27
28
28
28
193
55
27172
55
55
200
200
256
54
27
268
27
54
217
27
83217
83200
237 358
256
136
193
193
92
207
86
256
217
83 145 80
98
54
27
84
167
54
83161
83161
54
249
27
84
83 224
2754
27
54
2754
2754
27172
54
224
27 54
84
193
54
27
27
207
27
210
28
359
359
200
54
54
241
104
83 210
167
85
83161
85
150152
85
268
237358
83161
238
83207 238
136
27
27
85
187
131 132
131
238 358
144
0
0
0
0
0
0
0
0
0
0
0
0
0
0
0
0
0
0
0
0
0
0
0
0
0
0
0
0
0
0
0
0
0
0
0
0
0
0
0
0
0
0
0
0
0
33
33
33
33
33
33
33
33
33
33
33
33
33
0
0
0
0
0
0
IR Q_BMC _SMI_N
CP U1_X TRIG _L7
IR Q_C PU _BMC _N MI_N
CP U0_X TRIG _L5
CP U0_X TRIG _L4
IR Q_SMI_AC TIVE_N
IR Q_TPM_SPI_R _N
FM_SMM_C R ASH D U MP
FM_CP U1_B MC_RS T_R_N
P V DDCR_CP U0_P 0_O CP _N
FM_BMC _TPM_PR ES_N
FM_BMC _R EAD Y_R _N
FM_CP U0_X TRIG _L7CP U0_X TRIG _L7
FM_BMC _R EAD Y_N
FM_CP U1_B MC_RS T_N
P V DDCR_CP U1_P 0_O CP _N
FM_P V DDCR_CP U1_P 0_E N
FM_LE D_P W RG D_P V DDCR_CP U1_P 0
CP U1_S P 5R2
CP U0_CO RE TY P E 1
P12V_HSC_TEMP_ALERT_R_N
CP U0_S P 5R2
CP U1_CO RE TY P E 0
IR Q_TPM_SPI_R 1_N
IR Q_SMI_AC TIVE_N _R
FM_CP U0_X TRIG _L4
FM_CP U0_X TRIG _L5
IR Q_C PU _BMC _N MI_R _N
FM_CP U1_X TRIG _L7
P V DDCR_CP U1_P 1_O CP _N
CP U0_S P 5R1
FM_S E C_MUX _R_S E L
FM_S E C_MUX _O E _R_N
P V DDCR_CP U1_P 1_S MB _A LE RT
P V DDCR_CP U1_P 0_S MB _A LE RT
OCP_SFF_P3V3_P12V_ADC_R_ALERT
FM_LED_PWRGD_PVDDCR_SOC_P0
P12V_OCP_V3_1_PLD_PWRGD
P W RG D_P V DDCR_S O C_P 0
P V DDCR_S O C_P 0_E N
OC P_SFF_P3V3_P12V_AD C _ALER T
P W RG D_CHG L_CP U0_R2
P V DD11_S 3_P 0_E N
FM_P V DDCR_CP U1_P 1_R_E N
P W RG D_CHA F_CP U0_R2
FM_LED_PWRGD_PVDDCR_CPU0_P0
P 12V _O CP _V 3_1_P W RG D
FM_P V DDCR_CP U1_P 1_E N
E 1S _0_P RS NT_R_N
FM_CP U0_S P 5R4
FM_P RS NT_CP U0_R_N
FM_P RS NT_CP U1_R_N
E 1S _0_P RS NT_N
FM_CP U0_X TRIG _L6
IR Q_BMC _SMI_R _N
FM_SMM_C R ASH D U MP_R
FM_P V DDCR_CP U0_P 0_O CP _N
FM_P V DDCR_CP U1_P 0_O CP _N
FM_CP U0_S P 5R3
FM_P W RG D_P V DDCR_CP U1_P 0
FM_BMC _TPM_PR ES_N _R
FM_CP U1_X TRIG _L6
P W RG D_CHA F_CP U1_R2
CP U1_CO RE TY P E 2
CP U0_S P 5R3
FA B _B MC_RE V _ID1
FM_P RS NT_CP U1_N
FM_CP U1_S A 1
FM_CP U1_CO RE TY P E 0
FM_P V DDCR_CP U1_P 0_R_E N
FM_A P ML_MUX 2_O E _R_N
FM_CP U0_CO RE TY P E 1
FM_CP U1_CO RE TY P E 1CP U1_CO RE TY P E 1
FM_A P ML_MUX 2_S E L
FM_A P ML_MUX 2_O E _N
FM_CP U0_S P 5R1
FM_CP U0_S P 5R2
FM_CP U1_S P 5R1
FM_A P ML_MUX 2_S E L_R
FM_CP U1_CO RE TY P E 2
CP U1_S P 5R1
FM_CP U1_S P 5R2
LCMX O 3LF-9400C-5B G 484C
S MB _B MC_G P U_E N
CP U0_S A 1
FA B _B MC_RE V _ID0
SMLF
LCMX O 3LF-9400C-5B G 484C
P V DD11_S 3_P 1_P MA LE RT
IC
FM_CP U1_X TRIG _L5
FM_CP U1_X TRIG _L4CP U1_X TRIG _L4
CP U0_S P 5R4
CP U1_S A 1
CP U1_X TRIG _L5
CP U1_X TRIG _L6
CP U0_X TRIG _L6
LCMX O 3LF-9400C-5B G 484C
SMLF
IC
IC
SMLF
FPGA 3/6
CP U1_P RO CHO T_N
P V DD11_S 3_P 1_O CP _N
FM_CP U0_CO RE TY P E 0
FM_CP U0_S A 0
FM_CP U0_S A 1
FM_CP U1_P RO CHO T_R_N
FM_P V DD11_S 3_P 1_O CP _N
FM_P V DD11_S 3_P 0_O CP _N
FM_CP U1_S A 0
CP U1_THE RMTRIP _R_N
FM_P V DDCR_CP U0_P 1_O CP _N
FA B _B MC_RE V _ID2
FM_CP U0_P RO CHO T_R_N
FM_CP U1_S P 5R4 FM_P V DD11_S 3_P 0_E N
P W RG D_P V DDCR_CP U0_P 0
FM_INT_CP U0_HP _UB M_R_N
CP U1_S A 0
CP U0_S A 0
CP U0_P RO CHO T_N
P V DD11_S 3_P 0_O CP _N
CP U0_THE RMTRIP _R_N
P V DDCR_CP U0_P 1_O CP _N
FM_INT_CP U0_HP _UB M_N
RT_B O A RD_ID_ID1
RT_B O A RD_ID_ID0
P W RG D_P V DDCR_CP U1_P 0
CP U1_S P 5R3
CP U1_S P 5R4
FM_PD B_BU F_EN _R _N
P W RG D_CHG L_CP U1_R2
FM_P V DDCR_CP U1_P 1_O CP _N
FM_CP U1_S P 5R3
FM_PD B_BU F_EN _N
FM_CLK RE Q _M2_1_N
FM_P LD_O CP _S FF_A UX _P W R_R_E N
P V DDCR_CP U0_P 1_P MA LE RT
FM_P RS NT_CP U0_N
PW R GD _P5V_AU X_R 3
FM_S E C_MUX _O E _N
E1S_0_P3V3_P12V_ADC_ALERT
LE D_HDD_A CTIV ITY _B _P LD_N
FM_S CM_P RS NT1_N
FM_THE RMA L_A LE RT_R_N
P 12V _HS C_T_CRIT_R_N
E1S_0_P3V3_P12V_AD C _R _ALER T
FM_S E C_MUX _S E L
P 12V _S CM_A DC_A LE RT
P V DD11_S 3_P 0_P MA LE RT M2_0_P3V3_AD C _ALER T
FM_PLD _OC P_SFF_AU X_PW R _EN
OCP_V3_2_P3V3_P12V_ADC_ALERT
FM_CLR_CMO S
FM_CP U0_CO RE TY P E 2
FM_PLD_OCP_SFF_MAIN_PW R_EN_R
CP U0_CO RE TY P E 2
CP U0_CO RE TY P E 0
P W RG D_O CP _S FF_P W R_G O O D
FM_S MB _RS T_E 1S _0_N
CLR_CMOS
FM_OC P_SFF_PW R _GOOD
OC P_SFF_MAIN _PW R _EN
OC P_V3_2_P3V3_P12V_AD C _R _ALER T
M2_SSD 0_C LKR EQ_EN _N
R1339
R1329
R1340
R132
R6184
R6183
21 R6073
21 R284
21 R278
21 R270
21 R226
21 R179
21 R220
21 R266
21 R221
21 R81
21 R285
21 R271
2 1R958
2 1R6053
2 1R275
2 1R6054
21 R205
21 R227
21 R6051
21 R182
21 R223
21 R6052
2 1R183
2 1R959
2 1R185
21 R204
21 R234
21 R267
21 R244
21 R238
21 R235
21 R237
21 R187
21 R245
21 R236
21 R246
21 R190
21 R243
21 R239
21 R188
21 R231
21 R137
21 R189
21 R141
21 R269
21 R268
21 R233
21 R264
21 R222
21 R232
21 R261
21 R260
21 R184
21 R263
21 R181
21 R180
21 R262
R133
K8
J8
F3
M3
M8
L8
V3
P8
N8
W16
W11
W7
R14
R13
R12
R11
R10
R9
V20
P15
N15
M18
M15
L15
K15
J15
F20
H14
H12
H11
H9
G13
G10
C16
C12
C7
N13
N12
N11
N10
M12
M11
L12
L11
K13
K12
K11
K10
AB22
AB1
Y16
Y7
W12
V21
V2
R15
R8
P14
P13
P12
P11
P10
P9
N21
N14
N9
M14
M13
M10
M9
M4
L18
L14
L13
L10
L9
L2
K21
K14
K9
J14
J13
J12
J11
J10
J9
H15
H13
H10
H8
F21
F2
E18
E5
C11
C2
B16
B7
A22
A1
T7
V5
W4
Y3
Y2
W3
AA1
Y1
U5
V4
W2
W1
U4
U3
V1
U2
T6
T5
T4
T3
R7
R6
U1
T2
P7
R5
R4
R3
P6
P5
T1
R2
N7
N6
N5
P4
M7
P3
R1
P2
N4
N3
P1
N2
M5
M6
N1
M1
L4
L3
M2
L1
L5
L6
K1
K2
K3
K4
K5
L7
K6
K7
J1
J2
J3
J4
J5
H5
J6
J7
H1
H2
H3
H4
G1
G2
G4
G3
F1
E1
F4
E3
E2
D1
H6
G5
D2
C1
H7
G6
F5
E4
G7
F6
D4
D3
U18
U18
U18
1/7
BANK 5
BANK 4
BANK 3
PL12D
PL12C
PL12B
PL12A
PL11D
PL11C
PL11B
PL11A
PL10D
PL10C
PL10B
PL10A
PL7D
PL7C
PL7B||PCLKC5_0
PL7A||PCLKT5_0
PL30D
PL30C
PL30B
PL30A
PL29D
PL29C
PL29B
PL29A
PL28D
PL28C
PL28B
PL28A
PL27D
PL27C
PL27B||PCLKC3_0
PL27A||PCLKT3_0
PL19D
PL19C
PL19B
PL19A
PL18D
PL18C
PL18B
PL18A
PL17D
PL17C
PL17B
PL17A
PL26B
PL26A
PL25D
PL25C
PL24D
PL24C
PL24B
PL24A
PL25B
PL25A
PL6B
PL6A
PL6D
PL6C
PL16D
PL16C
PL14D
PL14C
PL26D
PL26C
PL21D
PL21C
PL21B
PL21A
PL20D
PL20C
PL20B
PL20A
PL16B||PCLKC4_0
PL16A||PCLKT4_0
PL14B
PL14A
PL13D
PL13C
PL13B
PL13A
PL5D
PL5C
PL5B
PL5A
PL4D
PL4C
PL4B||L_GPLLC_IN
PL4A||L_GPLLT_IN
PL3D
PL3C
PL3B||L_GPLLC_FB
PL3A||L_GPLLT_FB
PL2D
PL2C
PL2B
PL2A
5/7
VCCIO0_5
VCCIO0_6
VCCIO0_9
VCCIO0_8
VCCIO0_7
VCCIO0_4
VCCIO0_3
VCCIO0_2
VCCIO0_1
VCCIO1_9
VCCIO1_8
VCCIO1_7
VCCIO1_6
VCCIO1_5
VCCIO1_4
VCCIO1_3
VCCIO1_2
VCCIO1_1
VCCIO2_9
VCCIO2_8
VCCIO2_7
VCCIO2_6
VCCIO2_5
VCCIO2_4
VCCIO2_3
VCCIO2_2
VCCIO2_1
VCCIO3_3
VCCIO3_2
VCCIO3_1
VCCIO4_3
VCCIO4_2
VCCIO4_1
VCCIO5_3
VCCIO5_2
VCCIO5_1
VCC12
VCC11
VCC10
VCC9
VCC8
VCC7
VCC6
VCC5
VCC4
VCC3
VCC2
VCC1
6/7
GND52
GND51
GND49
GND50
GND48
GND47
GND46
GND45
GND44
GND43
GND42
GND41
GND40
GND39
GND38
GND37
GND36
GND35
GND34
GND33
GND32
GND31
GND30
GND29
GND28
GND27
GND26
GND25
GND24
GND23
GND22
GND21
GND20
GND19
GND18
GND17
GND16
GND15
GND14
GND13
GND12
GND11
GND10
GND9
GND8
GND7
GND6
GND5
GND4
GND3
GND2
GND1
2 1
21
21
21
21
21
21
1
SHEETDATE
23
7 3 2 16 5 4
E
A
B
C
E
D
C
B
A
7 6 5 4
D
DEPARTMENT
SIZE
PROJECT DOCUMENT NUMBER REV
REVIEWER
DESIGNER
IN
IN
OUT
IN
OUT
IN
OUT
IN
IN
OUT
IN
BI
IN
OUT
BI
BI
BI
IN
BI
OUT
BI
BI
BI
BI
OUT
BI
BI
IN
OUT
OUT
IN
IN
IN
IN
OUT
IN
IN
IN
IN
IN
IN
IN
IN
IN
IN
IN
IN
IN
OUT
OUT
IN
OUT
OUT
IN
IN
IN
IN
OUT OUT
OUT
IN
IN
IN
IN
IN
IN
OUT
OUT
IN
IN
OUT
IN
IN
IN
OUT
OUT
OUT
IN
OUT
IN
OUT
OUT
IN
IN
OUT
IN
OUT
IN
IN
IN
IN
IN
IN
IN
IN
IN
C



Thu Aug 24 14:09:24 2023<NAME_2>
<NAME_1>
MB FABCGTI V02
83 OF 365
P 1V 8_A UX
P 3V 3_A UX
P 3V 3_A UX
P V DD18_S 5_P 1
P 3V 3_A UXP 1V 8_A UX
P V DD18_S 5_P 0
8283161
8283161
1458082
80133139
80 159
80 159
81146147
80
8283161
28 81
28 81
55 81
55 81
81146147
80134135136
81140141142
81140141248
8129
8154
8154
80
80134135248
8185
8185
8283161
15080
17281
20782
22482
21082
20082
21782
19381
82 83 161
81 144
81 145
80 159
80 159
82 83 161
82 83 161
8185
8127
8127
8129
81 153
82 83 161
0402LF
CHIP
1/16W
1%
10K
0402LF
10K
1%
CHIP
1/16W
CHIP
10K
1%
0402LF
1/16W 1/16W
CHIP
1%
0402LF
10K
1%
10K
CHIP
1/16W
0402LF
0402LF
1%
1/16W
CHIP
10K
1/16W
CHIP
0402LF
10K
1%
1/16W
CHIP
0402LF
10K
1%
1/16W
0402LF
10K
1%
CHIP
1/16W
0402LF
10K
1%
CHIP
10K
CHIP
1%
1/16W
0402LF 0402LF
CHIP
1/16W
10K
1%
FM_APML_MUX2_OE_N
FM_APML_MUX2_SEL
10KE 1S _0_P RS NT_N
FM_S Y S _THRO TTLE _N
4.7K
E MP TY
4.7K
C040216V10%
NEAR CPLD
1K
1K
1K
FM_I3C_CP U0_MUX 0_O E _N
1%
FM_I3C_CP U0_MUX 1_O E _N
10K
E 1S _0_P 12V _E N
CP LD_JTA G _E N
E MP TY
10K
FM_SEC_MUX_OE_N
E MP TY
4.7K
FPGA 4/6
0.1UF
NEAR CPLD
X 7R10%
0.1UF 16V C0402
0.1UF
0.1UF
0.1UF
0.1UF
0.1UF
0.1UF
0.1UF
0.1UF
0.1UF
0.1UF
0.1UF
0.1UF
0.1UF
0.1UF X 7R
0.1UF
0.1UF
0.1UF
0.1UF
0.1UF
RS T_CP U0_P E RS T1_N
RS T_CP U0_P E RS T0_N
RS T_CP U1_P E RS T1_N
RS T_CP U1_P E RS T0_N
2.2K
1% 0402LF
CHIP2K
4.7KE 1S _0_P 3V 3_E N
E MP TYP 12V _O CP _S FF_E N_R
P 12V _O CP _V 3_2_E N_R
4.7KP 3V 3_O CP _V 3_2_E N_R
4.7KS CM_US B _O C_N
4.7K
4.7KFM_P 1_P CC1_N
4.7KFM_P 1_P CC0_N
1K
1KCP LD_P RO G RA MN
P 3V 3_O CP _S FF_E N_R 4.7K
CHIP
2K CHIP
2K
RST_PERST_CPU1_SWB_N
RST_PERST_CPU1_SWB_1_N
4.7K
E MP TY
4.7K
E MP TY
FM_SEC_MUX_SEL
S CM_S Y S _P W RB TN_N 1%1K
EMPTY
E MP TY
1K
P RS NT_HDT_N 1K
P V DD11_S 3_P 0_P MA LE RT
P V DD11_S 3_P 1_P MA LE RT
P V DDCR_CP U0_P 1_P MA LE RT 1K
P V DDCR_CP U1_P 0_S MB _A LE RT
P V DDCR_CP U1_P 1_S MB _A LE RT 1K
P V DDCR_CP U0_P 0_P MA LE RT 1K
1%
E MP TY
1/16W
1/16W
FM_APML_MUX2_SEL
1K
1%
CHIP
E MP TY
0.1UF
0.1UF
E MP TY
4.7K
E MP TY
4.7K
4.7K
1/16W RS T_P E RS T_M2_0_N
RS T_P E RS T_E 1S _0_N
0402LF
1/16W
FM_I3C_CP U1_MUX 0_O E _N
FM_I3C_CP U1_MUX 1_O E _N
FM_SEC_MUX_OE_N
FM_SEC_MUX_SEL
0402LF
0402LF
E MP TY
RST_PERST_CPU0_SWB_N
FM_P 0_P CC0_N
FM_P 0_P CC1_N
RS T_CP U0_K B RS T_R_N
FM_ESPI_CPU0_ALERT_R_SEL
FM_APML_MUX2_OE_N
R1304
R8033
R126 R136
R135
R134 R3
R6188
R6187
R6186
R6185
R6115
R6114
21C359
2
1
R17
2
1
R16
2
1
R800
21C361
21C360
21C362
2
1
R12
2
1
R11
2
1
R10
21C1133
21R1287
21R1288
21R1351
21R654
21R757
21R1071
21R639
2
1
R19
2
1
R18
2
1
R804
21C1171
21C1173
21C1172
21C1174
21C1175
21C1176
21C355
21C356
21C357
21C358
2
1
R25
21C1127
21C1126
21C1129
21C1128
21C352
21C1131
21C1132
21C1134
21R1285
21R1286
21R1185
21R1188
21R1186
21R1187
21R1190
21R1189
21R1527
21R1314
21R993
21R6062
21R6061
21R1195
21R638
R64
CAD NOTE:CAD NOTE:
21
2
1
21
2
1
2
1
21
21 21
21
2
1
21
2
1
21
21
1
SHEETDATE
23
7 3 2 16 5 4
E
A
B
C
E
D
C
B
A
7 6 5 4
D
DEPARTMENT
SIZE
PROJECT DOCUMENT NUMBER REV
REVIEWER
DESIGNER
IN
IN
OUT
OUT
OUT
OUT
OUT
OUT
OUT
OUT
OUT
OUT
OUT
OUT
OUT
OUT
OUT
OUT
OUT
IN
IN
IN
OUT
OUT
OUT IN
OUT
OUT
IN
OUT
IN
IN
OUT
IN
OUT
OUT
IN
IN
IN
OUT
IN
OUT
OUT
IN
IN
OUT
C



BOARD SKU ID0/1/2/3 FOR VR SOURCE OPTION
PVT2
DVT2
0
0
0 1
2 RT
8 RT
ID2
001
0
PVT1
EVT
REV
0 0
ID1
0 1
ID0
0
1
1
DVT1
ID0
0 0
00
AMD PLATFORM
0
BRD_SKU
20220613: BOARD SKU ID4 FOR PLATFORM OPTION
INTEL PLATFORM 0
ID4
1
0
0
1
ID1BRD_SKU
TBC
ID3 ID2
0
0
HSC-MPS5990+ADC-TIC+VR-RTT
HSC-MODULE+ADC-MAM+VR-SNI
HSC-MODULE+ADC-MAM+VR-MPS
0
1
0 0 0
0
1
MODIFY HSC-MODULE BOARD ID20220711:
HSC-REEDSEMI+ADC-TIC+VR-RTT
0 1
1HSC-MPS5990+ADC-TIC+VR-MPS
20220420: ADD SKU ID / REV ID TO INFORM BMC OF MB INFORMATION
Thu Aug 24 14:09:24 2023<NAME_2>
<NAME_1>
MB FABCGTI V02
84 OF 365
0402LF
P 1V 8_A UX
P V DD18_S 5_P 0
P V DD18_S 5_P 0
P 3V 3_A UX
P 3V 3_A UX
P 1V 8_A UX
1K
1/16W
FAB_BMC_REV_ID0
0402LF
EMPTY
1%
1K
0402LF
1%
CHIP
1/16W
1K 1K
0402LF
1/16W
EMPTY
1K
1%
CHIP
1%
0402LF
1%
0402LF
CHIP
1/16W
1K
1%
FAB_REV_ID0
0402LF
1/16W
EMPTY
1K
1%
0402LF
1%
1/16W 1/16W
EMPTY
FAB_REV_ID1
1%
1K
FAB_REV_ID2
1K
28
28
28
82
82
82
28
28
28
28
28
80
80
80
80
15081
80
FM_BOARD_SKU_ID4
FM_BOARD_SKU_ID1
0402LF
0402LF
0402LF
1/16W
FM_BOARD_SKU_ID3
FM_BOARD_SKU_ID2
EMPTY
1%
1K
1%
1/16W
0402LF
1/16W1/16W
0402LF
CHIP
1/16W
FM_BOARD_SKU_ID0
1/16W
FM_BOARD_BMC_SKU_ID2
FM_BOARD_BMC_SKU_ID3
EMPTYEMPTYEMPTY
0402LF
CHIP
1%
1/16W
0402LF
EMPTY
1/16W
0402LF
1K
1%
EMPTY
0402LF
1/16W
1K
0402LF
1K
1%
1K
1%
1/16W
CHIP
1/16W
1K
1%
1/16W
1%
1K
0402LF
0402LF
FPGA 5/6 (BOARD ID)
1/16W
CHIP
0402LF
1/16W
EMPTY
1%
CHIP
1%
1K
EMPTY
0402LF
EMPTY
CHIP
1%
0402LF
1K1K
1K
FM_BOARD_BMC_SKU_ID0
FM_BOARD_BMC_SKU_ID1
1K
CHIP
1%
1%
1K
1%
1/16W
CHIP
1K
CHIP
1/16W
1%
1%
0402LF
1%
1K
0402LF
EMPTY
CHIP
IC
S N74LV C1G 07DB V R
S MLF
CHIP
1/16W
5%
4.7K
0402LF
4.7K
1/16W
CHIP
5%
0402LF
25V
10%
X 7R
0.1UF
0402
S CM_IRQ _R_N S CM_IRQ _NS CM_IRQ _1V 8_N
1/16W
FM_BOARD_BMC_SKU_ID4
1K
1K
0402LF
1/16W
1K 1K
1/16W
1K
1% 1%
0402LF
1/16W
1%
33
1%
0402LF
1K1K
CHIP
1%
1/16W
CHIP
0402LF
CHIP
1/16W
1%
1K
0402LF
1/16W
EMPTY
0402LF
0402LF
EMPTY
1/16W 1/16W
FAB_BMC_REV_ID1
FAB_BMC_REV_ID2
2
1
R1338
21 R714
5
13
2
U92
2
1 C552
2
1
R996
NC
Y
GND
A
VCC
2
1
2
1
2
1
2
1
2
1
2
1
2
1
2
1
2
1
2
1
2
1
2
1
2
1
2
1
2
1
2
1
2
1
2
1
2
1
2
1
2
1
2
1
2
1
2
1
2
1
2
1
2
1
2
1
2
1
2
1
2
1
2
1
1
SHEETDATE
23
7 3 2 16 5 4
E
A
B
C
E
D
C
B
A
7 6 5 4
D
DEPARTMENT
SIZE
PROJECT DOCUMENT NUMBER REV
REVIEWER
DESIGNER
OUT
OUT
OUT
OUT
OUT
OUT
OUT
OUT
OUT
OUT
OUT
OUT
OUT
OUT
OUT
OUT
OUTIN
R6148
R6151
R6147
R6150
R6146
R6149
R6135
R6132R6131
R6134R6133
R6130
R6142
R6137
R6121
R6126
R6141
R6136
R6125
R6120 R6124R6123
R6129R6128
R6140R6139
R6127
R6138
R6143 R6144
R6122
R6145
C



PLACE THE 100PF CAPS FOR SI AND CLOSE TO MAIN PLD
TBC
PIN2: PROGRAMMER TDI
PIN3: PROGRAMMERTDO
CAD NOTE: IF DEPOP R1422, PLEASE POP R557
CAD NOTE: IF DEPOP R530, PLEASE POP R556
Thu Aug 24 14:09:02 2023<NAME_2>
<NAME_1>
MB FABCGTI V02
85 OF 365
P3V3_AUX
P3V3_AUX
P5V_AUX_VCC
P3V3_AUX P3V3_AUX
P 3V 3_A UX
G ND G ND
P 3V 3_A UX
P 3V 3_A UX
100K
IRQ_HSC_FAULT_N268 263
80
82
189190
82
81 81
28 81
55 81
28 81 78
55 81 78
8183
19081270
144150
236
8183
82
80
128
8183
145
128
128
242
82
255
150
17180
80171
17180
17180
33.2
0
0
0
0
0
0
0
0
0
33.2
33.2
0
IRQ_HSC_FAULT
IRQ_HSC_FAULT_BUF_N
1/16W
1%
0402LF
E MP TY
IC
PJT138K
SMLF
4.7K
CHIP
1/16W
5%
0402LF
0402LF
100K
1%
1/16W
CHIP
X7R
10%
0402
0.1UF
25V
0402LF 1/16W
E MP TY5%0
IC
SMLF
PJT138K
LED_HDD_ACTIVITY_B_PLD_N
PWRGD_P5V_AUX
PW R GD _P5V_AU X_R 2 PW R GD _P5V_AU X_R 3PW R GD _P5V_AU X_R 1
EMPTY
1/16W
1%
10K
0402LF
PJT138K
IC
SMLF
1/16W
CHIP
5%
4.7K
0402LF
0402LF
CHIP
1/16W
100K
1%
0402
X7R
10%
25V
0.1UF
IC
SMLF
PJT138K
B MC_FP G A _LE D1_R_N
B MC_FP G A _LE D1
B MC_FP G A _LE D2_R_N
B MC_FP G A _LE D1_N
B MC_FP G A _LE D2_N
B MC_FP G A _LE D2
200 1% CHIP1/16W 0402LF
0402LF200 1% CHIP1/16W
S MLF
LTST-C 190KSKT-P
IC
LE D_Y E LLO W
IC
S MLF
LTST-C190KSKT-P
LE D_Y E LLO W
2N7002K DW
IC
SMLF
RS T_CP U0_RE S E TL_N
RS T_CP U1_RE S E TL_NCHIP
0
0402LF
P W RG D_CP U0_P W RO K
P W RG D_CP U1_P W RO KCHIP
1/16W
0402LF
1%
100
1K
RST_PERST_CPU0_SWB_N
PWRGD_P3V3_AUX
LED_HDD_ACTIVITY_B_N
FM_THERMAL_ALERT_N
RST_PERST_CPU1_SWB_1_N
FM_S MB _RS T_E 1S _0_N
SCM_SYS_PWROK_R
CHIP
RST_PERST_CPU1_SWB_1_R_N
RST_PERST_CPU1_SWB_N
FM_S MB _RS T_E 1S _0_R_N
RST_PERST_CPU1_SWB_R_N
RST_PERST_CPU0_SWB_R_N
PWRGD_P3V3_AUX_PDB
FM_THERMAL_ALERT_R_N
100PF
SCM_SYS_PWROK_R2
SCM_SYS_PWROK_R1
JTA G _P LD_TCK
0
JTA G _S CM_P LD_TDO JTA G _P LD_TDO
JTA G _S CM_P LD_TDI JTA G _P LD_TDI
JTA G _S CM_P LD_TMS JTA G _P LD_TMS
1/16W
5%
4.7K
0402LF
CHIP
JTA G _S CM_P LD_TCK
THLF
IO
CO NN8_HB B 1081-L200D-8H
X 7R
10%
0.1UF
16V
C0402
50V
5%
NPO
0402
FPGA 6/6
2 1R6118
D8
D7
R2
21 R6112
21 R6093
21 R6092
21 R6113
21 R6078
21 R6075
21 R6074
41
52
36
Q28
21
R1194
21
R1266
2 1R15
2
1
R530
21R1036
2
1C20
8
7
6
5
4
3
2
1
J57
2 1R13
2 1R9
21R1303
2 1R14
G2G1
G2
G1
S2 D2
D1S1
S2 D2
D1S1
R9027
R9026
R1422
C8005
C1209
5
2
CA
CA
52
4 3
1 6
4 3
1 6
Q9003
Q9003
Q50Q50
A C
A C
D2D1
S2S1
G2G1
8
7
6
5
4
3
2
1
21R9028
2
1
2
1
2
1
2
1
2
1
2
1
21
2
1
2
1
2
1
2
1
2
1
1
SHEETDATE
23
7 3 2 16 5 4
E
A
B
C
E
D
C
B
A
7 6 5 4
D
DEPARTMENT
SIZE
PROJECT DOCUMENT NUMBER REV
REVIEWER
DESIGNER
IN OUT
IN OUT
OUT
IN OUT
OUT
IN OUT
IN
OUTIN
IN OUT
IN OUT
ININ
OUT
IN
OUT
OUT
BI
BIIN
OUT
OUT
IN OUT
IN
C9005
R9025
R6090
R2346R2344
R2343
C



Thu Aug 24 14:08:51 2023<NAME_2>
<NAME_1>
MB FABCGTI V02
86 OF 365
P 3V 3P 3V 3
P 3V 3_A UX
P 3V 3_A UX
P 3V 3_A UX
P 12V _ME M_CP U0
P 3V 3_A UX
1598788899091
10
10
10
10
10
10
10
10
10
10
10
86
82
8687
8889
9091
86 87 88 89 90 91
868788899091
10
10
10
10
10
10
10
10
86
10
10
10
87888990
91159
1K
0.1UF
25V
0402
1K
I3C_SPD_DDRAF_CPU0_SCL
M_A _CP U0_CLK _DN<0>
M_A _CP U0_CLK _DP <0>
M_A _CP U0_S A _CB <7:0>
10%
X 7R
M_A _CP U0_S A _CS _N<0>
M_A _CP U0_S A _P A R
M_A _CP U0_S A _RS P <0>
M_A _CP U0_S B _CS _N<1>
M_A _CP U0_S B _CS _N<0>
M_A _CP U0_S B _RS P <0>
M_A _CP U0_S B _P A R
M_A _CP U0_S A _CS _N<1>
P D_CHA _CP U0_DIMM0_S A A
PWRGD_CHAF_CPU0_R1 PWRGD_CHAF_CPU0_R2
P W RG D_CHA F_CP U0
PWRGD_CHAF_CPU0
PWRGD_CHAF_CPU0
M_A _CP U0_S A _CA <6:0>
M_A _CP U0_S B _CA <6:0>
M_A _CP U0_S A _DQ <31:0>
M_A _CP U0_S A _DQ S _DP <9:0>
M_A _CP U0_S A _DQ S _DN<9:0>
M_A _CP U0_S B _DQ S _DP <9:0>
M_A _CP U0_S B _DQ S _DN<9:0>
M_A _CP U0_S B _DQ <31:0>
DDR5 - CPU0 CHA
EMPTY
SMLF
B0530WS7F
1/16W 0402LFEMPTY
1%10K
0 5%
1/16W 0402LFCHIP
0 5%
1/16W CHIP 0402LF
0402LF
1%
10K
CHIP
1/16W
SMLF
IO
SCONN288_DDR506112002KQ
IO
SCONN288_DDR506112002KQ
SMLF
IO
SMLF
SCONN288_DDR506112002KQ
P D_CHA _CP U0_DIMM0_S A A
49.9
M_A _CP U0_S B _CB <7:0>
M_A _CP U0_RE S E T_N
M_A _CP U0_A LE RT_N
P W RG D_CHA _CP U0_DIMM0
I3C_SPD_DDRA_CPU0_SCL
I3C_SPD_DDRA_CPU0_SDA
I3C_S P D_DDRA F_CP U0_S DA
CHIP
10
0402LF
CHIP
1/16W
0402LF
10K
1%
X 6S
C0805
25V
10UF
10%
1K
0402LF
E MP TY
1/16W
1% 1%
0402LF
E MP TY
1/16W
10%
10UF
C0805
25V
X 6S
J1
J1
R1674
R1568
2
1C142
2
1
R89
2
1
R88
2 1R291
2
1C88
2
1C89
2
1
R7
6
0
5
8
9
9
8
7
5
6
7
6
5
4
4
3
2
3
2
1
0
1
0
9
8
9
8
7
5
6
7
6
5
4
3
4
3
2
0
1
2
1
0
28
27
31
30
29
24
25
26
22
21
23
18
17
16
20
19
15
14
11
9
10
8
6
7
4
5
3
1
2
31
30
0
29
27
26
25
28
24
22
21
20
23
19
18
17
16
14
15
13
11
12
10
9
8
7
6
5
4
3
2
0
1
2
1
0
3
4
5
6
7
3
1
0
2
4
5
0
1
2
3
6
4
5
1
2
4
3
7
6
13
12
J1
DQS7_A _c||TDQS7_A _c
DQS6_A _t||TDQS6_A _t
DQS8_B_t||TDQS8_B_t
DQS8_B_c||TDQS8_B_c
DQS7_B_t||TDQS7_B_t
DQS0_A _c
DQS0_A _t
DQS0_B_c
DQS0_B_t
DQS1_A _c
DQS1_A _t
DQS1_B_c
DQS1_B_t
DQS2_A _c
DQS2_A _t
DQS2_B_c
DQS2_B_t
DQS3_A _c
DQS3_A _t
DQS3_B_c
DQS3_B_t
DQS4_A _c
DQS4_A _t
DQS4_B_c
DQS4_B_t
DQS5_A _c||TDQS5_A _c||DQS5_A _t||TDQS5_A _t
DQS5_A _t||TDQS5_A _t
DQS5_B_c||TDQS5_B_c
DQS5_B_t||TDQS5_B_t
DQS6_A _c||TDQS6_A _c||DQS6_A _t||TDQS6_A _t
DQS6_B_c||TDQS6_B_c
DQS6_B_t||TDQS6_B_t
DQS7_A _t||TDQS7_A _t
DQS7_B_c||TDQS7_B_c
DQS8_A _c||TDQS8_A _c
DQS8_A _t||TDQS8_A _t
DQS9_A _c||TDQS9_A _c
DQS9_A _t||TDQS9_A _t
DQS9_B_c||TDQS9_B_c
DQS9_B_t||TDQS9_B_t||DBI4_B_n
21
288
286
284
281
279
277
275
273
270
268
266
264
262
259
257
255
253
251
248
246
244
242
240
237
235
233
230
228
226
224
222
219
216
214
212
210
208
206
204
202
199
197
195
193
191
188
186
184
182
180
177
175
173
171
169
166
164
162
160
158
155
153
151
143
141
139
136
134
132
130
128
125
123
121
119
117
114
112
110
108
106
103
101
99
97
95
92
90
88
85
83
81
79
77
75
73
71
69
67
65
63
61
59
57
54
52
50
48
46
43
41
39
37
35
32
30
28
26
24
21
19
17
15
13
10
8
6
146
145
1
G3
G2
G1
93
94
201
200
283
282
190
189
272
271
179
178
261
260
168
167
250
249
157
156
239
238
55
56
137
138
44
45
126
127
33
34
115
116
22
23
104
105
11
12
3
232
231
220
150
149
144
2
207
147
227
74
87
86
5
4
148
287
194
285
192
142
49
140
47
280
187
278
185
135
42
133
40
276
183
274
181
131
38
129
36
269
176
267
174
124
31
122
29
265
172
263
170
120
27
118
25
258
165
256
163
113
20
111
18
254
161
252
159
109
16
107
14
247
154
245
152
102
9
100
7
229
209
84
64
217
218
236
205
234
203
91
60
89
58
243
198
241
196
98
53
96
51
82
72
225
215
80
70
223
213
78
68
221
211
76
66
62
D8003
CA
3/3
G3
G2
G1
VSS62
VSS61
VSS60
VSS58
VSS104
VSS102
VSS100
VIN_BULK2
VIN_BULK1
VIN_BULK0
VSS126
VSS125
VSS124
VSS123
VSS122
VSS121
VSS120
VSS119
VSS118
VSS117
VSS116
VSS115
VSS114
VSS113
VSS112
VSS111
VSS110
VSS109
VSS108
VSS107
VSS106
VSS105
VSS103
VSS101
VSS99
VSS98
VSS97
VSS96
VSS95
VSS94
VSS93
VSS92
VSS91
VSS90
VSS89
VSS88
VSS87
VSS86
VSS85
VSS84
VSS83
VSS82
VSS81
VSS80
VSS79
VSS78
VSS77
VSS76
VSS75
VSS74
VSS73
VSS72
VSS71
VSS70
VSS69
VSS68
VSS67
VSS66
VSS65
VSS64
VSS63
VSS59
VSS57
VSS56
VSS55
VSS54
VSS53
VSS52
VSS51
VSS50
VSS49
VSS48
VSS47
VSS46
VSS45
VSS44
VSS43
VSS42
VSS41
VSS40
VSS39
VSS38
VSS37
VSS36
VSS35
VSS34
VSS33
VSS32
VSS31
VSS30
VSS29
VSS28
VSS27
VSS26
VSS25
VSS24
VSS23
VSS22
VSS21
VSS20
VSS19
VSS18
VSS17
VSS16
VSS15
VSS14
VSS13
VSS12
VSS11
VSS10
VSS9
VSS8
VSS7
VSS6
VSS5
VSS4
VSS3
VSS2
VSS1
VSS0
2/3
1/3
PWR_GOOD||FAIL_n
DQ31_A
CB7_A
CB4_A
CB1_A
CB7_B
ALERT_n
CA0_A
CA0_B
CA1_A
CA1_B
CA2_A
CA2_B
CA3_A
CA3_B
CA4_A
CA4_B
CA5_A
CA5_B
CA6_A
CA6_B
CB6_A
CB5_A
CB3_A
CB2_A
CB0_A
CB6_B
CB5_B
CB4_B
CB3_B
CB2_B
CB1_B
CB0_B
CK_c
CK_t
CS0_A_n
CS0_B_n
CS1_A_n
CS1_B_n
DQ30_A
DQ29_A
DQ28_A
DQ27_A
DQ26_A
DQ25_A
DQ24_A
DQ23_A
DQ22_A
DQ21_A
DQ20_A
DQ19_A
DQ18_A
DQ17_A
DQ16_A
DQ15_A
DQ14_A
DQ13_A
DQ12_A
DQ11_A
DQ10_A
DQ9_A
DQ8_A
DQ7_A
DQ6_A
DQ5_A
DQ4_A
DQ3_A
DQ2_A
DQ1_A
DQ0_A
DQ31_B
DQ30_B
DQ29_B
DQ28_B
DQ27_B
DQ26_B
DQ25_B
DQ24_B
DQ23_B
DQ22_B
DQ21_B
DQ20_B
DQ19_B
DQ18_B
DQ17_B
DQ16_B
DQ15_B
DQ14_B
DQ13_B
DQ12_B
DQ11_B
DQ10_B
DQ9_B
DQ8_B
DQ7_B
DQ6_B
DQ5_B
DQ4_B
DQ3_B
DQ2_B
DQ1_B
DQ0_B
HAS
HSCL
HSDA
LBD||RSP_A_n
LBS||RSP_B_n
PAR_A
PAR_B
RESET_n
RFU6
RFU5
RFU4
RFU3
RFU2
RFU1
RFU0
VIN_MGMT
21
21
2121
2
1
21
1
SHEETDATE
23
7 3 2 16 5 4
E
A
B
C
E
D
C
B
A
7 6 5 4
D
DEPARTMENT
SIZE
PROJECT DOCUMENT NUMBER REV
REVIEWER
DESIGNER
BI
BIBI
OUT
OUT
BI
OUT
IN
IN
OUT
OUT
OUT
OUT
BI
BI
IN
BI
IN
OUT
OUT
IN
IN
IN
IN
IN
IN
IN
IN
IN
BI
R8082
R8081R8080
R8037
C



Thu Aug 24 14:08:51 2023<NAME_2>
<NAME_1>
MB FABCGTI V02
87 OF 365
P 3V 3
P 3V 3_A UX
P 12V _ME M_CP U0
87
11
11
1598688899091
8688
8990
91
868889
9091159
11
11
11
11
11
11
11
11
11
11
11
87
11
11
11
11
11
11
11
11
11
1K
C0805
25V
10UF
10%
X 6S
C0805
25V
10UF
10%
X 6S
1%
E MP TY
1K
0402LF
1/16W
0.1UF
X 7R
0402
25V
10%
10
CHIP
0402LF
P D_CHB _CP U0_DIMM_S A A
M_B _CP U0_A LE RT_N
M_B _CP U0_RE S E T_N
I3C_SPD_DDRB_CPU0_SCL
I3C_SPD_DDRAF_CPU0_SCL
P W RG D_CHA F_CP U0
I3C_SPD_DDRB_CPU0_SDA
I3C_S P D_DDRA F_CP U0_S DA
49.9
P W RG D_CHB _CP U0_DIMM
1/16W
CHIP
1%
15.4K
0402LF
SMLF
S CO NN288_DDR506112002K Q
IO
S CO NN288_DDR506112002K Q
IO
SMLF
IO
S CO NN288_DDR506112002K Q
SMLF
DDR5 - CPU0 CHB
M_B _CP U0_S B _CB <7:0>
M_B _CP U0_S B _DQ <31:0>
M_B _CP U0_S A _DQ <31:0>
M_B _CP U0_S B _DQ S _DP <9:0>
M_B _CP U0_S B _DQ S _DN<9:0>
M_B _CP U0_S A _DQ S _DN<9:0>
M_B _CP U0_S A _DQ S _DP <9:0>
M_B _CP U0_S A _CA <6:0>
M_B _CP U0_S A _CB <7:0>
M_B _CP U0_S B _CA <6:0>
M_B _CP U0_S B _RS P <0>
P D_CHB _CP U0_DIMM_S A A
M_B _CP U0_CLK _DN<0>
M_B _CP U0_S A _CS _N<0>
M_B _CP U0_S A _CS _N<1>
M_B _CP U0_S B _CS _N<1>
M_B _CP U0_S A _RS P <0>
M_B _CP U0_S B _P A R
M_B _CP U0_S A _P A R
M_B _CP U0_S B _CS _N<0>
M_B _CP U0_CLK _DP <0>
21R1675
R1569
2
1C145
2
1C143
2
1
R90
2 1R292
2
1C92
2
1
R761
1
2
0
3
4
5
7
6
2
1
0
3
4
5
6
7
3
1
0
2
1
0
2
3
4
5
7
6
8
9
10
11
12
13
15
14
18
17
16
21
22
20
23
19
26
27
25
28
24
0
30
31
29
2
1
3
4
5
7
6
8
9
10
14
15
13
12
11
17
18
16
20
19
6
4
5
0
1
2
3
5
4
6
23
21
22
24
25
26
31
27
28
30
29
0
1
2
1
0
2
3
4
3
4
5
6
7
6
5
7
8
9
8
9
0
1
0
1
2
3
2
3
4
4
5
6
7
6
5
7
8
9
9
8
J15
J15
J15
DQS7_A _c||TDQS7_A _c
DQS6_A _t||TDQS6_A _t
DQS8_B_t||TDQS8_B_t
DQS8_B_c||TDQS8_B_c
DQS7_B_t||TDQS7_B_t
DQS0_A _c
DQS0_A _t
DQS0_B_c
DQS0_B_t
DQS1_A _c
DQS1_A _t
DQS1_B_c
DQS1_B_t
DQS2_A _c
DQS2_A _t
DQS2_B_c
DQS2_B_t
DQS3_A _c
DQS3_A _t
DQS3_B_c
DQS3_B_t
DQS4_A _c
DQS4_A _t
DQS4_B_c
DQS4_B_t
DQS5_A _c||TDQS5_A _c||DQS5_A _t||TDQS5_A _t
DQS5_A _t||TDQS5_A _t
DQS5_B_c||TDQS5_B_c
DQS5_B_t||TDQS5_B_t
DQS6_A _c||TDQS6_A _c||DQS6_A _t||TDQS6_A _t
DQS6_B_c||TDQS6_B_c
DQS6_B_t||TDQS6_B_t
DQS7_A _t||TDQS7_A _t
DQS7_B_c||TDQS7_B_c
DQS8_A _c||TDQS8_A _c
DQS8_A _t||TDQS8_A _t
DQS9_A _c||TDQS9_A _c
DQS9_A _t||TDQS9_A _t
DQS9_B_c||TDQS9_B_c
DQS9_B_t||TDQS9_B_t||DBI4_B_n 93
94
201
200
283
282
190
189
272
271
179
178
261
260
168
167
250
249
157
156
239
238
55
56
137
138
44
45
126
127
33
34
115
116
22
23
104
105
11
12
288
286
284
281
279
277
275
273
270
268
266
264
262
259
257
255
253
251
248
246
244
242
240
237
235
233
230
228
226
224
222
219
216
214
212
210
208
206
204
202
199
197
195
193
191
188
186
184
182
180
177
175
173
171
169
166
164
162
160
158
155
153
151
143
141
139
136
134
132
130
128
125
123
121
119
117
114
112
110
108
106
103
101
99
97
95
92
90
88
85
83
81
79
77
75
73
71
69
67
65
63
61
59
57
54
52
50
48
46
43
41
39
37
35
32
30
28
26
24
21
19
17
15
13
10
8
6
146
145
1
G3
G2
G1
3
232
231
220
150
149
144
2
207
147
227
74
87
86
5
4
148
287
194
285
192
142
49
140
47
280
187
278
185
135
42
133
40
276
183
274
181
131
38
129
36
269
176
267
174
124
31
122
29
265
172
263
170
120
27
118
25
258
165
256
163
113
20
111
18
254
161
252
159
109
16
107
14
247
154
245
152
102
9
100
7
229
209
84
64
217
218
236
205
234
203
91
60
89
58
243
198
241
196
98
53
96
51
82
72
225
215
80
70
223
213
78
68
221
211
76
66
62
2/3
3/3
G3
G2
G1
VSS62
VSS61
VSS60
VSS58
VSS104
VSS102
VSS100
VIN_BULK2
VIN_BULK1
VIN_BULK0
VSS126
VSS125
VSS124
VSS123
VSS122
VSS121
VSS120
VSS119
VSS118
VSS117
VSS116
VSS115
VSS114
VSS113
VSS112
VSS111
VSS110
VSS109
VSS108
VSS107
VSS106
VSS105
VSS103
VSS101
VSS99
VSS98
VSS97
VSS96
VSS95
VSS94
VSS93
VSS92
VSS91
VSS90
VSS89
VSS88
VSS87
VSS86
VSS85
VSS84
VSS83
VSS82
VSS81
VSS80
VSS79
VSS78
VSS77
VSS76
VSS75
VSS74
VSS73
VSS72
VSS71
VSS70
VSS69
VSS68
VSS67
VSS66
VSS65
VSS64
VSS63
VSS59
VSS57
VSS56
VSS55
VSS54
VSS53
VSS52
VSS51
VSS50
VSS49
VSS48
VSS47
VSS46
VSS45
VSS44
VSS43
VSS42
VSS41
VSS40
VSS39
VSS38
VSS37
VSS36
VSS35
VSS34
VSS33
VSS32
VSS31
VSS30
VSS29
VSS28
VSS27
VSS26
VSS25
VSS24
VSS23
VSS22
VSS21
VSS20
VSS19
VSS18
VSS17
VSS16
VSS15
VSS14
VSS13
VSS12
VSS11
VSS10
VSS9
VSS8
VSS7
VSS6
VSS5
VSS4
VSS3
VSS2
VSS1
VSS0
1/3
PWR_GOOD||FAIL_n
DQ31_A
CB7_A
CB4_A
CB1_A
CB7_B
ALERT_n
CA0_A
CA0_B
CA1_A
CA1_B
CA2_A
CA2_B
CA3_A
CA3_B
CA4_A
CA4_B
CA5_A
CA5_B
CA6_A
CA6_B
CB6_A
CB5_A
CB3_A
CB2_A
CB0_A
CB6_B
CB5_B
CB4_B
CB3_B
CB2_B
CB1_B
CB0_B
CK_c
CK_t
CS0_A_n
CS0_B_n
CS1_A_n
CS1_B_n
DQ30_A
DQ29_A
DQ28_A
DQ27_A
DQ26_A
DQ25_A
DQ24_A
DQ23_A
DQ22_A
DQ21_A
DQ20_A
DQ19_A
DQ18_A
DQ17_A
DQ16_A
DQ15_A
DQ14_A
DQ13_A
DQ12_A
DQ11_A
DQ10_A
DQ9_A
DQ8_A
DQ7_A
DQ6_A
DQ5_A
DQ4_A
DQ3_A
DQ2_A
DQ1_A
DQ0_A
DQ31_B
DQ30_B
DQ29_B
DQ28_B
DQ27_B
DQ26_B
DQ25_B
DQ24_B
DQ23_B
DQ22_B
DQ21_B
DQ20_B
DQ19_B
DQ18_B
DQ17_B
DQ16_B
DQ15_B
DQ14_B
DQ13_B
DQ12_B
DQ11_B
DQ10_B
DQ9_B
DQ8_B
DQ7_B
DQ6_B
DQ5_B
DQ4_B
DQ3_B
DQ2_B
DQ1_B
DQ0_B
HAS
HSCL
HSDA
LBD||RSP_A_n
LBS||RSP_B_n
PAR_A
PAR_B
RESET_n
RFU6
RFU5
RFU4
RFU3
RFU2
RFU1
RFU0
VIN_MGMT
21
1
SHEETDATE
23
7 3 2 16 5 4
E
A
B
C
E
D
C
B
A
7 6 5 4
D
DEPARTMENT
SIZE
PROJECT DOCUMENT NUMBER REV
REVIEWER
DESIGNER
BI
BI
IN
OUT
IN
OUT
OUT
OUT
OUT
OUT
BIIN
IN
BI
IN
IN
IN
IN
IN
IN
IN
BI
IN
IN
BI
OUT
OUT
C



Thu Aug 24 14:08:51 2023<NAME_2>
<NAME_1>
MB FABCGTI V02
88 OF 365
P 12V _ME M_CP U0
P 3V 3
P 3V 3_A UX
I3C_SPD_DDRC_CPU0_SCL
12
88
868789
9091159
1598687899091
12
12
12
12
12
12
12
12
12
88
12
12
8687
8990
91
12
12
12
12
12
12
12
12
12
12
1K
25V
0402
0.1UF
10%
X 7R
E MP TY
1/16W
1K
0402LF
1%
X 6S
10%
10UF
C0805
25V
X 6S
10%
10UF
25V
C0805
10
CHIP 0402LF
I3C_SPD_DDRC_CPU0_SDA
M_C_CP U0_A LE RT_N
P D_CHC_CP U0_DIMM_S A A
I3C_S P D_DDRA F_CP U0_S DA
49.9
I3C_S P D_DDRA F_CP U0_S CL
M_C_CP U0_RE S E T_N
M_C_CP U0_CLK _DN<0>
M_C_CP U0_CLK _DP <0>
M_C_CP U0_S A _CS _N<0>
M_C_CP U0_S B _CS _N<0>
M_C_CP U0_S A _CS _N<1>
M_C_CP U0_S B _CS _N<1>
M_C_CP U0_S A _P A R
M_C_CP U0_S B _P A R
P D_CHC_CP U0_DIMM_S A A
M_C_CP U0_S B _RS P <0>
M_C_CP U0_S A _RS P <0>
P W RG D_CHA F_CP U0
P W RG D_CHC_CP U0_DIMM
M_C_CP U0_S B _DQ S _DN<9:0>
M_C_CP U0_S B _DQ S _DP <9:0>
M_C_CP U0_S A _DQ S _DP <9:0>
M_C_CP U0_S A _DQ S _DN<9:0>
M_C_CP U0_S B _DQ <31:0>
M_C_CP U0_S B _CA <6:0>
M_C_CP U0_S A _CA <6:0>
M_C_CP U0_S B _CB <7:0>
M_C_CP U0_S A _CB <7:0>
M_C_CP U0_S A _DQ <31:0>
DDR5 - CPU0 CHC
S CO NN288_DDR506112002K Q
SMLF
IO
IO
S CO NN288_DDR506112002K Q
SMLF
IO
SMLF
S CO NN288_DDR506112002K Q
0402LF
23.2K
1%
CHIP
1/16W
J17
J17
J17
R1677
R1570
2
1C147
2
1C146
2
1
R91
2 1R293
2
1C96
2
1
R762
0
1
2
3
4
5
6
7
9
8
1
0
2
3
4
6
5
7
8
9
0
1
3
2
4
5
7
6
8
9
0
1
2
3
4
5
6
8
7
9
29
30
28
27
31
26
25
24
22
21
23
6
4
5
3
2
1
0
5
4
6
19
20
16
18
17
11
12
13
15
14
10
9
8
6
7
5
4
3
1
2
29
31
30
0
24
28
25
27
26
19
23
20
22
21
16
17
18
14
15
13
12
11
10
9
8
6
7
5
4
3
2
0
1
2
0
1
3
7
6
5
4
3
0
1
2
6
7
5
4
3
0
2
1
DQS7_A _c||TDQS7_A _c
DQS6_A _t||TDQS6_A _t
DQS8_B_t||TDQS8_B_t
DQS8_B_c||TDQS8_B_c
DQS7_B_t||TDQS7_B_t
DQS0_A _c
DQS0_A _t
DQS0_B_c
DQS0_B_t
DQS1_A _c
DQS1_A _t
DQS1_B_c
DQS1_B_t
DQS2_A _c
DQS2_A _t
DQS2_B_c
DQS2_B_t
DQS3_A _c
DQS3_A _t
DQS3_B_c
DQS3_B_t
DQS4_A _c
DQS4_A _t
DQS4_B_c
DQS4_B_t
DQS5_A _c||TDQS5_A _c||DQS5_A _t||TDQS5_A _t
DQS5_A _t||TDQS5_A _t
DQS5_B_c||TDQS5_B_c
DQS5_B_t||TDQS5_B_t
DQS6_A _c||TDQS6_A _c||DQS6_A _t||TDQS6_A _t
DQS6_B_c||TDQS6_B_c
DQS6_B_t||TDQS6_B_t
DQS7_A _t||TDQS7_A _t
DQS7_B_c||TDQS7_B_c
DQS8_A _c||TDQS8_A _c
DQS8_A _t||TDQS8_A _t
DQS9_A _c||TDQS9_A _c
DQS9_A _t||TDQS9_A _t
DQS9_B_c||TDQS9_B_c
DQS9_B_t||TDQS9_B_t||DBI4_B_n 93
94
201
200
283
282
190
189
272
271
179
178
261
260
168
167
250
249
157
156
239
238
55
56
137
138
44
45
126
127
33
34
115
116
22
23
104
105
11
12
288
286
284
281
279
277
275
273
270
268
266
264
262
259
257
255
253
251
248
246
244
242
240
237
235
233
230
228
226
224
222
219
216
214
212
210
208
206
204
202
199
197
195
193
191
188
186
184
182
180
177
175
173
171
169
166
164
162
160
158
155
153
151
143
141
139
136
134
132
130
128
125
123
121
119
117
114
112
110
108
106
103
101
99
97
95
92
90
88
85
83
81
79
77
75
73
71
69
67
65
63
61
59
57
54
52
50
48
46
43
41
39
37
35
32
30
28
26
24
21
19
17
15
13
10
8
6
146
145
1
G3
G2
G1
3
232
231
220
150
149
144
2
207
147
227
74
87
86
5
4
148
287
194
285
192
142
49
140
47
280
187
278
185
135
42
133
40
276
183
274
181
131
38
129
36
269
176
267
174
124
31
122
29
265
172
263
170
120
27
118
25
258
165
256
163
113
20
111
18
254
161
252
159
109
16
107
14
247
154
245
152
102
9
100
7
229
209
84
64
217
218
236
205
234
203
91
60
89
58
243
198
241
196
98
53
96
51
82
72
225
215
80
70
223
213
78
68
221
211
76
66
62
2/3
3/3
G3
G2
G1
VSS62
VSS61
VSS60
VSS58
VSS104
VSS102
VSS100
VIN_BULK2
VIN_BULK1
VIN_BULK0
VSS126
VSS125
VSS124
VSS123
VSS122
VSS121
VSS120
VSS119
VSS118
VSS117
VSS116
VSS115
VSS114
VSS113
VSS112
VSS111
VSS110
VSS109
VSS108
VSS107
VSS106
VSS105
VSS103
VSS101
VSS99
VSS98
VSS97
VSS96
VSS95
VSS94
VSS93
VSS92
VSS91
VSS90
VSS89
VSS88
VSS87
VSS86
VSS85
VSS84
VSS83
VSS82
VSS81
VSS80
VSS79
VSS78
VSS77
VSS76
VSS75
VSS74
VSS73
VSS72
VSS71
VSS70
VSS69
VSS68
VSS67
VSS66
VSS65
VSS64
VSS63
VSS59
VSS57
VSS56
VSS55
VSS54
VSS53
VSS52
VSS51
VSS50
VSS49
VSS48
VSS47
VSS46
VSS45
VSS44
VSS43
VSS42
VSS41
VSS40
VSS39
VSS38
VSS37
VSS36
VSS35
VSS34
VSS33
VSS32
VSS31
VSS30
VSS29
VSS28
VSS27
VSS26
VSS25
VSS24
VSS23
VSS22
VSS21
VSS20
VSS19
VSS18
VSS17
VSS16
VSS15
VSS14
VSS13
VSS12
VSS11
VSS10
VSS9
VSS8
VSS7
VSS6
VSS5
VSS4
VSS3
VSS2
VSS1
VSS0
1/3
PWR_GOOD||FAIL_n
DQ31_A
CB7_A
CB4_A
CB1_A
CB7_B
ALERT_n
CA0_A
CA0_B
CA1_A
CA1_B
CA2_A
CA2_B
CA3_A
CA3_B
CA4_A
CA4_B
CA5_A
CA5_B
CA6_A
CA6_B
CB6_A
CB5_A
CB3_A
CB2_A
CB0_A
CB6_B
CB5_B
CB4_B
CB3_B
CB2_B
CB1_B
CB0_B
CK_c
CK_t
CS0_A_n
CS0_B_n
CS1_A_n
CS1_B_n
DQ30_A
DQ29_A
DQ28_A
DQ27_A
DQ26_A
DQ25_A
DQ24_A
DQ23_A
DQ22_A
DQ21_A
DQ20_A
DQ19_A
DQ18_A
DQ17_A
DQ16_A
DQ15_A
DQ14_A
DQ13_A
DQ12_A
DQ11_A
DQ10_A
DQ9_A
DQ8_A
DQ7_A
DQ6_A
DQ5_A
DQ4_A
DQ3_A
DQ2_A
DQ1_A
DQ0_A
DQ31_B
DQ30_B
DQ29_B
DQ28_B
DQ27_B
DQ26_B
DQ25_B
DQ24_B
DQ23_B
DQ22_B
DQ21_B
DQ20_B
DQ19_B
DQ18_B
DQ17_B
DQ16_B
DQ15_B
DQ14_B
DQ13_B
DQ12_B
DQ11_B
DQ10_B
DQ9_B
DQ8_B
DQ7_B
DQ6_B
DQ5_B
DQ4_B
DQ3_B
DQ2_B
DQ1_B
DQ0_B
HAS
HSCL
HSDA
LBD||RSP_A_n
LBS||RSP_B_n
PAR_A
PAR_B
RESET_n
RFU6
RFU5
RFU4
RFU3
RFU2
RFU1
RFU0
VIN_MGMT
21
21
1
SHEETDATE
23
7 3 2 16 5 4
E
A
B
C
E
D
C
B
A
7 6 5 4
D
DEPARTMENT
SIZE
PROJECT DOCUMENT NUMBER REV
REVIEWER
DESIGNER
BI
IN
OUT
OUT
OUT
OUT
BI
OUT
IN
OUT
BIIN
IN
BI
IN
IN
IN
IN
IN
IN
IN
BI
IN
IN
BI
OUT
OUT
C



Thu Aug 24 14:08:52 2023<NAME_2>
<NAME_1>
MB FABCGTI V02
89 OF 365
P 3V 3
P 12V _ME M_CP U0
P 3V 3_A UX
P D_CHD_CP U0_DIMM_S A A89
86878890
91159
1598687889091
13
13
868788
9091
13
13
13
13
13
13
13
13
13
13
89
13
13
13
13
13
13
13
13
13
13
1K
10%
25V
0.1UF
X 7R
0402
0402LF
1K
E MP TY
1/16W
1%
10UF
25V
C0805
X 6S
10%
X 6S
10UF
25V
C0805
10%
0402LFCHIP
10 I3C_SPD_DDRD_CPU0_SDA
I3C_S P D_DDRA F_CP U0_S DA I3C_SPD_DDRD_CPU0_SCL
I3C_S P D_DDRA F_CP U0_S CL
M_D_CP U0_A LE RT_N
P W RG D_CHD_CP U0_DIMM
M_D_CP U0_RE S E T_N
P W RG D_CHA F_CP U0
M_D_CP U0_S A _RS P <0>
M_D_CP U0_S A _P A R
M_D_CP U0_S B _P A R
M_D_CP U0_S B _RS P <0>
M_D_CP U0_S B _CS _N<1>
M_D_CP U0_S A _CS _N<1>
M_D_CP U0_S B _CS _N<0>
M_D_CP U0_S A _CS _N<0>
M_D_CP U0_CLK _DP <0>
M_D_CP U0_CLK _DN<0>
P D_CHD_CP U0_DIMM_S A A
M_D_CP U0_S B _CA <6:0>
M_D_CP U0_S A _CB <7:0>
M_D_CP U0_S B _CB <7:0>
M_D_CP U0_S B _DQ <31:0>
M_D_CP U0_S A _CA <6:0>
M_D_CP U0_S A _DQ S _DP <9:0>
M_D_CP U0_S B _DQ S _DN<9:0>
M_D_CP U0_S B _DQ S _DP <9:0>
M_D_CP U0_S A _DQ S _DN<9:0>
M_D_CP U0_S A _DQ <31:0>
DDR5 - CPU0 CHD
IO
SMLF
S CO NN288_DDR506112002K Q
SMLF
S CO NN288_DDR506112002K Q
IO
S CO NN288_DDR506112002K Q
IO
SMLF
0402LF
35.7K
1%
CHIP
1/16W
49.9
J19
J19
J19
21R1676
R1
2
1C150
2
1C149
2 1
R294 2
1
R92
2
1C100
2
1
R763
0
0
1
3
2
4
5
1
2
3
4
5
6
6
8
7
0
9
7
8
9
0
1
2
3
4
5
1
2
3
4
5
6
7
9
8
6
7
8
9
31
30
29
28
27
26
25
24
23
21
22
20
19
16
18
17
15
14
13
12
11
10
9
8
6
7
5
4
3
6
5
4
3
2
1
0
6
5
4
3
2
1
0
7
2
1
31
0
30
29
28
27
26
25
24
23
22
21
19
20
16
17
18
13
14
15
11
12
10
9
8
6
7
5
4
3
2
1
0
6
5
4
2
3
1
0
7
6
5
4
2
3
1
0
DQS7_A _c||TDQS7_A _c
DQS6_A _t||TDQS6_A _t
DQS8_B_t||TDQS8_B_t
DQS8_B_c||TDQS8_B_c
DQS7_B_t||TDQS7_B_t
DQS0_A _c
DQS0_A _t
DQS0_B_c
DQS0_B_t
DQS1_A _c
DQS1_A _t
DQS1_B_c
DQS1_B_t
DQS2_A _c
DQS2_A _t
DQS2_B_c
DQS2_B_t
DQS3_A _c
DQS3_A _t
DQS3_B_c
DQS3_B_t
DQS4_A _c
DQS4_A _t
DQS4_B_c
DQS4_B_t
DQS5_A _c||TDQS5_A _c||DQS5_A _t||TDQS5_A _t
DQS5_A _t||TDQS5_A _t
DQS5_B_c||TDQS5_B_c
DQS5_B_t||TDQS5_B_t
DQS6_A _c||TDQS6_A _c||DQS6_A _t||TDQS6_A _t
DQS6_B_c||TDQS6_B_c
DQS6_B_t||TDQS6_B_t
DQS7_A _t||TDQS7_A _t
DQS7_B_c||TDQS7_B_c
DQS8_A _c||TDQS8_A _c
DQS8_A _t||TDQS8_A _t
DQS9_A _c||TDQS9_A _c
DQS9_A _t||TDQS9_A _t
DQS9_B_c||TDQS9_B_c
DQS9_B_t||TDQS9_B_t||DBI4_B_n 93
94
201
200
283
282
190
189
272
271
179
178
261
260
168
167
250
249
157
156
239
238
55
56
137
138
44
45
126
127
33
34
115
116
22
23
104
105
11
12
288
286
284
281
279
277
275
273
270
268
266
264
262
259
257
255
253
251
248
246
244
242
240
237
235
233
230
228
226
224
222
219
216
214
212
210
208
206
204
202
199
197
195
193
191
188
186
184
182
180
177
175
173
171
169
166
164
162
160
158
155
153
151
143
141
139
136
134
132
130
128
125
123
121
119
117
114
112
110
108
106
103
101
99
97
95
92
90
88
85
83
81
79
77
75
73
71
69
67
65
63
61
59
57
54
52
50
48
46
43
41
39
37
35
32
30
28
26
24
21
19
17
15
13
10
8
6
146
145
1
G3
G2
G1
3
232
231
220
150
149
144
2
207
147
227
74
87
86
5
4
148
287
194
285
192
142
49
140
47
280
187
278
185
135
42
133
40
276
183
274
181
131
38
129
36
269
176
267
174
124
31
122
29
265
172
263
170
120
27
118
25
258
165
256
163
113
20
111
18
254
161
252
159
109
16
107
14
247
154
245
152
102
9
100
7
229
209
84
64
217
218
236
205
234
203
91
60
89
58
243
198
241
196
98
53
96
51
82
72
225
215
80
70
223
213
78
68
221
211
76
66
62
2/3
3/3
G3
G2
G1
VSS62
VSS61
VSS60
VSS58
VSS104
VSS102
VSS100
VIN_BULK2
VIN_BULK1
VIN_BULK0
VSS126
VSS125
VSS124
VSS123
VSS122
VSS121
VSS120
VSS119
VSS118
VSS117
VSS116
VSS115
VSS114
VSS113
VSS112
VSS111
VSS110
VSS109
VSS108
VSS107
VSS106
VSS105
VSS103
VSS101
VSS99
VSS98
VSS97
VSS96
VSS95
VSS94
VSS93
VSS92
VSS91
VSS90
VSS89
VSS88
VSS87
VSS86
VSS85
VSS84
VSS83
VSS82
VSS81
VSS80
VSS79
VSS78
VSS77
VSS76
VSS75
VSS74
VSS73
VSS72
VSS71
VSS70
VSS69
VSS68
VSS67
VSS66
VSS65
VSS64
VSS63
VSS59
VSS57
VSS56
VSS55
VSS54
VSS53
VSS52
VSS51
VSS50
VSS49
VSS48
VSS47
VSS46
VSS45
VSS44
VSS43
VSS42
VSS41
VSS40
VSS39
VSS38
VSS37
VSS36
VSS35
VSS34
VSS33
VSS32
VSS31
VSS30
VSS29
VSS28
VSS27
VSS26
VSS25
VSS24
VSS23
VSS22
VSS21
VSS20
VSS19
VSS18
VSS17
VSS16
VSS15
VSS14
VSS13
VSS12
VSS11
VSS10
VSS9
VSS8
VSS7
VSS6
VSS5
VSS4
VSS3
VSS2
VSS1
VSS0
1/3
PWR_GOOD||FAIL_n
DQ31_A
CB7_A
CB4_A
CB1_A
CB7_B
ALERT_n
CA0_A
CA0_B
CA1_A
CA1_B
CA2_A
CA2_B
CA3_A
CA3_B
CA4_A
CA4_B
CA5_A
CA5_B
CA6_A
CA6_B
CB6_A
CB5_A
CB3_A
CB2_A
CB0_A
CB6_B
CB5_B
CB4_B
CB3_B
CB2_B
CB1_B
CB0_B
CK_c
CK_t
CS0_A_n
CS0_B_n
CS1_A_n
CS1_B_n
DQ30_A
DQ29_A
DQ28_A
DQ27_A
DQ26_A
DQ25_A
DQ24_A
DQ23_A
DQ22_A
DQ21_A
DQ20_A
DQ19_A
DQ18_A
DQ17_A
DQ16_A
DQ15_A
DQ14_A
DQ13_A
DQ12_A
DQ11_A
DQ10_A
DQ9_A
DQ8_A
DQ7_A
DQ6_A
DQ5_A
DQ4_A
DQ3_A
DQ2_A
DQ1_A
DQ0_A
DQ31_B
DQ30_B
DQ29_B
DQ28_B
DQ27_B
DQ26_B
DQ25_B
DQ24_B
DQ23_B
DQ22_B
DQ21_B
DQ20_B
DQ19_B
DQ18_B
DQ17_B
DQ16_B
DQ15_B
DQ14_B
DQ13_B
DQ12_B
DQ11_B
DQ10_B
DQ9_B
DQ8_B
DQ7_B
DQ6_B
DQ5_B
DQ4_B
DQ3_B
DQ2_B
DQ1_B
DQ0_B
HAS
HSCL
HSDA
LBD||RSP_A_n
LBS||RSP_B_n
PAR_A
PAR_B
RESET_n
RFU6
RFU5
RFU4
RFU3
RFU2
RFU1
RFU0
VIN_MGMT
21
1
SHEETDATE
23
7 3 2 16 5 4
E
A
B
C
E
D
C
B
A
7 6 5 4
D
DEPARTMENT
SIZE
PROJECT DOCUMENT NUMBER REV
REVIEWER
DESIGNER
BI
IN
OUT
OUT
OUT
OUT
BI
OUT
IN
OUT
BI
BI
IN
IN
IN
IN
IN
IN
IN
IN
IN
IN
BI
IN
BI
OUT
OUT
C



Thu Aug 24 14:08:52 2023<NAME_2>
<NAME_1>
MB FABCGTI V02
90 OF 365
P 3V 3
P 12V _ME M_CP U0
P 3V 3_A UX
90
1598687888991
86878889
91159
14
14
14
14
14
14
86
87
88
89
91
90
14
14
14
14
14
14
14
14
14
14
14
14
14
14
14
14
1K
0.1UF
0402
25V
10%
X 7R
0402LF
1K
E MP TY
1%
1/16W
10%
C0805
X 6S
10UF
25V
X 6S
10%
25V
C0805
10UF
10
CHIP 0402LF
P D_CHE _CP U0_DIMM_S A A
I3C_SPD_DDRE_CPU0_SCL
I3C_SPD_DDRE_CPU0_SDA
I3C_S P D_DDRA F_CP U0_S CL
P W RG D_CHE _CP U0_DIMM
I3C_SPD_DDRAF_CPU0_SDA
M_E _CP U0_RE S E T_N
M_E _CP U0_A LE RT_N
M_E _CP U0_S A _DQ S _DN<9:0>
M_E _CP U0_S A _DQ S _DP <9:0>
M_E _CP U0_S B _DQ S _DN<9:0>
M_E _CP U0_S B _DQ S _DP <9:0>
49.9
P W RG D_CHA F_CP U0
P D_CHE _CP U0_DIMM_S A A
M_E _CP U0_S A _CS _N<0>
M_E _CP U0_CLK _DP <0>
M_E _CP U0_S B _P A R
M_E _CP U0_S A _P A R
M_E _CP U0_S B _RS P <0>
M_E _CP U0_S A _RS P <0>
M_E _CP U0_S B _CS _N<1>
M_E _CP U0_S A _CS _N<1>
M_E _CP U0_S B _CS _N<0>
M_E _CP U0_CLK _DN<0>
M_E _CP U0_S B _CB <7:0>
M_E _CP U0_S B _DQ <31:0>
M_E _CP U0_S A _CA <6:0>
M_E _CP U0_S B _CA <6:0>
M_E _CP U0_S A _CB <7:0>
M_E _CP U0_S A _DQ <31:0>
DDR5 - CPU0 CHE
IO
S CO NN288_DDR506112002K Q
SMLF
IO
S CO NN288_DDR506112002K Q
SMLF
IO
S CO NN288_DDR506112002K Q
SMLF
1/16W
CHIP
1%
54.9K
0402LF
J21
J21J21
R1678
R1572
2
1C153
2
1C151
2
1
R93
2 1
R295
2
1C104
2
1
R5
18
8
14
0
0
1
2
2
1
3
4
3
5
5
4
6
7
8
7
6
8
9
0
0
9
1
2
1
3
2
3
5
4
5
4
6
7
7
6
9
8
9
29
30
28
27
31
26
25
24
22
21
23
6
4
5
3
2
1
0
5
4
6
19
20
16
18
17
11
12
13
15
10
9
8
6
7
5
4
3
1
2
29
31
30
0
24
28
25
27
26
19
23
20
22
21
16
17
14
15
13
12
11
10
9
8
6
7
5
4
3
2
0
1
2
0
1
3
7
6
5
4
3
0
1
2
6
7
5
4
3
0
2
1
DQS7_A _c||TDQS7_A _c
DQS6_A _t||TDQS6_A _t
DQS8_B_t||TDQS8_B_t
DQS8_B_c||TDQS8_B_c
DQS7_B_t||TDQS7_B_t
DQS0_A _c
DQS0_A _t
DQS0_B_c
DQS0_B_t
DQS1_A _c
DQS1_A _t
DQS1_B_c
DQS1_B_t
DQS2_A _c
DQS2_A _t
DQS2_B_c
DQS2_B_t
DQS3_A _c
DQS3_A _t
DQS3_B_c
DQS3_B_t
DQS4_A _c
DQS4_A _t
DQS4_B_c
DQS4_B_t
DQS5_A _c||TDQS5_A _c||DQS5_A _t||TDQS5_A _t
DQS5_A _t||TDQS5_A _t
DQS5_B_c||TDQS5_B_c
DQS5_B_t||TDQS5_B_t
DQS6_A _c||TDQS6_A _c||DQS6_A _t||TDQS6_A _t
DQS6_B_c||TDQS6_B_c
DQS6_B_t||TDQS6_B_t
DQS7_A _t||TDQS7_A _t
DQS7_B_c||TDQS7_B_c
DQS8_A _c||TDQS8_A _c
DQS8_A _t||TDQS8_A _t
DQS9_A _c||TDQS9_A _c
DQS9_A _t||TDQS9_A _t
DQS9_B_c||TDQS9_B_c
DQS9_B_t||TDQS9_B_t||DBI4_B_n 93
94
201
200
283
282
190
189
272
271
179
178
261
260
168
167
250
249
157
156
239
238
55
56
137
138
44
45
126
127
33
34
115
116
22
23
104
105
11
12
288
286
284
281
279
277
275
273
270
268
266
264
262
259
257
255
253
251
248
246
244
242
240
237
235
233
230
228
226
224
222
219
216
214
212
210
208
206
204
202
199
197
195
193
191
188
186
184
182
180
177
175
173
171
169
166
164
162
160
158
155
153
151
143
141
139
136
134
132
130
128
125
123
121
119
117
114
112
110
108
106
103
101
99
97
95
92
90
88
85
83
81
79
77
75
73
71
69
67
65
63
61
59
57
54
52
50
48
46
43
41
39
37
35
32
30
28
26
24
21
19
17
15
13
10
8
6
146
145
1
G3
G2
G1
3
232
231
220
150
149
144
2
207
147
227
74
87
86
5
4
148
287
194
285
192
142
49
140
47
280
187
278
185
135
42
133
40
276
183
274
181
131
38
129
36
269
176
267
174
124
31
122
29
265
172
263
170
120
27
118
25
258
165
256
163
113
20
111
18
254
161
252
159
109
16
107
14
247
154
245
152
102
9
100
7
229
209
84
64
217
218
236
205
234
203
91
60
89
58
243
198
241
196
98
53
96
51
82
72
225
215
80
70
223
213
78
68
221
211
76
66
62
2/3
3/3
G3
G2
G1
VSS62
VSS61
VSS60
VSS58
VSS104
VSS102
VSS100
VIN_BULK2
VIN_BULK1
VIN_BULK0
VSS126
VSS125
VSS124
VSS123
VSS122
VSS121
VSS120
VSS119
VSS118
VSS117
VSS116
VSS115
VSS114
VSS113
VSS112
VSS111
VSS110
VSS109
VSS108
VSS107
VSS106
VSS105
VSS103
VSS101
VSS99
VSS98
VSS97
VSS96
VSS95
VSS94
VSS93
VSS92
VSS91
VSS90
VSS89
VSS88
VSS87
VSS86
VSS85
VSS84
VSS83
VSS82
VSS81
VSS80
VSS79
VSS78
VSS77
VSS76
VSS75
VSS74
VSS73
VSS72
VSS71
VSS70
VSS69
VSS68
VSS67
VSS66
VSS65
VSS64
VSS63
VSS59
VSS57
VSS56
VSS55
VSS54
VSS53
VSS52
VSS51
VSS50
VSS49
VSS48
VSS47
VSS46
VSS45
VSS44
VSS43
VSS42
VSS41
VSS40
VSS39
VSS38
VSS37
VSS36
VSS35
VSS34
VSS33
VSS32
VSS31
VSS30
VSS29
VSS28
VSS27
VSS26
VSS25
VSS24
VSS23
VSS22
VSS21
VSS20
VSS19
VSS18
VSS17
VSS16
VSS15
VSS14
VSS13
VSS12
VSS11
VSS10
VSS9
VSS8
VSS7
VSS6
VSS5
VSS4
VSS3
VSS2
VSS1
VSS0
1/3
PWR_GOOD||FAIL_n
DQ31_A
CB7_A
CB4_A
CB1_A
CB7_B
ALERT_n
CA0_A
CA0_B
CA1_A
CA1_B
CA2_A
CA2_B
CA3_A
CA3_B
CA4_A
CA4_B
CA5_A
CA5_B
CA6_A
CA6_B
CB6_A
CB5_A
CB3_A
CB2_A
CB0_A
CB6_B
CB5_B
CB4_B
CB3_B
CB2_B
CB1_B
CB0_B
CK_c
CK_t
CS0_A_n
CS0_B_n
CS1_A_n
CS1_B_n
DQ30_A
DQ29_A
DQ28_A
DQ27_A
DQ26_A
DQ25_A
DQ24_A
DQ23_A
DQ22_A
DQ21_A
DQ20_A
DQ19_A
DQ18_A
DQ17_A
DQ16_A
DQ15_A
DQ14_A
DQ13_A
DQ12_A
DQ11_A
DQ10_A
DQ9_A
DQ8_A
DQ7_A
DQ6_A
DQ5_A
DQ4_A
DQ3_A
DQ2_A
DQ1_A
DQ0_A
DQ31_B
DQ30_B
DQ29_B
DQ28_B
DQ27_B
DQ26_B
DQ25_B
DQ24_B
DQ23_B
DQ22_B
DQ21_B
DQ20_B
DQ19_B
DQ18_B
DQ17_B
DQ16_B
DQ15_B
DQ14_B
DQ13_B
DQ12_B
DQ11_B
DQ10_B
DQ9_B
DQ8_B
DQ7_B
DQ6_B
DQ5_B
DQ4_B
DQ3_B
DQ2_B
DQ1_B
DQ0_B
HAS
HSCL
HSDA
LBD||RSP_A_n
LBS||RSP_B_n
PAR_A
PAR_B
RESET_n
RFU6
RFU5
RFU4
RFU3
RFU2
RFU1
RFU0
VIN_MGMT
21
21
1
SHEETDATE
23
7 3 2 16 5 4
E
A
B
C
E
D
C
B
A
7 6 5 4
D
DEPARTMENT
SIZE
PROJECT DOCUMENT NUMBER REV
REVIEWER
DESIGNER
BI
IN
OUT
OUT
OUT
OUT
BI
OUT
IN
OUT
BIIN
IN
BI
IN
IN
IN
IN
IN
IN
IN
BI
IN
IN
BI
OUT
OUT
C



Thu Aug 24 14:08:53 2023<NAME_2>
<NAME_1>
MB FABCGTI V02
91 OF 365
P 3V 3
P 12V _ME M_CP U0
P 3V 3_A UX
I3C_SPD_DDRF_CPU0_SCL
1598687888990
86878889
90159
91
15
15
15
8687
8889
90
15
15
15
15
15
15
15
15
15
15
91
15
15
15
15
15
15
15
15
15
1K
25V
10%
0402
X 7R
0.1UF
E MP TY
0402LF
1/16W
1%
1K
25V
10%
C0805
10UF
X 6S
25V
C0805
10UF
10%
X 6S
10
0402LFCHIP
I3C_S P D_DDRA F_CP U0_S CL
P W RG D_CHF_CP U0_DIMM
49.9
I3C_S P D_DDRA F_CP U0_S DA
I3C_SPD_DDRF_CPU0_SDA
P D_CHF_CP U0_DIMM_S A A
M_F_CP U0_A LE RT_N
M_F_CP U0_RE S E T_N
M_F_CP U0_S B _CB <7:0>
P W RG D_CHA F_CP U0
M_F_CP U0_S B _P A R
M_F_CP U0_S A _P A R
M_F_CP U0_S B _RS P <0>
M_F_CP U0_S A _RS P <0>
M_F_CP U0_S B _CS _N<1>
M_F_CP U0_S A _CS _N<1>
M_F_CP U0_S B _CS _N<0>
M_F_CP U0_S A _CS _N<0>
M_F_CP U0_CLK _DP <0>
M_F_CP U0_CLK _DN<0>
P D_CHF_CP U0_DIMM_S A A
M_F_CP U0_S A _CB <7:0>
M_F_CP U0_S A _CA <6:0>
M_F_CP U0_S A _DQ S _DN<9:0>
M_F_CP U0_S A _DQ S _DP <9:0>
M_F_CP U0_S B _DQ S _DN<9:0>
M_F_CP U0_S B _DQ S _DP <9:0>
M_F_CP U0_S A _DQ <31:0>
M_F_CP U0_S B _CA <6:0>
M_F_CP U0_S B _DQ <31:0>
DDR5 - CPU0 CHF
IO
S CO NN288_DDR506112002K Q
SMLF
S CO NN288_DDR506112002K Q
SMLF
IO
S CO NN288_DDR506112002K Q
SMLF
IO
1/16W
CHIP
1%
84.5K
0402LF
J23
J23
J23
R1679
R1573
2
1C155
2
1C154
2
1
R94
2 1
R296
2
1C108
2
1
R764
0
1
2
4
3
1
0
2
3
4
5
6
7
9
8
6
5
7
8
9
0
1
2
4
3
0
1
2
3
4
5
6
7
9
8
5
7
6
8
9
1
0
2
3
4
5
7
6
8
9
10
11
12
13
15
14
18
17
16
21
22
20
23
19
26
27
25
28
24
0
30
31
29
2
1
3
4
5
7
6
8
9
10
14
15
13
12
11
17
18
16
20
19
23
21
22
24
25
26
31
27
28
30
29
6
5
3
4
2
1
0
6
5
3
4
1
2
0
6
7
4
5
3
2
1
0
7
6
5
3
4
2
1
0
DQS7_A _c||TDQS7_A _c
DQS6_A _t||TDQS6_A _t
DQS8_B_t||TDQS8_B_t
DQS8_B_c||TDQS8_B_c
DQS7_B_t||TDQS7_B_t
DQS0_A _c
DQS0_A _t
DQS0_B_c
DQS0_B_t
DQS1_A _c
DQS1_A _t
DQS1_B_c
DQS1_B_t
DQS2_A _c
DQS2_A _t
DQS2_B_c
DQS2_B_t
DQS3_A _c
DQS3_A _t
DQS3_B_c
DQS3_B_t
DQS4_A _c
DQS4_A _t
DQS4_B_c
DQS4_B_t
DQS5_A _c||TDQS5_A _c||DQS5_A _t||TDQS5_A _t
DQS5_A _t||TDQS5_A _t
DQS5_B_c||TDQS5_B_c
DQS5_B_t||TDQS5_B_t
DQS6_A _c||TDQS6_A _c||DQS6_A _t||TDQS6_A _t
DQS6_B_c||TDQS6_B_c
DQS6_B_t||TDQS6_B_t
DQS7_A _t||TDQS7_A _t
DQS7_B_c||TDQS7_B_c
DQS8_A _c||TDQS8_A _c
DQS8_A _t||TDQS8_A _t
DQS9_A _c||TDQS9_A _c
DQS9_A _t||TDQS9_A _t
DQS9_B_c||TDQS9_B_c
DQS9_B_t||TDQS9_B_t||DBI4_B_n 93
94
201
200
283
282
190
189
272
271
179
178
261
260
168
167
250
249
157
156
239
238
55
56
137
138
44
45
126
127
33
34
115
116
22
23
104
105
11
12
288
286
284
281
279
277
275
273
270
268
266
264
262
259
257
255
253
251
248
246
244
242
240
237
235
233
230
228
226
224
222
219
216
214
212
210
208
206
204
202
199
197
195
193
191
188
186
184
182
180
177
175
173
171
169
166
164
162
160
158
155
153
151
143
141
139
136
134
132
130
128
125
123
121
119
117
114
112
110
108
106
103
101
99
97
95
92
90
88
85
83
81
79
77
75
73
71
69
67
65
63
61
59
57
54
52
50
48
46
43
41
39
37
35
32
30
28
26
24
21
19
17
15
13
10
8
6
146
145
1
G3
G2
G1
3
232
231
220
150
149
144
2
207
147
227
74
87
86
5
4
148
287
194
285
192
142
49
140
47
280
187
278
185
135
42
133
40
276
183
274
181
131
38
129
36
269
176
267
174
124
31
122
29
265
172
263
170
120
27
118
25
258
165
256
163
113
20
111
18
254
161
252
159
109
16
107
14
247
154
245
152
102
9
100
7
229
209
84
64
217
218
236
205
234
203
91
60
89
58
243
198
241
196
98
53
96
51
82
72
225
215
80
70
223
213
78
68
221
211
76
66
62
2/3
3/3
G3
G2
G1
VSS62
VSS61
VSS60
VSS58
VSS104
VSS102
VSS100
VIN_BULK2
VIN_BULK1
VIN_BULK0
VSS126
VSS125
VSS124
VSS123
VSS122
VSS121
VSS120
VSS119
VSS118
VSS117
VSS116
VSS115
VSS114
VSS113
VSS112
VSS111
VSS110
VSS109
VSS108
VSS107
VSS106
VSS105
VSS103
VSS101
VSS99
VSS98
VSS97
VSS96
VSS95
VSS94
VSS93
VSS92
VSS91
VSS90
VSS89
VSS88
VSS87
VSS86
VSS85
VSS84
VSS83
VSS82
VSS81
VSS80
VSS79
VSS78
VSS77
VSS76
VSS75
VSS74
VSS73
VSS72
VSS71
VSS70
VSS69
VSS68
VSS67
VSS66
VSS65
VSS64
VSS63
VSS59
VSS57
VSS56
VSS55
VSS54
VSS53
VSS52
VSS51
VSS50
VSS49
VSS48
VSS47
VSS46
VSS45
VSS44
VSS43
VSS42
VSS41
VSS40
VSS39
VSS38
VSS37
VSS36
VSS35
VSS34
VSS33
VSS32
VSS31
VSS30
VSS29
VSS28
VSS27
VSS26
VSS25
VSS24
VSS23
VSS22
VSS21
VSS20
VSS19
VSS18
VSS17
VSS16
VSS15
VSS14
VSS13
VSS12
VSS11
VSS10
VSS9
VSS8
VSS7
VSS6
VSS5
VSS4
VSS3
VSS2
VSS1
VSS0
1/3
PWR_GOOD||FAIL_n
DQ31_A
CB7_A
CB4_A
CB1_A
CB7_B
ALERT_n
CA0_A
CA0_B
CA1_A
CA1_B
CA2_A
CA2_B
CA3_A
CA3_B
CA4_A
CA4_B
CA5_A
CA5_B
CA6_A
CA6_B
CB6_A
CB5_A
CB3_A
CB2_A
CB0_A
CB6_B
CB5_B
CB4_B
CB3_B
CB2_B
CB1_B
CB0_B
CK_c
CK_t
CS0_A_n
CS0_B_n
CS1_A_n
CS1_B_n
DQ30_A
DQ29_A
DQ28_A
DQ27_A
DQ26_A
DQ25_A
DQ24_A
DQ23_A
DQ22_A
DQ21_A
DQ20_A
DQ19_A
DQ18_A
DQ17_A
DQ16_A
DQ15_A
DQ14_A
DQ13_A
DQ12_A
DQ11_A
DQ10_A
DQ9_A
DQ8_A
DQ7_A
DQ6_A
DQ5_A
DQ4_A
DQ3_A
DQ2_A
DQ1_A
DQ0_A
DQ31_B
DQ30_B
DQ29_B
DQ28_B
DQ27_B
DQ26_B
DQ25_B
DQ24_B
DQ23_B
DQ22_B
DQ21_B
DQ20_B
DQ19_B
DQ18_B
DQ17_B
DQ16_B
DQ15_B
DQ14_B
DQ13_B
DQ12_B
DQ11_B
DQ10_B
DQ9_B
DQ8_B
DQ7_B
DQ6_B
DQ5_B
DQ4_B
DQ3_B
DQ2_B
DQ1_B
DQ0_B
HAS
HSCL
HSDA
LBD||RSP_A_n
LBS||RSP_B_n
PAR_A
PAR_B
RESET_n
RFU6
RFU5
RFU4
RFU3
RFU2
RFU1
RFU0
VIN_MGMT
21
21
1
SHEETDATE
23
7 3 2 16 5 4
E
A
B
C
E
D
C
B
A
7 6 5 4
D
DEPARTMENT
SIZE
PROJECT DOCUMENT NUMBER REV
REVIEWER
DESIGNER
BI
IN
OUT
OUT
OUT
OUT
BI
OUT
IN
OUT
BI
BI
IN
IN
IN
IN
IN
IN
IN
IN
IN
IN
BI
BI
IN
OUT
OUT
C



Thu Aug 24 14:08:53 2023<NAME_2>
<NAME_1>
MB FABCGTI V02
92 OF 365
P 3V 3
P 3V 3_A UX
P 3V 3
P 12V _ME M_CP U0
P 3V 3_A UX
P 3V 3_A UX
P 3V 3_A UX
9394959697159
92
1599394959697
16
16
16
16 16
16
16
16
16
16
929394959697
16
16
16
16
16
16
16
16
16
92
16
82
92 93 94 95 96 97
929394
959697
16
16
I3C_S P D_DDRG L_CP U0_S DA
P D_CHG _CP U0_DIMM0_S A A
1K
X 6S
10%
10UF
25V
C0805
X 6S
10%
25V
C0805
10UF
E MP TY
1/16W
1%
1K
0402LF 0402LF
1K
E MP TY
1/16W
1%
0402
10%
X 7R
0.1UF
25V
1/16W
CHIP
10K
0402LF
1%
10
0402LFCHIP
I3C_S P D_DDRG L_CP U0_S CL
I3C_SPD_DDRG_CPU0_SCL
49.9
P W RG D_CHG _CP U0_DIMM0
M_G _CP U0_S B _CB <7:0>
I3C_SPD_DDRG_CPU0_SDA
IO
SMLF
S CO NN288_DDR506112002K Q
S CO NN288_DDR506112002K Q
SMLF
IO
IO
S CO NN288_DDR506112002K Q
SMLF
CHIP
0402LF
1%
1/16W
10K
1/16W 0402LF
5%
CHIP
0
1/16W 0402LFEMPTY
1%10K
0 5%
CHIP 0402LF1/16W
SMLF
B0530WS7F
EMPTY
DDR5 - CPU0 CHG
M_G _CP U0_S A _CB <7:0>
M_G _CP U0_S B _CA <6:0>
M_G _CP U0_S A _CA <6:0> M_G _CP U0_S A _DQ <31:0>
M_G _CP U0_S B _DQ <31:0>
M_G _CP U0_S A _DQ S _DN<9:0>
M_G _CP U0_S A _DQ S _DP <9:0>
M_G _CP U0_S B _DQ S _DP <9:0>
M_G _CP U0_S B _DQ S _DN<9:0>
PWRGD_CHGL_CPU0
M_G _CP U0_S A _RS P <0>
M_G _CP U0_S A _CS _N<1>
M_G _CP U0_S B _P A R
M_G _CP U0_S A _P A R
M_G _CP U0_S B _CS _N<1>
M_G _CP U0_S B _CS _N<0>
M_G _CP U0_S A _CS _N<0>
M_G _CP U0_CLK _DP <0>
M_G _CP U0_CLK _DN<0>
P D_CHG _CP U0_DIMM0_S A A
M_G _CP U0_S B _RS P <0>
PWRGD_CHGL_CPU0_R2PWRGD_CHGL_CPU0_R1
PWRGD_CHGL_CPU0
P W RG D_CHG L_CP U0
M_G _CP U0_A LE RT_N
M_G _CP U0_RE S E T_N
J16
J16
J16
R1680
R1574
2
1C158
2
1C157
2
1
R95
2
1
R96
2 1
R297
2
1C112
2
1
R35
24
5
8
9
7
12
11
10
13
14
17
16
15
18
19
22
21
20
24
23
26
27
25
30
28
29
31
9
8
9
8
7
7
5
6
4
3
5
6
4
2
3
2
1
0
9
8
0
1
8
9
7
6
5
4
3
6
7
5
4
3
0
2
1
0
0
1
2
1
2
3
4
5
6
7
0
1
2
3
4
5
6
7
1
0
4
3
2
5
6
9
8
7
10
11
14
13
12
16
15
17
19
18
20
21
22
23
25
26
27
29
28
30
31
1
0
3
4
2
0
1
2
3
4
5
6
1
0
2
3
4
5
6
6
DQS7_A _c||TDQS7_A _c
DQS6_A _t||TDQS6_A _t
DQS8_B_t||TDQS8_B_t
DQS8_B_c||TDQS8_B_c
DQS7_B_t||TDQS7_B_t
DQS0_A _c
DQS0_A _t
DQS0_B_c
DQS0_B_t
DQS1_A _c
DQS1_A _t
DQS1_B_c
DQS1_B_t
DQS2_A _c
DQS2_A _t
DQS2_B_c
DQS2_B_t
DQS3_A _c
DQS3_A _t
DQS3_B_c
DQS3_B_t
DQS4_A _c
DQS4_A _t
DQS4_B_c
DQS4_B_t
DQS5_A _c||TDQS5_A _c||DQS5_A _t||TDQS5_A _t
DQS5_A _t||TDQS5_A _t
DQS5_B_c||TDQS5_B_c
DQS5_B_t||TDQS5_B_t
DQS6_A _c||TDQS6_A _c||DQS6_A _t||TDQS6_A _t
DQS6_B_c||TDQS6_B_c
DQS6_B_t||TDQS6_B_t
DQS7_A _t||TDQS7_A _t
DQS7_B_c||TDQS7_B_c
DQS8_A _c||TDQS8_A _c
DQS8_A _t||TDQS8_A _t
DQS9_A _c||TDQS9_A _c
DQS9_A _t||TDQS9_A _t
DQS9_B_c||TDQS9_B_c
DQS9_B_t||TDQS9_B_t||DBI4_B_n
21
93
94
201
200
283
282
190
189
272
271
179
178
261
260
168
167
250
249
157
156
239
238
55
56
137
138
44
45
126
127
33
34
115
116
22
23
104
105
11
12
288
286
284
281
279
277
275
273
270
268
266
264
262
259
257
255
253
251
248
246
244
242
240
237
235
233
230
228
226
224
222
219
216
214
212
210
208
206
204
202
199
197
195
193
191
188
186
184
182
180
177
175
173
171
169
166
164
162
160
158
155
153
151
143
141
139
136
134
132
130
128
125
123
121
119
117
114
112
110
108
106
103
101
99
97
95
92
90
88
85
83
81
79
77
75
73
71
69
67
65
63
61
59
57
54
52
50
48
46
43
41
39
37
35
32
30
28
26
24
21
19
17
15
13
10
8
6
146
145
1
G3
G2
G1
3
232
231
220
150
149
144
2
207
147
227
74
87
86
5
4
148
287
194
285
192
142
49
140
47
280
187
278
185
135
42
133
40
276
183
274
181
131
38
129
36
269
176
267
174
124
31
122
29
265
172
263
170
120
27
118
25
258
165
256
163
113
20
111
18
254
161
252
159
109
16
107
14
247
154
245
152
102
9
100
7
229
209
84
64
217
218
236
205
234
203
91
60
89
58
243
198
241
196
98
53
96
51
82
72
225
215
80
70
223
213
78
68
221
211
76
66
62
D8004
CA
2/3
1/3
PWR_GOOD||FAIL_n
DQ31_A
CB7_A
CB4_A
CB1_A
CB7_B
ALERT_n
CA0_A
CA0_B
CA1_A
CA1_B
CA2_A
CA2_B
CA3_A
CA3_B
CA4_A
CA4_B
CA5_A
CA5_B
CA6_A
CA6_B
CB6_A
CB5_A
CB3_A
CB2_A
CB0_A
CB6_B
CB5_B
CB4_B
CB3_B
CB2_B
CB1_B
CB0_B
CK_c
CK_t
CS0_A_n
CS0_B_n
CS1_A_n
CS1_B_n
DQ30_A
DQ29_A
DQ28_A
DQ27_A
DQ26_A
DQ25_A
DQ24_A
DQ23_A
DQ22_A
DQ21_A
DQ20_A
DQ19_A
DQ18_A
DQ17_A
DQ16_A
DQ15_A
DQ14_A
DQ13_A
DQ12_A
DQ11_A
DQ10_A
DQ9_A
DQ8_A
DQ7_A
DQ6_A
DQ5_A
DQ4_A
DQ3_A
DQ2_A
DQ1_A
DQ0_A
DQ31_B
DQ30_B
DQ29_B
DQ28_B
DQ27_B
DQ26_B
DQ25_B
DQ24_B
DQ23_B
DQ22_B
DQ21_B
DQ20_B
DQ19_B
DQ18_B
DQ17_B
DQ16_B
DQ15_B
DQ14_B
DQ13_B
DQ12_B
DQ11_B
DQ10_B
DQ9_B
DQ8_B
DQ7_B
DQ6_B
DQ5_B
DQ4_B
DQ3_B
DQ2_B
DQ1_B
DQ0_B
HAS
HSCL
HSDA
LBD||RSP_A_n
LBS||RSP_B_n
PAR_A
PAR_B
RESET_n
RFU6
RFU5
RFU4
RFU3
RFU2
RFU1
RFU0
VIN_MGMT
3/3
G3
G2
G1
VSS62
VSS61
VSS60
VSS58
VSS104
VSS102
VSS100
VIN_BULK2
VIN_BULK1
VIN_BULK0
VSS126
VSS125
VSS124
VSS123
VSS122
VSS121
VSS120
VSS119
VSS118
VSS117
VSS116
VSS115
VSS114
VSS113
VSS112
VSS111
VSS110
VSS109
VSS108
VSS107
VSS106
VSS105
VSS103
VSS101
VSS99
VSS98
VSS97
VSS96
VSS95
VSS94
VSS93
VSS92
VSS91
VSS90
VSS89
VSS88
VSS87
VSS86
VSS85
VSS84
VSS83
VSS82
VSS81
VSS80
VSS79
VSS78
VSS77
VSS76
VSS75
VSS74
VSS73
VSS72
VSS71
VSS70
VSS69
VSS68
VSS67
VSS66
VSS65
VSS64
VSS63
VSS59
VSS57
VSS56
VSS55
VSS54
VSS53
VSS52
VSS51
VSS50
VSS49
VSS48
VSS47
VSS46
VSS45
VSS44
VSS43
VSS42
VSS41
VSS40
VSS39
VSS38
VSS37
VSS36
VSS35
VSS34
VSS33
VSS32
VSS31
VSS30
VSS29
VSS28
VSS27
VSS26
VSS25
VSS24
VSS23
VSS22
VSS21
VSS20
VSS19
VSS18
VSS17
VSS16
VSS15
VSS14
VSS13
VSS12
VSS11
VSS10
VSS9
VSS8
VSS7
VSS6
VSS5
VSS4
VSS3
VSS2
VSS1
VSS0
21
21
21
21
2
1
21
1
SHEETDATE
23
7 3 2 16 5 4
E
A
B
C
E
D
C
B
A
7 6 5 4
D
DEPARTMENT
SIZE
PROJECT DOCUMENT NUMBER REV
REVIEWER
DESIGNER
IN
BI
OUT
IN
BI
BIBI
OUT
IN
IN
IN
OUT
OUT
OUT
OUT
OUTIN
BI
IN
IN
IN
IN
IN
IN
OUT
BI
IN
BI
BI
OUT
R8084
R8085
R8083
R8038
C



Thu Aug 24 14:08:53 2023<NAME_2>
<NAME_1>
MB FABCGTI V02
93 OF 365
P 3V 3
P 12V _ME M_CP U0
P 3V 3_A UX
929495
9697159
1599294959697
93
17
17
9294
9596
97
17
17
17
17
17
17
17
17
17
17
17
17
17
17
17
17
17
93
17
17
17
1K
10%
C0805
X 6S
25V
10UF
C0805
25V
10UF
10%
X 6S
1%
0402LF
E MP TY
1/16W
1K
25V
0.1UF
10%
X 7R
0402
10
0402LFCHIP
I3C_S P D_DDRG L_CP U0_S DA
I3C_S P D_DDRG L_CP U0_S CL
I3C_SPD_DDRH_CPU0_SCL
I3C_SPD_DDRH_CPU0_SDA
P D_CHH_CP U0_DIMM_S A A
M_H_CP U0_A LE RT_N
M_H_CP U0_RE S E T_N
P W RG D_CHG L_CP U0
49.9
1/16W
CHIP
1%
15.4K
0402LF
SMLF
IO
S CO NN288_DDR506112002K Q
SMLF
IO
S CO NN288_DDR506112002K Q
IO
DDR5 - CPU0 CHH
M_H_CP U0_S A _DQ <31:0>
M_H_CP U0_S A _CB <7:0>
M_H_CP U0_S A _CA <6:0>
M_H_CP U0_S B _CA <6:0>
M_H_CP U0_S B _DQ <31:0>
M_H_CP U0_S A _DQ S _DN<9:0>
M_H_CP U0_S A _DQ S _DP <9:0>
M_H_CP U0_S B _DQ S _DP <9:0>
M_H_CP U0_S B _DQ S _DN<9:0>
M_H_CP U0_S B _P A R
M_H_CP U0_S A _P A R
M_H_CP U0_S B _CS _N<1>
M_H_CP U0_S A _CS _N<1>
M_H_CP U0_S B _CS _N<0>
M_H_CP U0_S A _CS _N<0>
M_H_CP U0_CLK _DP <0>
M_H_CP U0_CLK _DN<0>
P D_CHH_CP U0_DIMM_S A A
M_H_CP U0_S A _RS P <0>
M_H_CP U0_S B _RS P <0>
S CO NN288_DDR506112002K Q
SMLF
M_H_CP U0_S B _CB <7:0>
P W RG D_CHH_CP U0_DIMM
J69
J69
J69
R1681
R1575
2
1C161
2
1C159
2
1
R97
2 1
R298
2
1C116
2
1
R765
7
6
8
9
11
12
13
14
10
19
16
18
15
20
21
22
25
23
24
29
30
28
27
26
31
9
8
9
8
7
6
4
5
3
5
7
6
4
3
2
1
0
8
9
0
2
1
8
9
7
6
5
3
4
5
7
6
4
0
3
2
1
0
0
1
2
1
2
3
4
6
5
7
0
1
2
3
0
1
2
3
4
5
6
7
8
9
10
11
12
13
14
16
15
17
19
20
22
21
18
24
25
27
26
23
29
31
30
28
4
5
7
6
0
1
2
4
3
5
6
0
1
2
3
4
5
6
0
1
2
3
4
5
17
DQS7_A _c||TDQS7_A _c
DQS6_A _t||TDQS6_A _t
DQS8_B_t||TDQS8_B_t
DQS8_B_c||TDQS8_B_c
DQS7_B_t||TDQS7_B_t
DQS0_A _c
DQS0_A _t
DQS0_B_c
DQS0_B_t
DQS1_A _c
DQS1_A _t
DQS1_B_c
DQS1_B_t
DQS2_A _c
DQS2_A _t
DQS2_B_c
DQS2_B_t
DQS3_A _c
DQS3_A _t
DQS3_B_c
DQS3_B_t
DQS4_A _c
DQS4_A _t
DQS4_B_c
DQS4_B_t
DQS5_A _c||TDQS5_A _c||DQS5_A _t||TDQS5_A _t
DQS5_A _t||TDQS5_A _t
DQS5_B_c||TDQS5_B_c
DQS5_B_t||TDQS5_B_t
DQS6_A _c||TDQS6_A _c||DQS6_A _t||TDQS6_A _t
DQS6_B_c||TDQS6_B_c
DQS6_B_t||TDQS6_B_t
DQS7_A _t||TDQS7_A _t
DQS7_B_c||TDQS7_B_c
DQS8_A _c||TDQS8_A _c
DQS8_A _t||TDQS8_A _t
DQS9_A _c||TDQS9_A _c
DQS9_A _t||TDQS9_A _t
DQS9_B_c||TDQS9_B_c
DQS9_B_t||TDQS9_B_t||DBI4_B_n 93
94
201
200
283
282
190
189
272
271
179
178
261
260
168
167
250
249
157
156
239
238
55
56
137
138
44
45
126
127
33
34
115
116
22
23
104
105
11
12
288
286
284
281
279
277
275
273
270
268
266
264
262
259
257
255
253
251
248
246
244
242
240
237
235
233
230
228
226
224
222
219
216
214
212
210
208
206
204
202
199
197
195
193
191
188
186
184
182
180
177
175
173
171
169
166
164
162
160
158
155
153
151
143
141
139
136
134
132
130
128
125
123
121
119
117
114
112
110
108
106
103
101
99
97
95
92
90
88
85
83
81
79
77
75
73
71
69
67
65
63
61
59
57
54
52
50
48
46
43
41
39
37
35
32
30
28
26
24
21
19
17
15
13
10
8
6
146
145
1
G3
G2
G1
3
232
231
220
150
149
144
2
207
147
227
74
87
86
5
4
148
287
194
285
192
142
49
140
47
280
187
278
185
135
42
133
40
276
183
274
181
131
38
129
36
269
176
267
174
124
31
122
29
265
172
263
170
120
27
118
25
258
165
256
163
113
20
111
18
254
161
252
159
109
16
107
14
247
154
245
152
102
9
100
7
229
209
84
64
217
218
236
205
234
203
91
60
89
58
243
198
241
196
98
53
96
51
82
72
225
215
80
70
223
213
78
68
221
211
76
66
62
2/3
1/3
PWR_GOOD||FAIL_n
DQ31_A
CB7_A
CB4_A
CB1_A
CB7_B
ALERT_n
CA0_A
CA0_B
CA1_A
CA1_B
CA2_A
CA2_B
CA3_A
CA3_B
CA4_A
CA4_B
CA5_A
CA5_B
CA6_A
CA6_B
CB6_A
CB5_A
CB3_A
CB2_A
CB0_A
CB6_B
CB5_B
CB4_B
CB3_B
CB2_B
CB1_B
CB0_B
CK_c
CK_t
CS0_A_n
CS0_B_n
CS1_A_n
CS1_B_n
DQ30_A
DQ29_A
DQ28_A
DQ27_A
DQ26_A
DQ25_A
DQ24_A
DQ23_A
DQ22_A
DQ21_A
DQ20_A
DQ19_A
DQ18_A
DQ17_A
DQ16_A
DQ15_A
DQ14_A
DQ13_A
DQ12_A
DQ11_A
DQ10_A
DQ9_A
DQ8_A
DQ7_A
DQ6_A
DQ5_A
DQ4_A
DQ3_A
DQ2_A
DQ1_A
DQ0_A
DQ31_B
DQ30_B
DQ29_B
DQ28_B
DQ27_B
DQ26_B
DQ25_B
DQ24_B
DQ23_B
DQ22_B
DQ21_B
DQ20_B
DQ19_B
DQ18_B
DQ17_B
DQ16_B
DQ15_B
DQ14_B
DQ13_B
DQ12_B
DQ11_B
DQ10_B
DQ9_B
DQ8_B
DQ7_B
DQ6_B
DQ5_B
DQ4_B
DQ3_B
DQ2_B
DQ1_B
DQ0_B
HAS
HSCL
HSDA
LBD||RSP_A_n
LBS||RSP_B_n
PAR_A
PAR_B
RESET_n
RFU6
RFU5
RFU4
RFU3
RFU2
RFU1
RFU0
VIN_MGMT
3/3
G3
G2
G1
VSS62
VSS61
VSS60
VSS58
VSS104
VSS102
VSS100
VIN_BULK2
VIN_BULK1
VIN_BULK0
VSS126
VSS125
VSS124
VSS123
VSS122
VSS121
VSS120
VSS119
VSS118
VSS117
VSS116
VSS115
VSS114
VSS113
VSS112
VSS111
VSS110
VSS109
VSS108
VSS107
VSS106
VSS105
VSS103
VSS101
VSS99
VSS98
VSS97
VSS96
VSS95
VSS94
VSS93
VSS92
VSS91
VSS90
VSS89
VSS88
VSS87
VSS86
VSS85
VSS84
VSS83
VSS82
VSS81
VSS80
VSS79
VSS78
VSS77
VSS76
VSS75
VSS74
VSS73
VSS72
VSS71
VSS70
VSS69
VSS68
VSS67
VSS66
VSS65
VSS64
VSS63
VSS59
VSS57
VSS56
VSS55
VSS54
VSS53
VSS52
VSS51
VSS50
VSS49
VSS48
VSS47
VSS46
VSS45
VSS44
VSS43
VSS42
VSS41
VSS40
VSS39
VSS38
VSS37
VSS36
VSS35
VSS34
VSS33
VSS32
VSS31
VSS30
VSS29
VSS28
VSS27
VSS26
VSS25
VSS24
VSS23
VSS22
VSS21
VSS20
VSS19
VSS18
VSS17
VSS16
VSS15
VSS14
VSS13
VSS12
VSS11
VSS10
VSS9
VSS8
VSS7
VSS6
VSS5
VSS4
VSS3
VSS2
VSS1
VSS0
21
21
1
SHEETDATE
23
7 3 2 16 5 4
E
A
B
C
E
D
C
B
A
7 6 5 4
D
DEPARTMENT
SIZE
PROJECT DOCUMENT NUMBER REV
REVIEWER
DESIGNER
IN
IN
BI
BI
IN
IN
IN
OUT
OUT
OUT
OUT
OUT
IN
BI
IN
OUT
IN
IN
IN
IN
IN
OUT
BI
IN
BI
BI
OUT
C



Thu Aug 24 14:08:54 2023<NAME_2>
<NAME_1>
MB FABCGTI V02
94 OF 365
P 3V 3_A UX
P 12V _ME M_CP U0
P 3V 3
929395
9697159
1599293959697
94
92
93
95
96
97
18
18
18
18
18
18
18
18
94
18
18
18
18
18
18
18
18
18
18
18
18
18
18
1K
0402
25V
0.1UF
X 7R
10%
1%
1/16W
E MP TY
1K
0402LF
C0805
25V
10UF
10%
X 6S
C0805
25V
10UF
10%
X 6S
10
0402LFCHIP
I3C_S P D_DDRG L_CP U0_S DA
P W RG D_CHI_CP U0_DIMM
I3C_SPD_DDRI_CPU0_SCL
I3C_S P D_DDRG L_CP U0_S CL
P D_CHI_CP U0_DIMM_S A A
49.9
I3C_SPD_DDRI_CPU0_SDA
P W RG D_CHG L_CP U0
M_I_CP U0_CLK _DP <0>
M_I_CP U0_S A _CS _N<0>
M_I_CP U0_S B _CS _N<0>
M_I_CP U0_S A _CS _N<1>
M_I_CP U0_S B _CS _N<1>
M_I_CP U0_S A _P A R
M_I_CP U0_S B _P A R
M_I_CP U0_CLK _DN<0>
P D_CHI_CP U0_DIMM_S A A
M_I_CP U0_S B _RS P <0>
M_I_CP U0_S A _RS P <0>
M_I_CP U0_S B _DQ S _DN<9:0>
M_I_CP U0_S B _DQ S _DP <9:0>
M_I_CP U0_S A _DQ S _DP <9:0>
M_I_CP U0_S A _DQ S _DN<9:0>
M_I_CP U0_S B _DQ <31:0>
M_I_CP U0_S B _CA <6:0>
M_I_CP U0_S A _CA <6:0>
M_I_CP U0_S B _CB <7:0>
M_I_CP U0_S A _CB <7:0>
M_I_CP U0_S A _DQ <31:0>
DDR5 - CPU0 CHI
SMLF
IO
S CO NN288_DDR506112002K Q
IO
S CO NN288_DDR506112002K Q
SMLF
S CO NN288_DDR506112002K Q
SMLF
IO
0402LF
23.2K
1%
CHIP
1/16W
M_I_CP U0_RE S E T_N
M_I_CP U0_A LE RT_N
J18
J18J18
R1683
R1576
2
1C163
2
1C162
2
1
R98
2 1
R299
2
1C120
2
1
R766
5
4
6
3
2
1
5
6
4
3
2
0
1
6
5
4
0
1
2
3
5
6
7
0
30
31
29
28
27
26
25
24
23
22
21
20
19
18
17
16
15
14
12
13
11
10
9
8
7
6
5
4
1
3
2
0
4
3
2
1
0
7
6
5
4
0
1
3
0
2
1
3
4
5
2
7
6
0
1
2
3
4
5
6
7
8
9
8
0
2
1
3
4
6
7
0
9
1
2
3
4
5
6
7
9
8
8
9
5
31
30
27
28
29
26
24
25
23
22
20
21
19
17
18
15
16
14
13
12
10
11
9
8
7 DQS7_A _c||TDQS7_A _c
DQS6_A _t||TDQS6_A _t
DQS8_B_t||TDQS8_B_t
DQS8_B_c||TDQS8_B_c
DQS7_B_t||TDQS7_B_t
DQS0_A _c
DQS0_A _t
DQS0_B_c
DQS0_B_t
DQS1_A _c
DQS1_A _t
DQS1_B_c
DQS1_B_t
DQS2_A _c
DQS2_A _t
DQS2_B_c
DQS2_B_t
DQS3_A _c
DQS3_A _t
DQS3_B_c
DQS3_B_t
DQS4_A _c
DQS4_A _t
DQS4_B_c
DQS4_B_t
DQS5_A _c||TDQS5_A _c||DQS5_A _t||TDQS5_A _t
DQS5_A _t||TDQS5_A _t
DQS5_B_c||TDQS5_B_c
DQS5_B_t||TDQS5_B_t
DQS6_A _c||TDQS6_A _c||DQS6_A _t||TDQS6_A _t
DQS6_B_c||TDQS6_B_c
DQS6_B_t||TDQS6_B_t
DQS7_A _t||TDQS7_A _t
DQS7_B_c||TDQS7_B_c
DQS8_A _c||TDQS8_A _c
DQS8_A _t||TDQS8_A _t
DQS9_A _c||TDQS9_A _c
DQS9_A _t||TDQS9_A _t
DQS9_B_c||TDQS9_B_c
DQS9_B_t||TDQS9_B_t||DBI4_B_n 93
94
201
200
283
282
190
189
272
271
179
178
261
260
168
167
250
249
157
156
239
238
55
56
137
138
44
45
126
127
33
34
115
116
22
23
104
105
11
12
288
286
284
281
279
277
275
273
270
268
266
264
262
259
257
255
253
251
248
246
244
242
240
237
235
233
230
228
226
224
222
219
216
214
212
210
208
206
204
202
199
197
195
193
191
188
186
184
182
180
177
175
173
171
169
166
164
162
160
158
155
153
151
143
141
139
136
134
132
130
128
125
123
121
119
117
114
112
110
108
106
103
101
99
97
95
92
90
88
85
83
81
79
77
75
73
71
69
67
65
63
61
59
57
54
52
50
48
46
43
41
39
37
35
32
30
28
26
24
21
19
17
15
13
10
8
6
146
145
1
G3
G2
G1
3
232
231
220
150
149
144
2
207
147
227
74
87
86
5
4
148
287
194
285
192
142
49
140
47
280
187
278
185
135
42
133
40
276
183
274
181
131
38
129
36
269
176
267
174
124
31
122
29
265
172
263
170
120
27
118
25
258
165
256
163
113
20
111
18
254
161
252
159
109
16
107
14
247
154
245
152
102
9
100
7
229
209
84
64
217
218
236
205
234
203
91
60
89
58
243
198
241
196
98
53
96
51
82
72
225
215
80
70
223
213
78
68
221
211
76
66
62
2/3
1/3
PWR_GOOD||FAIL_n
DQ31_A
CB7_A
CB4_A
CB1_A
CB7_B
ALERT_n
CA0_A
CA0_B
CA1_A
CA1_B
CA2_A
CA2_B
CA3_A
CA3_B
CA4_A
CA4_B
CA5_A
CA5_B
CA6_A
CA6_B
CB6_A
CB5_A
CB3_A
CB2_A
CB0_A
CB6_B
CB5_B
CB4_B
CB3_B
CB2_B
CB1_B
CB0_B
CK_c
CK_t
CS0_A_n
CS0_B_n
CS1_A_n
CS1_B_n
DQ30_A
DQ29_A
DQ28_A
DQ27_A
DQ26_A
DQ25_A
DQ24_A
DQ23_A
DQ22_A
DQ21_A
DQ20_A
DQ19_A
DQ18_A
DQ17_A
DQ16_A
DQ15_A
DQ14_A
DQ13_A
DQ12_A
DQ11_A
DQ10_A
DQ9_A
DQ8_A
DQ7_A
DQ6_A
DQ5_A
DQ4_A
DQ3_A
DQ2_A
DQ1_A
DQ0_A
DQ31_B
DQ30_B
DQ29_B
DQ28_B
DQ27_B
DQ26_B
DQ25_B
DQ24_B
DQ23_B
DQ22_B
DQ21_B
DQ20_B
DQ19_B
DQ18_B
DQ17_B
DQ16_B
DQ15_B
DQ14_B
DQ13_B
DQ12_B
DQ11_B
DQ10_B
DQ9_B
DQ8_B
DQ7_B
DQ6_B
DQ5_B
DQ4_B
DQ3_B
DQ2_B
DQ1_B
DQ0_B
HAS
HSCL
HSDA
LBD||RSP_A_n
LBS||RSP_B_n
PAR_A
PAR_B
RESET_n
RFU6
RFU5
RFU4
RFU3
RFU2
RFU1
RFU0
VIN_MGMT
3/3
G3
G2
G1
VSS62
VSS61
VSS60
VSS58
VSS104
VSS102
VSS100
VIN_BULK2
VIN_BULK1
VIN_BULK0
VSS126
VSS125
VSS124
VSS123
VSS122
VSS121
VSS120
VSS119
VSS118
VSS117
VSS116
VSS115
VSS114
VSS113
VSS112
VSS111
VSS110
VSS109
VSS108
VSS107
VSS106
VSS105
VSS103
VSS101
VSS99
VSS98
VSS97
VSS96
VSS95
VSS94
VSS93
VSS92
VSS91
VSS90
VSS89
VSS88
VSS87
VSS86
VSS85
VSS84
VSS83
VSS82
VSS81
VSS80
VSS79
VSS78
VSS77
VSS76
VSS75
VSS74
VSS73
VSS72
VSS71
VSS70
VSS69
VSS68
VSS67
VSS66
VSS65
VSS64
VSS63
VSS59
VSS57
VSS56
VSS55
VSS54
VSS53
VSS52
VSS51
VSS50
VSS49
VSS48
VSS47
VSS46
VSS45
VSS44
VSS43
VSS42
VSS41
VSS40
VSS39
VSS38
VSS37
VSS36
VSS35
VSS34
VSS33
VSS32
VSS31
VSS30
VSS29
VSS28
VSS27
VSS26
VSS25
VSS24
VSS23
VSS22
VSS21
VSS20
VSS19
VSS18
VSS17
VSS16
VSS15
VSS14
VSS13
VSS12
VSS11
VSS10
VSS9
VSS8
VSS7
VSS6
VSS5
VSS4
VSS3
VSS2
VSS1
VSS0
21
21
1
SHEETDATE
23
7 3 2 16 5 4
E
A
B
C
E
D
C
B
A
7 6 5 4
D
DEPARTMENT
SIZE
PROJECT DOCUMENT NUMBER REV
REVIEWER
DESIGNER
IN
BI
OUT
IN
BI
IN
IN
IN
OUT
OUT
OUT
OUT
OUT
IN
BI
IN
IN
IN
IN
IN
IN
OUT
BI
BI
IN
BI
OUT
C



Thu Aug 24 14:08:54 2023<NAME_2>
<NAME_1>
MB FABCGTI V02
95 OF 365
P 12V _ME M_CP U0
P 3V 3_A UX
P 3V 3
M_J_CP U0_A LE RT_N
95
92939496
97159
1599293949697
19
19
19
19
19
19
19
19
929394
9697
19
19
19
19
19
19
95
19
19
19
19
19
19
19
19
1K
X 6S
10%
10UF
C0805
25V
X 6S
10%
10UF
25V
C0805
0402LF
1K
E MP TY
1/16W
1%
X 7R
10%
0.1UF
25V
0402
CHIP 0402LF
10
P D_CHJ_CP U0_DIMM_S A A
I3C_S P D_DDRG L_CP U0_S DA
I3C_S P D_DDRG L_CP U0_S CL
I3C_SPD_DDRJ_CPU0_SDA
P W RG D_CHJ_CP U0_DIMM
49.9
0402LF
35.7K
1%
CHIP
1/16W
S CO NN288_DDR506112002K Q
IO
SMLF
SMLF
S CO NN288_DDR506112002K Q
IO
SMLF
S CO NN288_DDR506112002K Q
IO
DDR5 - CPU0 CHJ
M_J_CP U0_S A _CA <6:0>
M_J_CP U0_S B _CA <6:0>
M_J_CP U0_S A _DQ <31:0>
M_J_CP U0_S B _DQ <31:0>
M_J_CP U0_S A _DQ S _DN<9:0>
M_J_CP U0_S A _DQ S _DP <9:0>
M_J_CP U0_S B _DQ S _DP <9:0>
M_J_CP U0_S B _DQ S _DN<9:0>
P W RG D_CHG L_CP U0
M_J_CP U0_S A _RS P <0>
M_J_CP U0_S B _P A R
M_J_CP U0_S A _P A R
M_J_CP U0_S B _CS _N<1>
M_J_CP U0_S A _CS _N<1>
M_J_CP U0_S A _CS _N<0>
P D_CHJ_CP U0_DIMM_S A A
M_J_CP U0_S B _CS _N<0>
M_J_CP U0_CLK _DP <0>
M_J_CP U0_CLK _DN<0>
M_J_CP U0_S A _CB <7:0>
M_J_CP U0_S B _CB <7:0>
M_J_CP U0_RE S E T_N
M_J_CP U0_S B _RS P <0>
I3C_SPD_DDRJ_CPU0_SCL
J68
J68
J68
R1684
R1577
2
1C166
2
1C165
2
1
R99
2 1
R300
2
1C124
2
1
R767
6
7
10
9
8
11
12
13
14
15
17
16
20
19
18
22
21
25
24
23
27
28
26
30
29
31
8
9
9
8
7
6
5
4
3
2
1
0
9
7
6
5
4
3
2
1
0
9
8
7
8
6
4
5
3
1
2
0
7
6
0
4
5
3
2
1
0
1
2
3
4
6
7
0
1
3
2
0
2
1
4
3
5
6
7
9
8
10
12
11
14
13
15
17
16
20
19
18
21
22
25
24
23
26
27
30
29
28
31
4
5
6
7
0
1
2
3
4
5
6
0
1
2
3
4
5
6
0
2
1
3
4
5
5
DQS7_A _c||TDQS7_A _c
DQS6_A _t||TDQS6_A _t
DQS8_B_t||TDQS8_B_t
DQS8_B_c||TDQS8_B_c
DQS7_B_t||TDQS7_B_t
DQS0_A _c
DQS0_A _t
DQS0_B_c
DQS0_B_t
DQS1_A _c
DQS1_A _t
DQS1_B_c
DQS1_B_t
DQS2_A _c
DQS2_A _t
DQS2_B_c
DQS2_B_t
DQS3_A _c
DQS3_A _t
DQS3_B_c
DQS3_B_t
DQS4_A _c
DQS4_A _t
DQS4_B_c
DQS4_B_t
DQS5_A _c||TDQS5_A _c||DQS5_A _t||TDQS5_A _t
DQS5_A _t||TDQS5_A _t
DQS5_B_c||TDQS5_B_c
DQS5_B_t||TDQS5_B_t
DQS6_A _c||TDQS6_A _c||DQS6_A _t||TDQS6_A _t
DQS6_B_c||TDQS6_B_c
DQS6_B_t||TDQS6_B_t
DQS7_A _t||TDQS7_A _t
DQS7_B_c||TDQS7_B_c
DQS8_A _c||TDQS8_A _c
DQS8_A _t||TDQS8_A _t
DQS9_A _c||TDQS9_A _c
DQS9_A _t||TDQS9_A _t
DQS9_B_c||TDQS9_B_c
DQS9_B_t||TDQS9_B_t||DBI4_B_n 93
94
201
200
283
282
190
189
272
271
179
178
261
260
168
167
250
249
157
156
239
238
55
56
137
138
44
45
126
127
33
34
115
116
22
23
104
105
11
12
288
286
284
281
279
277
275
273
270
268
266
264
262
259
257
255
253
251
248
246
244
242
240
237
235
233
230
228
226
224
222
219
216
214
212
210
208
206
204
202
199
197
195
193
191
188
186
184
182
180
177
175
173
171
169
166
164
162
160
158
155
153
151
143
141
139
136
134
132
130
128
125
123
121
119
117
114
112
110
108
106
103
101
99
97
95
92
90
88
85
83
81
79
77
75
73
71
69
67
65
63
61
59
57
54
52
50
48
46
43
41
39
37
35
32
30
28
26
24
21
19
17
15
13
10
8
6
146
145
1
G3
G2
G1
3
232
231
220
150
149
144
2
207
147
227
74
87
86
5
4
148
287
194
285
192
142
49
140
47
280
187
278
185
135
42
133
40
276
183
274
181
131
38
129
36
269
176
267
174
124
31
122
29
265
172
263
170
120
27
118
25
258
165
256
163
113
20
111
18
254
161
252
159
109
16
107
14
247
154
245
152
102
9
100
7
229
209
84
64
217
218
236
205
234
203
91
60
89
58
243
198
241
196
98
53
96
51
82
72
225
215
80
70
223
213
78
68
221
211
76
66
62
2/3
1/3
PWR_GOOD||FAIL_n
DQ31_A
CB7_A
CB4_A
CB1_A
CB7_B
ALERT_n
CA0_A
CA0_B
CA1_A
CA1_B
CA2_A
CA2_B
CA3_A
CA3_B
CA4_A
CA4_B
CA5_A
CA5_B
CA6_A
CA6_B
CB6_A
CB5_A
CB3_A
CB2_A
CB0_A
CB6_B
CB5_B
CB4_B
CB3_B
CB2_B
CB1_B
CB0_B
CK_c
CK_t
CS0_A_n
CS0_B_n
CS1_A_n
CS1_B_n
DQ30_A
DQ29_A
DQ28_A
DQ27_A
DQ26_A
DQ25_A
DQ24_A
DQ23_A
DQ22_A
DQ21_A
DQ20_A
DQ19_A
DQ18_A
DQ17_A
DQ16_A
DQ15_A
DQ14_A
DQ13_A
DQ12_A
DQ11_A
DQ10_A
DQ9_A
DQ8_A
DQ7_A
DQ6_A
DQ5_A
DQ4_A
DQ3_A
DQ2_A
DQ1_A
DQ0_A
DQ31_B
DQ30_B
DQ29_B
DQ28_B
DQ27_B
DQ26_B
DQ25_B
DQ24_B
DQ23_B
DQ22_B
DQ21_B
DQ20_B
DQ19_B
DQ18_B
DQ17_B
DQ16_B
DQ15_B
DQ14_B
DQ13_B
DQ12_B
DQ11_B
DQ10_B
DQ9_B
DQ8_B
DQ7_B
DQ6_B
DQ5_B
DQ4_B
DQ3_B
DQ2_B
DQ1_B
DQ0_B
HAS
HSCL
HSDA
LBD||RSP_A_n
LBS||RSP_B_n
PAR_A
PAR_B
RESET_n
RFU6
RFU5
RFU4
RFU3
RFU2
RFU1
RFU0
VIN_MGMT
3/3
G3
G2
G1
VSS62
VSS61
VSS60
VSS58
VSS104
VSS102
VSS100
VIN_BULK2
VIN_BULK1
VIN_BULK0
VSS126
VSS125
VSS124
VSS123
VSS122
VSS121
VSS120
VSS119
VSS118
VSS117
VSS116
VSS115
VSS114
VSS113
VSS112
VSS111
VSS110
VSS109
VSS108
VSS107
VSS106
VSS105
VSS103
VSS101
VSS99
VSS98
VSS97
VSS96
VSS95
VSS94
VSS93
VSS92
VSS91
VSS90
VSS89
VSS88
VSS87
VSS86
VSS85
VSS84
VSS83
VSS82
VSS81
VSS80
VSS79
VSS78
VSS77
VSS76
VSS75
VSS74
VSS73
VSS72
VSS71
VSS70
VSS69
VSS68
VSS67
VSS66
VSS65
VSS64
VSS63
VSS59
VSS57
VSS56
VSS55
VSS54
VSS53
VSS52
VSS51
VSS50
VSS49
VSS48
VSS47
VSS46
VSS45
VSS44
VSS43
VSS42
VSS41
VSS40
VSS39
VSS38
VSS37
VSS36
VSS35
VSS34
VSS33
VSS32
VSS31
VSS30
VSS29
VSS28
VSS27
VSS26
VSS25
VSS24
VSS23
VSS22
VSS21
VSS20
VSS19
VSS18
VSS17
VSS16
VSS15
VSS14
VSS13
VSS12
VSS11
VSS10
VSS9
VSS8
VSS7
VSS6
VSS5
VSS4
VSS3
VSS2
VSS1
VSS0
21
21
1
SHEETDATE
23
7 3 2 16 5 4
E
A
B
C
E
D
C
B
A
7 6 5 4
D
DEPARTMENT
SIZE
PROJECT DOCUMENT NUMBER REV
REVIEWER
DESIGNER
IN
BI
OUT
IN
BI
IN
IN
IN
OUT
OUT
OUT
OUT
OUT
IN
BI
IN
IN
IN
IN
IN
IN
OUT
BI
IN
BI
BI
OUT
C



Thu Aug 24 14:08:54 2023<NAME_2>
<NAME_1>
MB FABCGTI V02
96 OF 365
P 3V 3
P 12V _ME M_CP U0
P 3V 3_A UX
96
1599293949597
929394
9597159
20
20
20
20
20
20
20
20
20
20
96
20
20
20
20
20
20
20
20
20
20
92
93
94
95
97
20
20
1K
X 6S
10%
10UF
25V
C0805
X 6S
10%
10UF
25V
C0805
1/16W
E MP TY
0402LF
1K
1%
X 7R
10%
0402
25V
0.1UF
CHIP
10
0402LF
P D_CHK _CP U0_DIMM_S A A
I3C_S P D_DDRG L_CP U0_S CL
I3C_S P D_DDRG L_CP U0_S DA
I3C_SPD_DDRK_CPU0_SDA
I3C_SPD_DDRK_CPU0_SCL
P W RG D_CHK _CP U0_DIMM
M_K _CP U0_RE S E T_N
1/16W
CHIP
1%
54.9K
0402LF
IO
S CO NN288_DDR506112002K Q
SMLF
IO
S CO NN288_DDR506112002K Q
SMLF
S CO NN288_DDR506112002K Q
IO
SMLF
DDR5 - CPU0 CHK
M_K _CP U0_S A _CA <6:0>
M_K _CP U0_S B _DQ S _DP <9:0>
M_K _CP U0_S B _DQ S _DN<9:0>
M_K _CP U0_S A _DQ S _DP <9:0>
M_K _CP U0_S A _DQ S _DN<9:0>
M_K _CP U0_S B _DQ <31:0>
M_K _CP U0_S A _DQ <31:0>
M_K _CP U0_S A _CB <7:0>
M_K _CP U0_S B _CA <6:0>
P D_CHK _CP U0_DIMM_S A A
M_K _CP U0_S B _CS _N<0>
M_K _CP U0_S B _CS _N<1>
M_K _CP U0_S A _P A R
M_K _CP U0_S B _P A R
M_K _CP U0_S A _CS _N<1>
M_K _CP U0_S A _CS _N<0>
M_K _CP U0_S B _RS P <0>
M_K _CP U0_CLK _DP <0>
M_K _CP U0_CLK _DN<0>
M_K _CP U0_S A _RS P <0>
P W RG D_CHG L_CP U0
M_K _CP U0_S B _CB <7:0>
M_K _CP U0_A LE RT_N
49.9
J20
J20
J20
R1578
2
1C169
2
1C167
2
1
R100
2 1
R301
2
1C128
2
1
R768
25
6
6
7
8
9
10
12
11
13
14
15
16
17
18
19
20
21
22
23
24
25
26
27
28
30
29
31
6
6
7
9
8
9
7
8
7
5
6
4
3
2
0
1
9
8
6
5
4
2
3
1
0
9
8
7
4
5
3
2
1
0
0
5
4
3
2
1
0
1
2
4
3
5
6
7
0
1
2
3
5
4
0
1
2
3
4
6
5
8
7
9
11
10
12
13
14
16
15
17
18
19
20
21
22
24
23
26
27
29
28
31
30
0
1
7
0
2
1
4
3
5
6
0
1
2
3
4
5
6
2
3
4
5
R1685
DQS7_A _c||TDQS7_A _c
DQS6_A _t||TDQS6_A _t
DQS8_B_t||TDQS8_B_t
DQS8_B_c||TDQS8_B_c
DQS7_B_t||TDQS7_B_t
DQS0_A _c
DQS0_A _t
DQS0_B_c
DQS0_B_t
DQS1_A _c
DQS1_A _t
DQS1_B_c
DQS1_B_t
DQS2_A _c
DQS2_A _t
DQS2_B_c
DQS2_B_t
DQS3_A _c
DQS3_A _t
DQS3_B_c
DQS3_B_t
DQS4_A _c
DQS4_A _t
DQS4_B_c
DQS4_B_t
DQS5_A _c||TDQS5_A _c||DQS5_A _t||TDQS5_A _t
DQS5_A _t||TDQS5_A _t
DQS5_B_c||TDQS5_B_c
DQS5_B_t||TDQS5_B_t
DQS6_A _c||TDQS6_A _c||DQS6_A _t||TDQS6_A _t
DQS6_B_c||TDQS6_B_c
DQS6_B_t||TDQS6_B_t
DQS7_A _t||TDQS7_A _t
DQS7_B_c||TDQS7_B_c
DQS8_A _c||TDQS8_A _c
DQS8_A _t||TDQS8_A _t
DQS9_A _c||TDQS9_A _c
DQS9_A _t||TDQS9_A _t
DQS9_B_c||TDQS9_B_c
DQS9_B_t||TDQS9_B_t||DBI4_B_n 93
94
201
200
283
282
190
189
272
271
179
178
261
260
168
167
250
249
157
156
239
238
55
56
137
138
44
45
126
127
33
34
115
116
22
23
104
105
11
12
288
286
284
281
279
277
275
273
270
268
266
264
262
259
257
255
253
251
248
246
244
242
240
237
235
233
230
228
226
224
222
219
216
214
212
210
208
206
204
202
199
197
195
193
191
188
186
184
182
180
177
175
173
171
169
166
164
162
160
158
155
153
151
143
141
139
136
134
132
130
128
125
123
121
119
117
114
112
110
108
106
103
101
99
97
95
92
90
88
85
83
81
79
77
75
73
71
69
67
65
63
61
59
57
54
52
50
48
46
43
41
39
37
35
32
30
28
26
24
21
19
17
15
13
10
8
6
146
145
1
G3
G2
G1
3
232
231
220
150
149
144
2
207
147
227
74
87
86
5
4
148
287
194
285
192
142
49
140
47
280
187
278
185
135
42
133
40
276
183
274
181
131
38
129
36
269
176
267
174
124
31
122
29
265
172
263
170
120
27
118
25
258
165
256
163
113
20
111
18
254
161
252
159
109
16
107
14
247
154
245
152
102
9
100
7
229
209
84
64
217
218
236
205
234
203
91
60
89
58
243
198
241
196
98
53
96
51
82
72
225
215
80
70
223
213
78
68
221
211
76
66
62
2/3
1/3
PWR_GOOD||FAIL_n
DQ31_A
CB7_A
CB4_A
CB1_A
CB7_B
ALERT_n
CA0_A
CA0_B
CA1_A
CA1_B
CA2_A
CA2_B
CA3_A
CA3_B
CA4_A
CA4_B
CA5_A
CA5_B
CA6_A
CA6_B
CB6_A
CB5_A
CB3_A
CB2_A
CB0_A
CB6_B
CB5_B
CB4_B
CB3_B
CB2_B
CB1_B
CB0_B
CK_c
CK_t
CS0_A_n
CS0_B_n
CS1_A_n
CS1_B_n
DQ30_A
DQ29_A
DQ28_A
DQ27_A
DQ26_A
DQ25_A
DQ24_A
DQ23_A
DQ22_A
DQ21_A
DQ20_A
DQ19_A
DQ18_A
DQ17_A
DQ16_A
DQ15_A
DQ14_A
DQ13_A
DQ12_A
DQ11_A
DQ10_A
DQ9_A
DQ8_A
DQ7_A
DQ6_A
DQ5_A
DQ4_A
DQ3_A
DQ2_A
DQ1_A
DQ0_A
DQ31_B
DQ30_B
DQ29_B
DQ28_B
DQ27_B
DQ26_B
DQ25_B
DQ24_B
DQ23_B
DQ22_B
DQ21_B
DQ20_B
DQ19_B
DQ18_B
DQ17_B
DQ16_B
DQ15_B
DQ14_B
DQ13_B
DQ12_B
DQ11_B
DQ10_B
DQ9_B
DQ8_B
DQ7_B
DQ6_B
DQ5_B
DQ4_B
DQ3_B
DQ2_B
DQ1_B
DQ0_B
HAS
HSCL
HSDA
LBD||RSP_A_n
LBS||RSP_B_n
PAR_A
PAR_B
RESET_n
RFU6
RFU5
RFU4
RFU3
RFU2
RFU1
RFU0
VIN_MGMT
3/3
G3
G2
G1
VSS62
VSS61
VSS60
VSS58
VSS104
VSS102
VSS100
VIN_BULK2
VIN_BULK1
VIN_BULK0
VSS126
VSS125
VSS124
VSS123
VSS122
VSS121
VSS120
VSS119
VSS118
VSS117
VSS116
VSS115
VSS114
VSS113
VSS112
VSS111
VSS110
VSS109
VSS108
VSS107
VSS106
VSS105
VSS103
VSS101
VSS99
VSS98
VSS97
VSS96
VSS95
VSS94
VSS93
VSS92
VSS91
VSS90
VSS89
VSS88
VSS87
VSS86
VSS85
VSS84
VSS83
VSS82
VSS81
VSS80
VSS79
VSS78
VSS77
VSS76
VSS75
VSS74
VSS73
VSS72
VSS71
VSS70
VSS69
VSS68
VSS67
VSS66
VSS65
VSS64
VSS63
VSS59
VSS57
VSS56
VSS55
VSS54
VSS53
VSS52
VSS51
VSS50
VSS49
VSS48
VSS47
VSS46
VSS45
VSS44
VSS43
VSS42
VSS41
VSS40
VSS39
VSS38
VSS37
VSS36
VSS35
VSS34
VSS33
VSS32
VSS31
VSS30
VSS29
VSS28
VSS27
VSS26
VSS25
VSS24
VSS23
VSS22
VSS21
VSS20
VSS19
VSS18
VSS17
VSS16
VSS15
VSS14
VSS13
VSS12
VSS11
VSS10
VSS9
VSS8
VSS7
VSS6
VSS5
VSS4
VSS3
VSS2
VSS1
VSS0
21
21
1
SHEETDATE
23
7 3 2 16 5 4
E
A
B
C
E
D
C
B
A
7 6 5 4
D
DEPARTMENT
SIZE
PROJECT DOCUMENT NUMBER REV
REVIEWER
DESIGNER
IN
BI
OUT
OUT
OUT
IN
BI
IN
IN
IN
OUT
OUT
OUT
OUT
IN
BI
IN
IN
IN
IN
IN
BI
OUT
BI
IN
IN
BI
C



Thu Aug 24 14:08:55 2023<NAME_2>
<NAME_1>
MB FABCGTI V02
97 OF 365
P 12V _ME M_CP U0
P 3V 3_A UX
P 3V 3
97
92939495
96159
1599293949596
21
21
21
21
21
21
21
21
21
21
929394
9596
21
21
21
21
21
21
21
21
97
21
21
21
21
1K
10%
10UF
25V
C0805
X 6S
10UF
25V
C0805
X 6S
10%
1K
0402LF
E MP TY
1/16W
1%
X 7R
0.1UF
10%
25V
0402
CHIP
10
0402LF
P D_CHL_CP U0_DIMM_S A A
I3C_S P D_DDRG L_CP U0_S DA
I3C_SPD_DDRL_CPU0_SDA
49.9
I3C_SPD_DDRL_CPU0_SCL
I3C_S P D_DDRG L_CP U0_S CL
0402LF
84.5K
1%
CHIP
1/16W
IO
SMLF
S CO NN288_DDR506112002K Q
IO
S CO NN288_DDR506112002K Q
SMLF
IO
S CO NN288_DDR506112002K Q
SMLF
DDR5 - CPU0 CHL
M_L_CP U0_S A _CB <7:0>
M_L_CP U0_S B _CB <7:0>
M_L_CP U0_S A _CA <6:0>
M_L_CP U0_S B _CA <6:0>
M_L_CP U0_S A _DQ <31:0>
M_L_CP U0_S B _DQ <31:0>
M_L_CP U0_S A _DQ S _DN<9:0>
M_L_CP U0_S A _DQ S _DP <9:0>
M_L_CP U0_S B _DQ S _DP <9:0>
M_L_CP U0_S B _DQ S _DN<9:0>
P W RG D_CHG L_CP U0
M_L_CP U0_S B _P A R
M_L_CP U0_S A _P A R
M_L_CP U0_S B _CS _N<1>
M_L_CP U0_S A _CS _N<1>
M_L_CP U0_S B _CS _N<0>
M_L_CP U0_S A _CS _N<0>
M_L_CP U0_CLK _DP <0>
M_L_CP U0_CLK _DN<0>
P D_CHL_CP U0_DIMM_S A A
M_L_CP U0_A LE RT_N
M_L_CP U0_RE S E T_N
P W RG D_CHL_CP U0_DIMM
M_L_CP U0_S A _RS P <0>
M_L_CP U0_S B _RS P <0>
J67
J67
J67
2
1C171
2
1C170
2
1
R101
2 1
R302
2
1C132
2
1
R769
8
9
10
12
11
13
14
15
16
18
17
19
20
21
22
23
24
25
26
27
28
30
31
29
9
8
9
8
7
6
7
6
4
5
5
3
4
2
3
1
2
1
9
0
0
9
8
7
8
7
6
5
6
4
5
4
2
3
0
1
3
2
1
0
0
1
2
4
5
3
7
1
0
6
0
1
2
3
4
5
6
7
8
10
9
11
12
13
14
15
16
17
18
19
20
21
22
23
24
25
26
27
28
29
30
2
3
5
6
4
7
0
1
2
3
4
6
5
1
2
3
0
5
6
4
31
0
1
2
3
4
5
6
7
R1686
R1579
DQS7_A _c||TDQS7_A _c
DQS6_A _t||TDQS6_A _t
DQS8_B_t||TDQS8_B_t
DQS8_B_c||TDQS8_B_c
DQS7_B_t||TDQS7_B_t
DQS0_A _c
DQS0_A _t
DQS0_B_c
DQS0_B_t
DQS1_A _c
DQS1_A _t
DQS1_B_c
DQS1_B_t
DQS2_A _c
DQS2_A _t
DQS2_B_c
DQS2_B_t
DQS3_A _c
DQS3_A _t
DQS3_B_c
DQS3_B_t
DQS4_A _c
DQS4_A _t
DQS4_B_c
DQS4_B_t
DQS5_A _c||TDQS5_A _c||DQS5_A _t||TDQS5_A _t
DQS5_A _t||TDQS5_A _t
DQS5_B_c||TDQS5_B_c
DQS5_B_t||TDQS5_B_t
DQS6_A _c||TDQS6_A _c||DQS6_A _t||TDQS6_A _t
DQS6_B_c||TDQS6_B_c
DQS6_B_t||TDQS6_B_t
DQS7_A _t||TDQS7_A _t
DQS7_B_c||TDQS7_B_c
DQS8_A _c||TDQS8_A _c
DQS8_A _t||TDQS8_A _t
DQS9_A _c||TDQS9_A _c
DQS9_A _t||TDQS9_A _t
DQS9_B_c||TDQS9_B_c
DQS9_B_t||TDQS9_B_t||DBI4_B_n 93
94
201
200
283
282
190
189
272
271
179
178
261
260
168
167
250
249
157
156
239
238
55
56
137
138
44
45
126
127
33
34
115
116
22
23
104
105
11
12
288
286
284
281
279
277
275
273
270
268
266
264
262
259
257
255
253
251
248
246
244
242
240
237
235
233
230
228
226
224
222
219
216
214
212
210
208
206
204
202
199
197
195
193
191
188
186
184
182
180
177
175
173
171
169
166
164
162
160
158
155
153
151
143
141
139
136
134
132
130
128
125
123
121
119
117
114
112
110
108
106
103
101
99
97
95
92
90
88
85
83
81
79
77
75
73
71
69
67
65
63
61
59
57
54
52
50
48
46
43
41
39
37
35
32
30
28
26
24
21
19
17
15
13
10
8
6
146
145
1
G3
G2
G1
3
232
231
220
150
149
144
2
207
147
227
74
87
86
5
4
148
287
194
285
192
142
49
140
47
280
187
278
185
135
42
133
40
276
183
274
181
131
38
129
36
269
176
267
174
124
31
122
29
265
172
263
170
120
27
118
25
258
165
256
163
113
20
111
18
254
161
252
159
109
16
107
14
247
154
245
152
102
9
100
7
229
209
84
64
217
218
236
205
234
203
91
60
89
58
243
198
241
196
98
53
96
51
82
72
225
215
80
70
223
213
78
68
221
211
76
66
62
2/3
1/3
PWR_GOOD||FAIL_n
DQ31_A
CB7_A
CB4_A
CB1_A
CB7_B
ALERT_n
CA0_A
CA0_B
CA1_A
CA1_B
CA2_A
CA2_B
CA3_A
CA3_B
CA4_A
CA4_B
CA5_A
CA5_B
CA6_A
CA6_B
CB6_A
CB5_A
CB3_A
CB2_A
CB0_A
CB6_B
CB5_B
CB4_B
CB3_B
CB2_B
CB1_B
CB0_B
CK_c
CK_t
CS0_A_n
CS0_B_n
CS1_A_n
CS1_B_n
DQ30_A
DQ29_A
DQ28_A
DQ27_A
DQ26_A
DQ25_A
DQ24_A
DQ23_A
DQ22_A
DQ21_A
DQ20_A
DQ19_A
DQ18_A
DQ17_A
DQ16_A
DQ15_A
DQ14_A
DQ13_A
DQ12_A
DQ11_A
DQ10_A
DQ9_A
DQ8_A
DQ7_A
DQ6_A
DQ5_A
DQ4_A
DQ3_A
DQ2_A
DQ1_A
DQ0_A
DQ31_B
DQ30_B
DQ29_B
DQ28_B
DQ27_B
DQ26_B
DQ25_B
DQ24_B
DQ23_B
DQ22_B
DQ21_B
DQ20_B
DQ19_B
DQ18_B
DQ17_B
DQ16_B
DQ15_B
DQ14_B
DQ13_B
DQ12_B
DQ11_B
DQ10_B
DQ9_B
DQ8_B
DQ7_B
DQ6_B
DQ5_B
DQ4_B
DQ3_B
DQ2_B
DQ1_B
DQ0_B
HAS
HSCL
HSDA
LBD||RSP_A_n
LBS||RSP_B_n
PAR_A
PAR_B
RESET_n
RFU6
RFU5
RFU4
RFU3
RFU2
RFU1
RFU0
VIN_MGMT
3/3
G3
G2
G1
VSS62
VSS61
VSS60
VSS58
VSS104
VSS102
VSS100
VIN_BULK2
VIN_BULK1
VIN_BULK0
VSS126
VSS125
VSS124
VSS123
VSS122
VSS121
VSS120
VSS119
VSS118
VSS117
VSS116
VSS115
VSS114
VSS113
VSS112
VSS111
VSS110
VSS109
VSS108
VSS107
VSS106
VSS105
VSS103
VSS101
VSS99
VSS98
VSS97
VSS96
VSS95
VSS94
VSS93
VSS92
VSS91
VSS90
VSS89
VSS88
VSS87
VSS86
VSS85
VSS84
VSS83
VSS82
VSS81
VSS80
VSS79
VSS78
VSS77
VSS76
VSS75
VSS74
VSS73
VSS72
VSS71
VSS70
VSS69
VSS68
VSS67
VSS66
VSS65
VSS64
VSS63
VSS59
VSS57
VSS56
VSS55
VSS54
VSS53
VSS52
VSS51
VSS50
VSS49
VSS48
VSS47
VSS46
VSS45
VSS44
VSS43
VSS42
VSS41
VSS40
VSS39
VSS38
VSS37
VSS36
VSS35
VSS34
VSS33
VSS32
VSS31
VSS30
VSS29
VSS28
VSS27
VSS26
VSS25
VSS24
VSS23
VSS22
VSS21
VSS20
VSS19
VSS18
VSS17
VSS16
VSS15
VSS14
VSS13
VSS12
VSS11
VSS10
VSS9
VSS8
VSS7
VSS6
VSS5
VSS4
VSS3
VSS2
VSS1
VSS0
21
21
1
SHEETDATE
23
7 3 2 16 5 4
E
A
B
C
E
D
C
B
A
7 6 5 4
D
DEPARTMENT
SIZE
PROJECT DOCUMENT NUMBER REV
REVIEWER
DESIGNER
IN
OUT
IN
BI
IN
OUT
OUT
IN
IN
OUT
OUT
OUT
IN
BI
IN
IN
IN
IN
IN
BI
OUT
BI
BI
IN
IN
BI
OUT
C



Thu Aug 24 14:08:55 2023<NAME_2>
<NAME_1>
MB FABCGTI V02
98 OF 365
P 3V 3_A UX
P 3V 3_A UX
P 3V 3_A UX
P 3V 3_A UX
P 12V _ME M_CP U1
P 3V 3P 3V 3
99100101102103159
15999100101102103
98
37
37
37
9899100
101102
103
37
37
37
37
37
37
37
37
37
98
829899100101102103
98 99 100 101 102 103
37
37
37
37
37
37
37
37
37
37
1K
1/16W
0402LF
X 7R
10%
0.1UF
25V
0402
E MP TY
0402LF
1K
1/16W
1% 1%
1/16W
E MP TY
0402LF
1K
X 6S
10%
10UF
25V
C0805
X 6S
10%
10UF
25V
C0805
0402LF
10
CHIP
I3C_S P D_DDRA F_CP U1_S DA
I3C_SPD_DDRA_CPU1_SDA
I3C_SPD_DDRA_CPU1_SCL
I3C_S P D_DDRA F_CP U1_S CL
P W RG D_CHA _CP U1_DIMM0
P D_CHA _CP U1_DIMM0_S A A
M_A _CP U1_RE S E T_N
M_A _CP U1_A LE RT_N
49.9
M_A _CP U1_S B _CS _N<1>
P W RG D_CHA F_CP U1
M_A _CP U1_S B _P A R
M_A _CP U1_S A _P A R
M_A _CP U1_S B _RS P <0>
M_A _CP U1_S A _RS P <0>
M_A _CP U1_S A _CS _N<1>
M_A _CP U1_S B _CS _N<0>
M_A _CP U1_S A _CS _N<0>
M_A _CP U1_CLK _DP <0>
M_A _CP U1_CLK _DN<0>
P D_CHA _CP U1_DIMM0_S A A
PWRGD_CHAF_CPU1_R2PWRGD_CHAF_CPU1
PWRGD_CHAF_CPU1
PWRGD_CHAF_CPU1_R1
M_A _CP U1_S B _CA <6:0>
M_A _CP U1_S A _CB <7:0>
M_A _CP U1_S B _CB <7:0>
M_A _CP U1_S A _DQ S _DN<9:0>
M_A _CP U1_S B _DQ S _DN<9:0>
M_A _CP U1_S B _DQ S _DP <9:0>
M_A _CP U1_S A _DQ <31:0>
M_A _CP U1_S A _DQ S _DP <9:0>
M_A _CP U1_S A _CA <6:0>
M_A _CP U1_S B _DQ <31:0>
DDR5 - CPU1 CHA
SMLF
B0530WS7F
EMPTY
0 5%
0402LFCHIP1/16W
1%10K
1/16W 0402LFEMPTY
1/16W 0402LFCHIP
5%0
0402LF
CHIP
10K
1/16W
1%
S CO NN288_DDR506112002K Q
IO
SMLF
IO
SMLF
S CO NN288_DDR506112002K Q
SMLF
IO
S CO NN288_DDR506112002K Q
10K
1%
CHIP
J24
J24J24
R1687
R1580
2
1C174
2
1C173
2
1
R103
2 1R303
2
1
R102
2
1C136
2
1
R36
1
4
29
6
6
5
4
3
2
0
1
6
5
4
3
2
1
0
2
4
3
0
1
31
30
28
27
26
25
23
24
22
21
20
18
19
17
15
16
12
13
14
11
10
7
8
9
6
5
2
3
4
0
1
7
6
5
4
3
2
0
7
6
5
3
2
1
1
0
0
1
2
3
5
4
0
6
3
2
4
5
6
7
8
9
1
0
7
8
9
0
1
2
3
6
5
4
2
4
3
5
6
7
8
9
7
8
9
31
29
28
30
25
27
26
23
24
20
21
22
19
18
15
16
17
14
13
10
11
12
7
9
8
5
DQS7_A _c||TDQS7_A _c
DQS6_A _t||TDQS6_A _t
DQS8_B_t||TDQS8_B_t
DQS8_B_c||TDQS8_B_c
DQS7_B_t||TDQS7_B_t
DQS0_A _c
DQS0_A _t
DQS0_B_c
DQS0_B_t
DQS1_A _c
DQS1_A _t
DQS1_B_c
DQS1_B_t
DQS2_A _c
DQS2_A _t
DQS2_B_c
DQS2_B_t
DQS3_A _c
DQS3_A _t
DQS3_B_c
DQS3_B_t
DQS4_A _c
DQS4_A _t
DQS4_B_c
DQS4_B_t
DQS5_A _c||TDQS5_A _c||DQS5_A _t||TDQS5_A _t
DQS5_A _t||TDQS5_A _t
DQS5_B_c||TDQS5_B_c
DQS5_B_t||TDQS5_B_t
DQS6_A _c||TDQS6_A _c||DQS6_A _t||TDQS6_A _t
DQS6_B_c||TDQS6_B_c
DQS6_B_t||TDQS6_B_t
DQS7_A _t||TDQS7_A _t
DQS7_B_c||TDQS7_B_c
DQS8_A _c||TDQS8_A _c
DQS8_A _t||TDQS8_A _t
DQS9_A _c||TDQS9_A _c
DQS9_A _t||TDQS9_A _t
DQS9_B_c||TDQS9_B_c
DQS9_B_t||TDQS9_B_t||DBI4_B_n
21
93
94
201
200
283
282
190
189
272
271
179
178
261
260
168
167
250
249
157
156
239
238
55
56
137
138
44
45
126
127
33
34
115
116
22
23
104
105
11
12
288
286
284
281
279
277
275
273
270
268
266
264
262
259
257
255
253
251
248
246
244
242
240
237
235
233
230
228
226
224
222
219
216
214
212
210
208
206
204
202
199
197
195
193
191
188
186
184
182
180
177
175
173
171
169
166
164
162
160
158
155
153
151
143
141
139
136
134
132
130
128
125
123
121
119
117
114
112
110
108
106
103
101
99
97
95
92
90
88
85
83
81
79
77
75
73
71
69
67
65
63
61
59
57
54
52
50
48
46
43
41
39
37
35
32
30
28
26
24
21
19
17
15
13
10
8
6
146
145
1
G3
G2
G1
3
232
231
220
150
149
144
2
207
147
227
74
87
86
5
4
148
287
194
285
192
142
49
140
47
280
187
278
185
135
42
133
40
276
183
274
181
131
38
129
36
269
176
267
174
124
31
122
29
265
172
263
170
120
27
118
25
258
165
256
163
113
20
111
18
254
161
252
159
109
16
107
14
247
154
245
152
102
9
100
7
229
209
84
64
217
218
236
205
234
203
91
60
89
58
243
198
241
196
98
53
96
51
82
72
225
215
80
70
223
213
78
68
221
211
76
66
62
D8005
CA
2/3
1/3
PWR_GOOD||FAIL_n
DQ31_A
CB7_A
CB4_A
CB1_A
CB7_B
ALERT_n
CA0_A
CA0_B
CA1_A
CA1_B
CA2_A
CA2_B
CA3_A
CA3_B
CA4_A
CA4_B
CA5_A
CA5_B
CA6_A
CA6_B
CB6_A
CB5_A
CB3_A
CB2_A
CB0_A
CB6_B
CB5_B
CB4_B
CB3_B
CB2_B
CB1_B
CB0_B
CK_c
CK_t
CS0_A_n
CS0_B_n
CS1_A_n
CS1_B_n
DQ30_A
DQ29_A
DQ28_A
DQ27_A
DQ26_A
DQ25_A
DQ24_A
DQ23_A
DQ22_A
DQ21_A
DQ20_A
DQ19_A
DQ18_A
DQ17_A
DQ16_A
DQ15_A
DQ14_A
DQ13_A
DQ12_A
DQ11_A
DQ10_A
DQ9_A
DQ8_A
DQ7_A
DQ6_A
DQ5_A
DQ4_A
DQ3_A
DQ2_A
DQ1_A
DQ0_A
DQ31_B
DQ30_B
DQ29_B
DQ28_B
DQ27_B
DQ26_B
DQ25_B
DQ24_B
DQ23_B
DQ22_B
DQ21_B
DQ20_B
DQ19_B
DQ18_B
DQ17_B
DQ16_B
DQ15_B
DQ14_B
DQ13_B
DQ12_B
DQ11_B
DQ10_B
DQ9_B
DQ8_B
DQ7_B
DQ6_B
DQ5_B
DQ4_B
DQ3_B
DQ2_B
DQ1_B
DQ0_B
HAS
HSCL
HSDA
LBD||RSP_A_n
LBS||RSP_B_n
PAR_A
PAR_B
RESET_n
RFU6
RFU5
RFU4
RFU3
RFU2
RFU1
RFU0
VIN_MGMT
3/3
G3
G2
G1
VSS62
VSS61
VSS60
VSS58
VSS104
VSS102
VSS100
VIN_BULK2
VIN_BULK1
VIN_BULK0
VSS126
VSS125
VSS124
VSS123
VSS122
VSS121
VSS120
VSS119
VSS118
VSS117
VSS116
VSS115
VSS114
VSS113
VSS112
VSS111
VSS110
VSS109
VSS108
VSS107
VSS106
VSS105
VSS103
VSS101
VSS99
VSS98
VSS97
VSS96
VSS95
VSS94
VSS93
VSS92
VSS91
VSS90
VSS89
VSS88
VSS87
VSS86
VSS85
VSS84
VSS83
VSS82
VSS81
VSS80
VSS79
VSS78
VSS77
VSS76
VSS75
VSS74
VSS73
VSS72
VSS71
VSS70
VSS69
VSS68
VSS67
VSS66
VSS65
VSS64
VSS63
VSS59
VSS57
VSS56
VSS55
VSS54
VSS53
VSS52
VSS51
VSS50
VSS49
VSS48
VSS47
VSS46
VSS45
VSS44
VSS43
VSS42
VSS41
VSS40
VSS39
VSS38
VSS37
VSS36
VSS35
VSS34
VSS33
VSS32
VSS31
VSS30
VSS29
VSS28
VSS27
VSS26
VSS25
VSS24
VSS23
VSS22
VSS21
VSS20
VSS19
VSS18
VSS17
VSS16
VSS15
VSS14
VSS13
VSS12
VSS11
VSS10
VSS9
VSS8
VSS7
VSS6
VSS5
VSS4
VSS3
VSS2
VSS1
VSS0
21
21
21
21
2
1
21
1
SHEETDATE
23
7 3 2 16 5 4
E
A
B
C
E
D
C
B
A
7 6 5 4
D
DEPARTMENT
SIZE
PROJECT DOCUMENT NUMBER REV
REVIEWER
DESIGNER
IN
BI
OUT
IN
BI
BIBI
OUT
IN
IN
IN
OUT
OUT
OUT
OUT
OUTIN
BI
IN
IN
IN
IN
IN
IN
OUT
BI
IN
BI
BI
OUT
R8087
R8088
R8086
R8039
C



Thu Aug 24 14:08:56 2023<NAME_2>
<NAME_1>
MB FABCGTI V02
99 OF 365
P 3V 3
P 12V _ME M_CP U1
P 3V 3_A UX
15998100101102103
98100101
102103
159
99
38
38
38
38
38
38 38
38
38
38
38
38
98100101102103
38
38
38
38
38
38
38
99
38
38
38
1K
X 6S
C0805
10%
25V
10UF
25V
10UF
X 6S
10%
C0805
0402LF
1K
1/16W
E MP TY
1%
X 7R
10%
25V
0.1UF
0402
10
CHIP 0402LF
I3C_S P D_DDRA F_CP U1_S CL
P W RG D_CHB _CP U1_DIMM
I3C_SPD_DDRB_CPU1_SCL
I3C_S P D_DDRA F_CP U1_S DA
I3C_SPD_DDRB_CPU1_SDA
P D_CHB _CP U1_DIMM_S A A
M_B _CP U1_S B _RS P <0>
M_B _CP U1_S A _RS P <0>
M_B _CP U1_S A _CB <7:0>
0402LF
15.4K
1%
CHIP
1/16W
IO
S CO NN288_DDR506112002K Q
SMLF
IO
S CO NN288_DDR506112002K Q
SMLF
IO
SMLF
S CO NN288_DDR506112002K Q
DDR5 - CPU1 CHB
M_B _CP U1_S B _CB <7:0>
M_B _CP U1_S B _CA <6:0>
M_B _CP U1_S A _CA <6:0> M_B _CP U1_S A _DQ <31:0>
M_B _CP U1_S B _DQ <31:0>
M_B _CP U1_S A _DQ S _DN<9:0>
M_B _CP U1_S A _DQ S _DP <9:0>
M_B _CP U1_S B _DQ S _DP <9:0>
M_B _CP U1_S B _DQ S _DN<9:0>
P W RG D_CHA F_CP U1
M_B _CP U1_S B _P A R
M_B _CP U1_S A _P A R
M_B _CP U1_S B _CS _N<1>
M_B _CP U1_S A _CS _N<1>
M_B _CP U1_S B _CS _N<0>
M_B _CP U1_CLK _DP <0>
M_B _CP U1_CLK _DN<0>
P D_CHB _CP U1_DIMM_S A A
M_B _CP U1_S A _CS _N<0>
M_B _CP U1_RE S E T_N
M_B _CP U1_A LE RT_N
49.9
J26
J26
J26
R1581
2
1C177
2
1C175
2
1
R104
2 1R304
2
1C140
2
1
R770
7
12
11
10
9
8
17
16
13
15
14
21
22
19
20
18
23
24
25
28
27
26
30
29
31
2
9
8
7
6
5
8
9
7
5
6
4
3
0
1
8
9
7
6
3
4
2
1
0
8
9
7
6
5
5
4
3
2
1
0
0
3
4
2
0
1
2
4
3
5
7
6
0
1
2
3
5
4
6
1
0
2
3
4
5
7
6
9
8
13
14
12
11
10
15
17
16
18
19
20
23
24
25
22
21
28
30
29
27
26
31
1
2
0
7
0
1
2
3
5
4
0
6
1
2
3
4
5
6
3
4
5
6
1
R1696
DQS7_A _c||TDQS7_A _c
DQS6_A _t||TDQS6_A _t
DQS8_B_t||TDQS8_B_t
DQS8_B_c||TDQS8_B_c
DQS7_B_t||TDQS7_B_t
DQS0_A _c
DQS0_A _t
DQS0_B_c
DQS0_B_t
DQS1_A _c
DQS1_A _t
DQS1_B_c
DQS1_B_t
DQS2_A _c
DQS2_A _t
DQS2_B_c
DQS2_B_t
DQS3_A _c
DQS3_A _t
DQS3_B_c
DQS3_B_t
DQS4_A _c
DQS4_A _t
DQS4_B_c
DQS4_B_t
DQS5_A _c||TDQS5_A _c||DQS5_A _t||TDQS5_A _t
DQS5_A _t||TDQS5_A _t
DQS5_B_c||TDQS5_B_c
DQS5_B_t||TDQS5_B_t
DQS6_A _c||TDQS6_A _c||DQS6_A _t||TDQS6_A _t
DQS6_B_c||TDQS6_B_c
DQS6_B_t||TDQS6_B_t
DQS7_A _t||TDQS7_A _t
DQS7_B_c||TDQS7_B_c
DQS8_A _c||TDQS8_A _c
DQS8_A _t||TDQS8_A _t
DQS9_A _c||TDQS9_A _c
DQS9_A _t||TDQS9_A _t
DQS9_B_c||TDQS9_B_c
DQS9_B_t||TDQS9_B_t||DBI4_B_n 93
94
201
200
283
282
190
189
272
271
179
178
261
260
168
167
250
249
157
156
239
238
55
56
137
138
44
45
126
127
33
34
115
116
22
23
104
105
11
12
288
286
284
281
279
277
275
273
270
268
266
264
262
259
257
255
253
251
248
246
244
242
240
237
235
233
230
228
226
224
222
219
216
214
212
210
208
206
204
202
199
197
195
193
191
188
186
184
182
180
177
175
173
171
169
166
164
162
160
158
155
153
151
143
141
139
136
134
132
130
128
125
123
121
119
117
114
112
110
108
106
103
101
99
97
95
92
90
88
85
83
81
79
77
75
73
71
69
67
65
63
61
59
57
54
52
50
48
46
43
41
39
37
35
32
30
28
26
24
21
19
17
15
13
10
8
6
146
145
1
G3
G2
G1
3
232
231
220
150
149
144
2
207
147
227
74
87
86
5
4
148
287
194
285
192
142
49
140
47
280
187
278
185
135
42
133
40
276
183
274
181
131
38
129
36
269
176
267
174
124
31
122
29
265
172
263
170
120
27
118
25
258
165
256
163
113
20
111
18
254
161
252
159
109
16
107
14
247
154
245
152
102
9
100
7
229
209
84
64
217
218
236
205
234
203
91
60
89
58
243
198
241
196
98
53
96
51
82
72
225
215
80
70
223
213
78
68
221
211
76
66
62
2/3
1/3
PWR_GOOD||FAIL_n
DQ31_A
CB7_A
CB4_A
CB1_A
CB7_B
ALERT_n
CA0_A
CA0_B
CA1_A
CA1_B
CA2_A
CA2_B
CA3_A
CA3_B
CA4_A
CA4_B
CA5_A
CA5_B
CA6_A
CA6_B
CB6_A
CB5_A
CB3_A
CB2_A
CB0_A
CB6_B
CB5_B
CB4_B
CB3_B
CB2_B
CB1_B
CB0_B
CK_c
CK_t
CS0_A_n
CS0_B_n
CS1_A_n
CS1_B_n
DQ30_A
DQ29_A
DQ28_A
DQ27_A
DQ26_A
DQ25_A
DQ24_A
DQ23_A
DQ22_A
DQ21_A
DQ20_A
DQ19_A
DQ18_A
DQ17_A
DQ16_A
DQ15_A
DQ14_A
DQ13_A
DQ12_A
DQ11_A
DQ10_A
DQ9_A
DQ8_A
DQ7_A
DQ6_A
DQ5_A
DQ4_A
DQ3_A
DQ2_A
DQ1_A
DQ0_A
DQ31_B
DQ30_B
DQ29_B
DQ28_B
DQ27_B
DQ26_B
DQ25_B
DQ24_B
DQ23_B
DQ22_B
DQ21_B
DQ20_B
DQ19_B
DQ18_B
DQ17_B
DQ16_B
DQ15_B
DQ14_B
DQ13_B
DQ12_B
DQ11_B
DQ10_B
DQ9_B
DQ8_B
DQ7_B
DQ6_B
DQ5_B
DQ4_B
DQ3_B
DQ2_B
DQ1_B
DQ0_B
HAS
HSCL
HSDA
LBD||RSP_A_n
LBS||RSP_B_n
PAR_A
PAR_B
RESET_n
RFU6
RFU5
RFU4
RFU3
RFU2
RFU1
RFU0
VIN_MGMT
3/3
G3
G2
G1
VSS62
VSS61
VSS60
VSS58
VSS104
VSS102
VSS100
VIN_BULK2
VIN_BULK1
VIN_BULK0
VSS126
VSS125
VSS124
VSS123
VSS122
VSS121
VSS120
VSS119
VSS118
VSS117
VSS116
VSS115
VSS114
VSS113
VSS112
VSS111
VSS110
VSS109
VSS108
VSS107
VSS106
VSS105
VSS103
VSS101
VSS99
VSS98
VSS97
VSS96
VSS95
VSS94
VSS93
VSS92
VSS91
VSS90
VSS89
VSS88
VSS87
VSS86
VSS85
VSS84
VSS83
VSS82
VSS81
VSS80
VSS79
VSS78
VSS77
VSS76
VSS75
VSS74
VSS73
VSS72
VSS71
VSS70
VSS69
VSS68
VSS67
VSS66
VSS65
VSS64
VSS63
VSS59
VSS57
VSS56
VSS55
VSS54
VSS53
VSS52
VSS51
VSS50
VSS49
VSS48
VSS47
VSS46
VSS45
VSS44
VSS43
VSS42
VSS41
VSS40
VSS39
VSS38
VSS37
VSS36
VSS35
VSS34
VSS33
VSS32
VSS31
VSS30
VSS29
VSS28
VSS27
VSS26
VSS25
VSS24
VSS23
VSS22
VSS21
VSS20
VSS19
VSS18
VSS17
VSS16
VSS15
VSS14
VSS13
VSS12
VSS11
VSS10
VSS9
VSS8
VSS7
VSS6
VSS5
VSS4
VSS3
VSS2
VSS1
VSS0
21
21
1
SHEETDATE
23
7 3 2 16 5 4
E
A
B
C
E
D
C
B
A
7 6 5 4
D
DEPARTMENT
SIZE
PROJECT DOCUMENT NUMBER REV
REVIEWER
DESIGNER
OUT
BI
BI
OUT
BI
IN
IN
OUT
OUT
IN
IN
OUT
OUT
BI
BI
IN
IN
IN
IN
IN
IN
OUT
BI
IN
IN
IN
OUT
C



Thu Aug 24 14:08:56 2023<NAME_2>
<NAME_1>
MB FABCGTI V02
100 OF 365
P 3V 3
P 12V _ME M_CP U1
P 3V 3_A UX
M_C_CP U1_A LE RT_N
100
9899101
102103
159
1599899101102103
39
39
39
39
39
39
39
39
39
39
9899
101
102
103
100
39
39
39
39
39
39
39
39
39
39
39
39
1K
10%
10UF
25V
C0805
X 6SX 6S
10UF
C0805
10%
25V
1K
1/16W
0402LF
E MP TY
1%
25V
0.1UF
10%
0402
X 7R
CHIP 0402LF
10
P D_CHC_CP U1_DIMM_S A A
I3C_S P D_DDRA F_CP U1_S DA
I3C_SPD_DDRC_CPU1_SCL
I3C_SPD_DDRC_CPU1_SDA
I3C_S P D_DDRA F_CP U1_S CL
P W RG D_CHC_CP U1_DIMM
49.9
1/16W
CHIP
1%
23.2K
0402LF
S CO NN288_DDR506112002K Q
SMLF
IOIO
S CO NN288_DDR506112002K Q
SMLF
S CO NN288_DDR506112002K Q
IO
SMLF
DDR5 - CPU1 CHC
M_C_CP U1_S A _DQ <31:0>
M_C_CP U1_S A _CB <7:0>
M_C_CP U1_S B _CB <7:0>
M_C_CP U1_S A _CA <6:0>
M_C_CP U1_S B _CA <6:0>
M_C_CP U1_S B _DQ <31:0>
M_C_CP U1_S A _DQ S _DN<9:0>
M_C_CP U1_S A _DQ S _DP <9:0>
M_C_CP U1_S B _DQ S _DP <9:0>
M_C_CP U1_S B _DQ S _DN<9:0>
P W RG D_CHA F_CP U1
P D_CHC_CP U1_DIMM_S A A
M_C_CP U1_S B _P A R
M_C_CP U1_S A _P A R
M_C_CP U1_S B _RS P <0>
M_C_CP U1_S A _RS P <0>
M_C_CP U1_S B _CS _N<1>
M_C_CP U1_S B _CS _N<0>
M_C_CP U1_S A _CS _N<0>
M_C_CP U1_S A _CS _N<1>
M_C_CP U1_CLK _DP <0>
M_C_CP U1_CLK _DN<0>
M_C_CP U1_RE S E T_N
J28
J28J28
R1582
2
1C179
2
1C178
2
1
R105
2 1R305
2
1C144
2
1
R771
3
4
5
6
7
9
10
8
11
12
14
15
13
16
17
20
19
18
21
22
23
24
25
28
27
26
29
30
31
1
2
8
9
8
9
7
5
7
6
6
5
3
4
4
3
0
2
1
0
8
9
9
8
7
5
7
6
6
5
4
3
4
2
0
3
0
1
2
1
0
2
1
3
4
5
7
6
0
1
2
3
1
0
2
3
4
5
7
6
9
8
11
12
10
13
14
15
17
16
18
19
20
22
21
23
25
24
26
27
29
30
28
31
4
5
6
7
0
2
1
3
4
5
6
0
1
2
3
5
4
6
0
2
1
R1697
DQS7_A _c||TDQS7_A _c
DQS6_A _t||TDQS6_A _t
DQS8_B_t||TDQS8_B_t
DQS8_B_c||TDQS8_B_c
DQS7_B_t||TDQS7_B_t
DQS0_A _c
DQS0_A _t
DQS0_B_c
DQS0_B_t
DQS1_A _c
DQS1_A _t
DQS1_B_c
DQS1_B_t
DQS2_A _c
DQS2_A _t
DQS2_B_c
DQS2_B_t
DQS3_A _c
DQS3_A _t
DQS3_B_c
DQS3_B_t
DQS4_A _c
DQS4_A _t
DQS4_B_c
DQS4_B_t
DQS5_A _c||TDQS5_A _c||DQS5_A _t||TDQS5_A _t
DQS5_A _t||TDQS5_A _t
DQS5_B_c||TDQS5_B_c
DQS5_B_t||TDQS5_B_t
DQS6_A _c||TDQS6_A _c||DQS6_A _t||TDQS6_A _t
DQS6_B_c||TDQS6_B_c
DQS6_B_t||TDQS6_B_t
DQS7_A _t||TDQS7_A _t
DQS7_B_c||TDQS7_B_c
DQS8_A _c||TDQS8_A _c
DQS8_A _t||TDQS8_A _t
DQS9_A _c||TDQS9_A _c
DQS9_A _t||TDQS9_A _t
DQS9_B_c||TDQS9_B_c
DQS9_B_t||TDQS9_B_t||DBI4_B_n 93
94
201
200
283
282
190
189
272
271
179
178
261
260
168
167
250
249
157
156
239
238
55
56
137
138
44
45
126
127
33
34
115
116
22
23
104
105
11
12
288
286
284
281
279
277
275
273
270
268
266
264
262
259
257
255
253
251
248
246
244
242
240
237
235
233
230
228
226
224
222
219
216
214
212
210
208
206
204
202
199
197
195
193
191
188
186
184
182
180
177
175
173
171
169
166
164
162
160
158
155
153
151
143
141
139
136
134
132
130
128
125
123
121
119
117
114
112
110
108
106
103
101
99
97
95
92
90
88
85
83
81
79
77
75
73
71
69
67
65
63
61
59
57
54
52
50
48
46
43
41
39
37
35
32
30
28
26
24
21
19
17
15
13
10
8
6
146
145
1
G3
G2
G1
3
232
231
220
150
149
144
2
207
147
227
74
87
86
5
4
148
287
194
285
192
142
49
140
47
280
187
278
185
135
42
133
40
276
183
274
181
131
38
129
36
269
176
267
174
124
31
122
29
265
172
263
170
120
27
118
25
258
165
256
163
113
20
111
18
254
161
252
159
109
16
107
14
247
154
245
152
102
9
100
7
229
209
84
64
217
218
236
205
234
203
91
60
89
58
243
198
241
196
98
53
96
51
82
72
225
215
80
70
223
213
78
68
221
211
76
66
62
2/3
1/3
PWR_GOOD||FAIL_n
DQ31_A
CB7_A
CB4_A
CB1_A
CB7_B
ALERT_n
CA0_A
CA0_B
CA1_A
CA1_B
CA2_A
CA2_B
CA3_A
CA3_B
CA4_A
CA4_B
CA5_A
CA5_B
CA6_A
CA6_B
CB6_A
CB5_A
CB3_A
CB2_A
CB0_A
CB6_B
CB5_B
CB4_B
CB3_B
CB2_B
CB1_B
CB0_B
CK_c
CK_t
CS0_A_n
CS0_B_n
CS1_A_n
CS1_B_n
DQ30_A
DQ29_A
DQ28_A
DQ27_A
DQ26_A
DQ25_A
DQ24_A
DQ23_A
DQ22_A
DQ21_A
DQ20_A
DQ19_A
DQ18_A
DQ17_A
DQ16_A
DQ15_A
DQ14_A
DQ13_A
DQ12_A
DQ11_A
DQ10_A
DQ9_A
DQ8_A
DQ7_A
DQ6_A
DQ5_A
DQ4_A
DQ3_A
DQ2_A
DQ1_A
DQ0_A
DQ31_B
DQ30_B
DQ29_B
DQ28_B
DQ27_B
DQ26_B
DQ25_B
DQ24_B
DQ23_B
DQ22_B
DQ21_B
DQ20_B
DQ19_B
DQ18_B
DQ17_B
DQ16_B
DQ15_B
DQ14_B
DQ13_B
DQ12_B
DQ11_B
DQ10_B
DQ9_B
DQ8_B
DQ7_B
DQ6_B
DQ5_B
DQ4_B
DQ3_B
DQ2_B
DQ1_B
DQ0_B
HAS
HSCL
HSDA
LBD||RSP_A_n
LBS||RSP_B_n
PAR_A
PAR_B
RESET_n
RFU6
RFU5
RFU4
RFU3
RFU2
RFU1
RFU0
VIN_MGMT
3/3
G3
G2
G1
VSS62
VSS61
VSS60
VSS58
VSS104
VSS102
VSS100
VIN_BULK2
VIN_BULK1
VIN_BULK0
VSS126
VSS125
VSS124
VSS123
VSS122
VSS121
VSS120
VSS119
VSS118
VSS117
VSS116
VSS115
VSS114
VSS113
VSS112
VSS111
VSS110
VSS109
VSS108
VSS107
VSS106
VSS105
VSS103
VSS101
VSS99
VSS98
VSS97
VSS96
VSS95
VSS94
VSS93
VSS92
VSS91
VSS90
VSS89
VSS88
VSS87
VSS86
VSS85
VSS84
VSS83
VSS82
VSS81
VSS80
VSS79
VSS78
VSS77
VSS76
VSS75
VSS74
VSS73
VSS72
VSS71
VSS70
VSS69
VSS68
VSS67
VSS66
VSS65
VSS64
VSS63
VSS59
VSS57
VSS56
VSS55
VSS54
VSS53
VSS52
VSS51
VSS50
VSS49
VSS48
VSS47
VSS46
VSS45
VSS44
VSS43
VSS42
VSS41
VSS40
VSS39
VSS38
VSS37
VSS36
VSS35
VSS34
VSS33
VSS32
VSS31
VSS30
VSS29
VSS28
VSS27
VSS26
VSS25
VSS24
VSS23
VSS22
VSS21
VSS20
VSS19
VSS18
VSS17
VSS16
VSS15
VSS14
VSS13
VSS12
VSS11
VSS10
VSS9
VSS8
VSS7
VSS6
VSS5
VSS4
VSS3
VSS2
VSS1
VSS0
21
21
1
SHEETDATE
23
7 3 2 16 5 4
E
A
B
C
E
D
C
B
A
7 6 5 4
D
DEPARTMENT
SIZE
PROJECT DOCUMENT NUMBER REV
REVIEWER
DESIGNER
IN
IN
BI
OUT
BI
IN
IN
OUT
OUT
IN
OUT
OUT
OUTIN
BI
IN
IN
IN
IN
OUT
IN
IN
BI
IN
BI
BI
OUT
C



Thu Aug 24 14:08:56 2023<NAME_2>
<NAME_1>
MB FABCGTI V02
101 OF 365
P 3V 3
P 3V 3_A UX
P 12V _ME M_CP U1
101
9899100
102103
159
1599899100102103
40
40
40
101
40
40
40
40
40
40
40
40
40
40
9899
100
102
103
40
40
40
40
40
40
40
40
40
1K
0402
0.1UF
25V
X 7R
10%
1%
1K
0402LF
E MP TY
1/16W
C0805
25V
10UF
10%
X 6S
C0805
25V
10UF
10%
X 6S
10
0402LFCHIP
P D_CHD_CP U1_DIMM_S A A
I3C_S P D_DDRA F_CP U1_S DA
I3C_SPD_DDRD_CPU1_SDA
I3C_SPD_DDRD_CPU1_SCL
I3C_S P D_DDRA F_CP U1_S CL
M_D_CP U1_A LE RT_N
M_D_CP U1_RE S E T_N
M_D_CP U1_S B _CB <7:0>
49.9
P D_CHD_CP U1_DIMM_S A A
M_D_CP U1_CLK _DN<0>
M_D_CP U1_CLK _DP <0>
M_D_CP U1_S A _CS _N<0>
M_D_CP U1_S B _CS _N<0>
M_D_CP U1_S A _CS _N<1>
M_D_CP U1_S B _CS _N<1>
M_D_CP U1_S A _P A R
M_D_CP U1_S B _P A R
M_D_CP U1_S B _RS P <0>
M_D_CP U1_S A _RS P <0>
P W RG D_CHA F_CP U1
P W RG D_CHD_CP U1_DIMM
M_D_CP U1_S B _DQ S _DN<9:0>
M_D_CP U1_S B _DQ S _DP <9:0>
M_D_CP U1_S A _DQ S _DP <9:0>
M_D_CP U1_S A _DQ S _DN<9:0>
M_D_CP U1_S B _DQ <31:0>
M_D_CP U1_S A _DQ <31:0>
M_D_CP U1_S B _CA <6:0>
M_D_CP U1_S A _CA <6:0>
M_D_CP U1_S A _CB <7:0>
DDR5 - CPU1 CHD
SMLF
IO
S CO NN288_DDR506112002K Q
SMLF
S CO NN288_DDR506112002K Q
IO
SMLF
IO
S CO NN288_DDR506112002K Q
1/16W
CHIP
1%
35.7K
0402LF
J30
J30
J30
R1583
2
1C182
2
1C181
2
1
R106
2 1R306
2
1C148
2
1
R772
0
3
1
2
0
31
29
30
28
27
25
26
24
23
22
20
21
19
18
17
16
14
15
13
12
11
10
9
7
8
6
5
4
2
3
1
0
5
6
4
0
1
3
2
5
6
4
3
2
1
0
7
5
6
4
0
2
1
0
4
5
3
3
1
2
3
4
5
7
6
9
8
2
6
7
8
0
9
0
1
4
7
3
4
5
5
7
6
9
8
6
7
0
8
9
3
2
2
11
6
4
5
2
3
31
30
28
29
27
26
24
25
23
22
21
19
20
18
17
1
15
16
14
13
12
10
11
9
8
7
6
5
4
R1699
DQS7_A _c||TDQS7_A _c
DQS6_A _t||TDQS6_A _t
DQS8_B_t||TDQS8_B_t
DQS8_B_c||TDQS8_B_c
DQS7_B_t||TDQS7_B_t
DQS0_A _c
DQS0_A _t
DQS0_B_c
DQS0_B_t
DQS1_A _c
DQS1_A _t
DQS1_B_c
DQS1_B_t
DQS2_A _c
DQS2_A _t
DQS2_B_c
DQS2_B_t
DQS3_A _c
DQS3_A _t
DQS3_B_c
DQS3_B_t
DQS4_A _c
DQS4_A _t
DQS4_B_c
DQS4_B_t
DQS5_A _c||TDQS5_A _c||DQS5_A _t||TDQS5_A _t
DQS5_A _t||TDQS5_A _t
DQS5_B_c||TDQS5_B_c
DQS5_B_t||TDQS5_B_t
DQS6_A _c||TDQS6_A _c||DQS6_A _t||TDQS6_A _t
DQS6_B_c||TDQS6_B_c
DQS6_B_t||TDQS6_B_t
DQS7_A _t||TDQS7_A _t
DQS7_B_c||TDQS7_B_c
DQS8_A _c||TDQS8_A _c
DQS8_A _t||TDQS8_A _t
DQS9_A _c||TDQS9_A _c
DQS9_A _t||TDQS9_A _t
DQS9_B_c||TDQS9_B_c
DQS9_B_t||TDQS9_B_t||DBI4_B_n 93
94
201
200
283
282
190
189
272
271
179
178
261
260
168
167
250
249
157
156
239
238
55
56
137
138
44
45
126
127
33
34
115
116
22
23
104
105
11
12
288
286
284
281
279
277
275
273
270
268
266
264
262
259
257
255
253
251
248
246
244
242
240
237
235
233
230
228
226
224
222
219
216
214
212
210
208
206
204
202
199
197
195
193
191
188
186
184
182
180
177
175
173
171
169
166
164
162
160
158
155
153
151
143
141
139
136
134
132
130
128
125
123
121
119
117
114
112
110
108
106
103
101
99
97
95
92
90
88
85
83
81
79
77
75
73
71
69
67
65
63
61
59
57
54
52
50
48
46
43
41
39
37
35
32
30
28
26
24
21
19
17
15
13
10
8
6
146
145
1
G3
G2
G1
3
232
231
220
150
149
144
2
207
147
227
74
87
86
5
4
148
287
194
285
192
142
49
140
47
280
187
278
185
135
42
133
40
276
183
274
181
131
38
129
36
269
176
267
174
124
31
122
29
265
172
263
170
120
27
118
25
258
165
256
163
113
20
111
18
254
161
252
159
109
16
107
14
247
154
245
152
102
9
100
7
229
209
84
64
217
218
236
205
234
203
91
60
89
58
243
198
241
196
98
53
96
51
82
72
225
215
80
70
223
213
78
68
221
211
76
66
62
1/3
PWR_GOOD||FAIL_n
DQ31_A
CB7_A
CB4_A
CB1_A
CB7_B
ALERT_n
CA0_A
CA0_B
CA1_A
CA1_B
CA2_A
CA2_B
CA3_A
CA3_B
CA4_A
CA4_B
CA5_A
CA5_B
CA6_A
CA6_B
CB6_A
CB5_A
CB3_A
CB2_A
CB0_A
CB6_B
CB5_B
CB4_B
CB3_B
CB2_B
CB1_B
CB0_B
CK_c
CK_t
CS0_A_n
CS0_B_n
CS1_A_n
CS1_B_n
DQ30_A
DQ29_A
DQ28_A
DQ27_A
DQ26_A
DQ25_A
DQ24_A
DQ23_A
DQ22_A
DQ21_A
DQ20_A
DQ19_A
DQ18_A
DQ17_A
DQ16_A
DQ15_A
DQ14_A
DQ13_A
DQ12_A
DQ11_A
DQ10_A
DQ9_A
DQ8_A
DQ7_A
DQ6_A
DQ5_A
DQ4_A
DQ3_A
DQ2_A
DQ1_A
DQ0_A
DQ31_B
DQ30_B
DQ29_B
DQ28_B
DQ27_B
DQ26_B
DQ25_B
DQ24_B
DQ23_B
DQ22_B
DQ21_B
DQ20_B
DQ19_B
DQ18_B
DQ17_B
DQ16_B
DQ15_B
DQ14_B
DQ13_B
DQ12_B
DQ11_B
DQ10_B
DQ9_B
DQ8_B
DQ7_B
DQ6_B
DQ5_B
DQ4_B
DQ3_B
DQ2_B
DQ1_B
DQ0_B
HAS
HSCL
HSDA
LBD||RSP_A_n
LBS||RSP_B_n
PAR_A
PAR_B
RESET_n
RFU6
RFU5
RFU4
RFU3
RFU2
RFU1
RFU0
VIN_MGMT
2/3
3/3
G3
G2
G1
VSS62
VSS61
VSS60
VSS58
VSS104
VSS102
VSS100
VIN_BULK2
VIN_BULK1
VIN_BULK0
VSS126
VSS125
VSS124
VSS123
VSS122
VSS121
VSS120
VSS119
VSS118
VSS117
VSS116
VSS115
VSS114
VSS113
VSS112
VSS111
VSS110
VSS109
VSS108
VSS107
VSS106
VSS105
VSS103
VSS101
VSS99
VSS98
VSS97
VSS96
VSS95
VSS94
VSS93
VSS92
VSS91
VSS90
VSS89
VSS88
VSS87
VSS86
VSS85
VSS84
VSS83
VSS82
VSS81
VSS80
VSS79
VSS78
VSS77
VSS76
VSS75
VSS74
VSS73
VSS72
VSS71
VSS70
VSS69
VSS68
VSS67
VSS66
VSS65
VSS64
VSS63
VSS59
VSS57
VSS56
VSS55
VSS54
VSS53
VSS52
VSS51
VSS50
VSS49
VSS48
VSS47
VSS46
VSS45
VSS44
VSS43
VSS42
VSS41
VSS40
VSS39
VSS38
VSS37
VSS36
VSS35
VSS34
VSS33
VSS32
VSS31
VSS30
VSS29
VSS28
VSS27
VSS26
VSS25
VSS24
VSS23
VSS22
VSS21
VSS20
VSS19
VSS18
VSS17
VSS16
VSS15
VSS14
VSS13
VSS12
VSS11
VSS10
VSS9
VSS8
VSS7
VSS6
VSS5
VSS4
VSS3
VSS2
VSS1
VSS0
21
21
1
SHEETDATE
23
7 3 2 16 5 4
E
A
B
C
E
D
C
B
A
7 6 5 4
D
DEPARTMENT
SIZE
PROJECT DOCUMENT NUMBER REV
REVIEWER
DESIGNER
BI
OUT
IN
OUT
IN
IN
IN
IN
IN
IN
IN
IN
IN
IN
IN
BI
IN
OUT
OUT
OUT
OUT
OUT
BI
BI
BI
BI
OUT
C



Thu Aug 24 14:08:57 2023<NAME_2>
<NAME_1>
MB FABCGTI V02
102 OF 365
P 3V 3
P 3V 3_A UX
P 12V _ME M_CP U1
I3C_SPD_DDRE_CPU1_SCL
9899100
101103
159
1599899100101103
4141
41
41
41
41
41
41
98
99
100
101
103
102
41
41
41
41
41
41
41
41
41
41
41
41
41
41
102
1K
X 6S
C0805
10%
25V
10UF
X 6S
10%
10UF
25V
C0805
1K
1/16W
1%
E MP TY
0402LF
X 7R
10%
25V
0.1UF
0402
0402LFCHIP
10
I3C_S P D_DDRA F_CP U1_S DA
I3C_S P D_DDRA F_CP U1_S CL
49.9
I3C_SPD_DDRE_CPU1_SDA
P W RG D_CHE _CP U1_DIMM
1/16W
CHIP
1%
54.9K
0402LF
S CO NN288_DDR506112002K Q
IO
SMLF
S CO NN288_DDR506112002K Q
SMLF
IO
IO
S CO NN288_DDR506112002K Q
SMLF
DDR5 - CPU1 CHE
M_E _CP U1_S A _DQ <31:0>M_E _CP U1_S A _CA <6:0>
M_E _CP U1_S B _CA <6:0>
M_E _CP U1_S B _DQ <31:0>
M_E _CP U1_S A _DQ S _DN<9:0>
M_E _CP U1_S A _DQ S _DP <9:0>
M_E _CP U1_S B _DQ S _DP <9:0>
M_E _CP U1_S B _DQ S _DN<9:0>
P W RG D_CHA F_CP U1
P D_CHE _CP U1_DIMM_S A A
M_E _CP U1_S A _RS P <0>
M_E _CP U1_S B _P A R
M_E _CP U1_S A _P A R
M_E _CP U1_S B _RS P <0>
M_E _CP U1_S A _CS _N<1>
M_E _CP U1_S A _CS _N<0>
M_E _CP U1_S B _CS _N<1>
M_E _CP U1_S B _CS _N<0>
M_E _CP U1_CLK _DP <0>
M_E _CP U1_CLK _DN<0>
M_E _CP U1_S A _CB <7:0>
M_E _CP U1_S B _CB <7:0>
M_E _CP U1_A LE RT_N
M_E _CP U1_RE S E T_N
P D_CHE _CP U1_DIMM_S A A
J32
J32J32
R1584
2
1C509
2
1C183
2
1
R107
2 1R307
2
1C152
2
1
R6
7
8
9
11
10
14
13
12
15
16
0
17
18
19
20
21
23
22
24
27
26
1
25
28
29
31
30
2
3
4
5
6
0
7
0
2
8
9
2
6
7
5
9
8
7
6
5
4
3
1
1
0
4
3
2
1
8
9
6
7
3
9
8
7
6
5
3
5
4
1
2
4
4
3
2
1
0
0
5
6
7
1
0
2
3
4
6
5
0
1
2
3
4
5
6
2
3
0
1
4
5
6
7
8
9
10
11
13
12
15
14
16
18
19
17
21
20
22
24
23
26
25
27
29
28
30
31
1
0
2
3
4
6
5
R1701
DQS7_A _c||TDQS7_A _c
DQS6_A _t||TDQS6_A _t
DQS8_B_t||TDQS8_B_t
DQS8_B_c||TDQS8_B_c
DQS7_B_t||TDQS7_B_t
DQS0_A _c
DQS0_A _t
DQS0_B_c
DQS0_B_t
DQS1_A _c
DQS1_A _t
DQS1_B_c
DQS1_B_t
DQS2_A _c
DQS2_A _t
DQS2_B_c
DQS2_B_t
DQS3_A _c
DQS3_A _t
DQS3_B_c
DQS3_B_t
DQS4_A _c
DQS4_A _t
DQS4_B_c
DQS4_B_t
DQS5_A _c||TDQS5_A _c||DQS5_A _t||TDQS5_A _t
DQS5_A _t||TDQS5_A _t
DQS5_B_c||TDQS5_B_c
DQS5_B_t||TDQS5_B_t
DQS6_A _c||TDQS6_A _c||DQS6_A _t||TDQS6_A _t
DQS6_B_c||TDQS6_B_c
DQS6_B_t||TDQS6_B_t
DQS7_A _t||TDQS7_A _t
DQS7_B_c||TDQS7_B_c
DQS8_A _c||TDQS8_A _c
DQS8_A _t||TDQS8_A _t
DQS9_A _c||TDQS9_A _c
DQS9_A _t||TDQS9_A _t
DQS9_B_c||TDQS9_B_c
DQS9_B_t||TDQS9_B_t||DBI4_B_n 93
94
201
200
283
282
190
189
272
271
179
178
261
260
168
167
250
249
157
156
239
238
55
56
137
138
44
45
126
127
33
34
115
116
22
23
104
105
11
12
288
286
284
281
279
277
275
273
270
268
266
264
262
259
257
255
253
251
248
246
244
242
240
237
235
233
230
228
226
224
222
219
216
214
212
210
208
206
204
202
199
197
195
193
191
188
186
184
182
180
177
175
173
171
169
166
164
162
160
158
155
153
151
143
141
139
136
134
132
130
128
125
123
121
119
117
114
112
110
108
106
103
101
99
97
95
92
90
88
85
83
81
79
77
75
73
71
69
67
65
63
61
59
57
54
52
50
48
46
43
41
39
37
35
32
30
28
26
24
21
19
17
15
13
10
8
6
146
145
1
G3
G2
G1
3
232
231
220
150
149
144
2
207
147
227
74
87
86
5
4
148
287
194
285
192
142
49
140
47
280
187
278
185
135
42
133
40
276
183
274
181
131
38
129
36
269
176
267
174
124
31
122
29
265
172
263
170
120
27
118
25
258
165
256
163
113
20
111
18
254
161
252
159
109
16
107
14
247
154
245
152
102
9
100
7
229
209
84
64
217
218
236
205
234
203
91
60
89
58
243
198
241
196
98
53
96
51
82
72
225
215
80
70
223
213
78
68
221
211
76
66
62
1/3
PWR_GOOD||FAIL_n
DQ31_A
CB7_A
CB4_A
CB1_A
CB7_B
ALERT_n
CA0_A
CA0_B
CA1_A
CA1_B
CA2_A
CA2_B
CA3_A
CA3_B
CA4_A
CA4_B
CA5_A
CA5_B
CA6_A
CA6_B
CB6_A
CB5_A
CB3_A
CB2_A
CB0_A
CB6_B
CB5_B
CB4_B
CB3_B
CB2_B
CB1_B
CB0_B
CK_c
CK_t
CS0_A_n
CS0_B_n
CS1_A_n
CS1_B_n
DQ30_A
DQ29_A
DQ28_A
DQ27_A
DQ26_A
DQ25_A
DQ24_A
DQ23_A
DQ22_A
DQ21_A
DQ20_A
DQ19_A
DQ18_A
DQ17_A
DQ16_A
DQ15_A
DQ14_A
DQ13_A
DQ12_A
DQ11_A
DQ10_A
DQ9_A
DQ8_A
DQ7_A
DQ6_A
DQ5_A
DQ4_A
DQ3_A
DQ2_A
DQ1_A
DQ0_A
DQ31_B
DQ30_B
DQ29_B
DQ28_B
DQ27_B
DQ26_B
DQ25_B
DQ24_B
DQ23_B
DQ22_B
DQ21_B
DQ20_B
DQ19_B
DQ18_B
DQ17_B
DQ16_B
DQ15_B
DQ14_B
DQ13_B
DQ12_B
DQ11_B
DQ10_B
DQ9_B
DQ8_B
DQ7_B
DQ6_B
DQ5_B
DQ4_B
DQ3_B
DQ2_B
DQ1_B
DQ0_B
HAS
HSCL
HSDA
LBD||RSP_A_n
LBS||RSP_B_n
PAR_A
PAR_B
RESET_n
RFU6
RFU5
RFU4
RFU3
RFU2
RFU1
RFU0
VIN_MGMT
2/3
3/3
G3
G2
G1
VSS62
VSS61
VSS60
VSS58
VSS104
VSS102
VSS100
VIN_BULK2
VIN_BULK1
VIN_BULK0
VSS126
VSS125
VSS124
VSS123
VSS122
VSS121
VSS120
VSS119
VSS118
VSS117
VSS116
VSS115
VSS114
VSS113
VSS112
VSS111
VSS110
VSS109
VSS108
VSS107
VSS106
VSS105
VSS103
VSS101
VSS99
VSS98
VSS97
VSS96
VSS95
VSS94
VSS93
VSS92
VSS91
VSS90
VSS89
VSS88
VSS87
VSS86
VSS85
VSS84
VSS83
VSS82
VSS81
VSS80
VSS79
VSS78
VSS77
VSS76
VSS75
VSS74
VSS73
VSS72
VSS71
VSS70
VSS69
VSS68
VSS67
VSS66
VSS65
VSS64
VSS63
VSS59
VSS57
VSS56
VSS55
VSS54
VSS53
VSS52
VSS51
VSS50
VSS49
VSS48
VSS47
VSS46
VSS45
VSS44
VSS43
VSS42
VSS41
VSS40
VSS39
VSS38
VSS37
VSS36
VSS35
VSS34
VSS33
VSS32
VSS31
VSS30
VSS29
VSS28
VSS27
VSS26
VSS25
VSS24
VSS23
VSS22
VSS21
VSS20
VSS19
VSS18
VSS17
VSS16
VSS15
VSS14
VSS13
VSS12
VSS11
VSS10
VSS9
VSS8
VSS7
VSS6
VSS5
VSS4
VSS3
VSS2
VSS1
VSS0
21
21
1
SHEETDATE
23
7 3 2 16 5 4
E
A
B
C
E
D
C
B
A
7 6 5 4
D
DEPARTMENT
SIZE
PROJECT DOCUMENT NUMBER REV
REVIEWER
DESIGNER
BI
OUT
IN
IN
IN
IN
IN
IN
IN
IN
OUT
IN
IN
IN
IN
BI
BI
IN
OUT
OUT
OUT
OUT
OUT
BI
OUT
BI
BI
C



Thu Aug 24 14:08:57 2023<NAME_2>
<NAME_1>
MB FABCGTI V02
103 OF 365
P 3V 3
P 12V _ME M_CP U1
P 3V 3_A UX
1599899100101102
9899100
101102
159
103
42
42
42
42
42
42
42
42
42
42
9899
100
101
102
42
42
42
42
42
42
42
42
42
42
103
42
42
1K
X 6S
10%
10UF
25V
C0805
X 6S
10%
10UF
25V
C0805
1K
1%
1/16W
E MP TY
0402LF
10%
25V
X 7R
0.1UF
0402
10
CHIP 0402LF
I3C_S P D_DDRA F_CP U1_S CL
I3C_SPD_DDRF_CPU1_SCL
I3C_S P D_DDRA F_CP U1_S DA
I3C_SPD_DDRF_CPU1_SDA
P D_CHF_CP U1_DIMM_S A A
P W RG D_CHF_CP U1_DIMM
0402LF
84.5K
1%
CHIP
1/16W
IO
S CO NN288_DDR506112002K Q
SMLF
IO
S CO NN288_DDR506112002K Q
SMLF
SMLF
IO
S CO NN288_DDR506112002K Q
DDR5 - CPU1 CHF
M_F_CP U1_S A _DQ <31:0>
M_F_CP U1_S A _CB <7:0>
M_F_CP U1_S B _CB <7:0>
M_F_CP U1_S A _CA <6:0>
M_F_CP U1_S B _CA <6:0>
M_F_CP U1_S B _DQ <31:0>
M_F_CP U1_S A _DQ S _DN<9:0>
M_F_CP U1_S A _DQ S _DP <9:0>
M_F_CP U1_S B _DQ S _DP <9:0>
M_F_CP U1_S B _DQ S _DN<9:0>
P W RG D_CHA F_CP U1
M_F_CP U1_S B _RS P <0>
M_F_CP U1_S A _RS P <0>
M_F_CP U1_S B _P A R
M_F_CP U1_S A _P A R
M_F_CP U1_S B _CS _N<1>
M_F_CP U1_S A _CS _N<1>
M_F_CP U1_S B _CS _N<0>
M_F_CP U1_S A _CS _N<0>
M_F_CP U1_CLK _DP <0>
M_F_CP U1_CLK _DN<0>
P D_CHF_CP U1_DIMM_S A A
M_F_CP U1_RE S E T_N
M_F_CP U1_A LE RT_N
49.9
J33
J33
J33
R1585
2
1C527
2
1C518
2
1
R108
2 1R1183
2
1C156
2
1
R773
7
6
8
9
11
12
13
14
10
19
16
18
17
15
20
21
22
25
23
24
29
30
28
27
26
31
2
4
9
8
7
9
8
6
7
6
5
4
3
2
5
1
3
0
1
9
8
7
9
0
8
7
6
5
3
4
2
4
6
5
2
3
1
0
0
1
1
2
3
4
6
5
7
0
1
2
3
0
1
2
3
4
5
6
7
8
9
10
11
12
13
14
16
15
17
19
20
22
21
18
24
25
27
26
23
29
31
30
28
4
5
7
6
0
1
2
4
3
5
6
0
1
2
3
4
5
6
0
1
2
3
4
5
0
R1704
DQS7_A _c||TDQS7_A _c
DQS6_A _t||TDQS6_A _t
DQS8_B_t||TDQS8_B_t
DQS8_B_c||TDQS8_B_c
DQS7_B_t||TDQS7_B_t
DQS0_A _c
DQS0_A _t
DQS0_B_c
DQS0_B_t
DQS1_A _c
DQS1_A _t
DQS1_B_c
DQS1_B_t
DQS2_A _c
DQS2_A _t
DQS2_B_c
DQS2_B_t
DQS3_A _c
DQS3_A _t
DQS3_B_c
DQS3_B_t
DQS4_A _c
DQS4_A _t
DQS4_B_c
DQS4_B_t
DQS5_A _c||TDQS5_A _c||DQS5_A _t||TDQS5_A _t
DQS5_A _t||TDQS5_A _t
DQS5_B_c||TDQS5_B_c
DQS5_B_t||TDQS5_B_t
DQS6_A _c||TDQS6_A _c||DQS6_A _t||TDQS6_A _t
DQS6_B_c||TDQS6_B_c
DQS6_B_t||TDQS6_B_t
DQS7_A _t||TDQS7_A _t
DQS7_B_c||TDQS7_B_c
DQS8_A _c||TDQS8_A _c
DQS8_A _t||TDQS8_A _t
DQS9_A _c||TDQS9_A _c
DQS9_A _t||TDQS9_A _t
DQS9_B_c||TDQS9_B_c
DQS9_B_t||TDQS9_B_t||DBI4_B_n 93
94
201
200
283
282
190
189
272
271
179
178
261
260
168
167
250
249
157
156
239
238
55
56
137
138
44
45
126
127
33
34
115
116
22
23
104
105
11
12
288
286
284
281
279
277
275
273
270
268
266
264
262
259
257
255
253
251
248
246
244
242
240
237
235
233
230
228
226
224
222
219
216
214
212
210
208
206
204
202
199
197
195
193
191
188
186
184
182
180
177
175
173
171
169
166
164
162
160
158
155
153
151
143
141
139
136
134
132
130
128
125
123
121
119
117
114
112
110
108
106
103
101
99
97
95
92
90
88
85
83
81
79
77
75
73
71
69
67
65
63
61
59
57
54
52
50
48
46
43
41
39
37
35
32
30
28
26
24
21
19
17
15
13
10
8
6
146
145
1
G3
G2
G1
3
232
231
220
150
149
144
2
207
147
227
74
87
86
5
4
148
287
194
285
192
142
49
140
47
280
187
278
185
135
42
133
40
276
183
274
181
131
38
129
36
269
176
267
174
124
31
122
29
265
172
263
170
120
27
118
25
258
165
256
163
113
20
111
18
254
161
252
159
109
16
107
14
247
154
245
152
102
9
100
7
229
209
84
64
217
218
236
205
234
203
91
60
89
58
243
198
241
196
98
53
96
51
82
72
225
215
80
70
223
213
78
68
221
211
76
66
62
2/3
1/3
PWR_GOOD||FAIL_n
DQ31_A
CB7_A
CB4_A
CB1_A
CB7_B
ALERT_n
CA0_A
CA0_B
CA1_A
CA1_B
CA2_A
CA2_B
CA3_A
CA3_B
CA4_A
CA4_B
CA5_A
CA5_B
CA6_A
CA6_B
CB6_A
CB5_A
CB3_A
CB2_A
CB0_A
CB6_B
CB5_B
CB4_B
CB3_B
CB2_B
CB1_B
CB0_B
CK_c
CK_t
CS0_A_n
CS0_B_n
CS1_A_n
CS1_B_n
DQ30_A
DQ29_A
DQ28_A
DQ27_A
DQ26_A
DQ25_A
DQ24_A
DQ23_A
DQ22_A
DQ21_A
DQ20_A
DQ19_A
DQ18_A
DQ17_A
DQ16_A
DQ15_A
DQ14_A
DQ13_A
DQ12_A
DQ11_A
DQ10_A
DQ9_A
DQ8_A
DQ7_A
DQ6_A
DQ5_A
DQ4_A
DQ3_A
DQ2_A
DQ1_A
DQ0_A
DQ31_B
DQ30_B
DQ29_B
DQ28_B
DQ27_B
DQ26_B
DQ25_B
DQ24_B
DQ23_B
DQ22_B
DQ21_B
DQ20_B
DQ19_B
DQ18_B
DQ17_B
DQ16_B
DQ15_B
DQ14_B
DQ13_B
DQ12_B
DQ11_B
DQ10_B
DQ9_B
DQ8_B
DQ7_B
DQ6_B
DQ5_B
DQ4_B
DQ3_B
DQ2_B
DQ1_B
DQ0_B
HAS
HSCL
HSDA
LBD||RSP_A_n
LBS||RSP_B_n
PAR_A
PAR_B
RESET_n
RFU6
RFU5
RFU4
RFU3
RFU2
RFU1
RFU0
VIN_MGMT
3/3
G3
G2
G1
VSS62
VSS61
VSS60
VSS58
VSS104
VSS102
VSS100
VIN_BULK2
VIN_BULK1
VIN_BULK0
VSS126
VSS125
VSS124
VSS123
VSS122
VSS121
VSS120
VSS119
VSS118
VSS117
VSS116
VSS115
VSS114
VSS113
VSS112
VSS111
VSS110
VSS109
VSS108
VSS107
VSS106
VSS105
VSS103
VSS101
VSS99
VSS98
VSS97
VSS96
VSS95
VSS94
VSS93
VSS92
VSS91
VSS90
VSS89
VSS88
VSS87
VSS86
VSS85
VSS84
VSS83
VSS82
VSS81
VSS80
VSS79
VSS78
VSS77
VSS76
VSS75
VSS74
VSS73
VSS72
VSS71
VSS70
VSS69
VSS68
VSS67
VSS66
VSS65
VSS64
VSS63
VSS59
VSS57
VSS56
VSS55
VSS54
VSS53
VSS52
VSS51
VSS50
VSS49
VSS48
VSS47
VSS46
VSS45
VSS44
VSS43
VSS42
VSS41
VSS40
VSS39
VSS38
VSS37
VSS36
VSS35
VSS34
VSS33
VSS32
VSS31
VSS30
VSS29
VSS28
VSS27
VSS26
VSS25
VSS24
VSS23
VSS22
VSS21
VSS20
VSS19
VSS18
VSS17
VSS16
VSS15
VSS14
VSS13
VSS12
VSS11
VSS10
VSS9
VSS8
VSS7
VSS6
VSS5
VSS4
VSS3
VSS2
VSS1
VSS0
21
21
1
SHEETDATE
23
7 3 2 16 5 4
E
A
B
C
E
D
C
B
A
7 6 5 4
D
DEPARTMENT
SIZE
PROJECT DOCUMENT NUMBER REV
REVIEWER
DESIGNER
IN
IN
BI
OUT
BI
IN
IN
IN
OUT
OUT
OUT
OUT
OUTIN
BI
IN
IN
IN
IN
IN
IN
OUT
BI
IN
BI
BI
OUT
C



Thu Aug 24 14:08:57 2023<NAME_2>
<NAME_1>
MB FABCGTI V02
104 OF 365
P 3V 3
P 3V 3_A UX
P 3V 3_A UX
P 3V 3_A UX
P 3V 3_A UX
P 12V _ME M_CP U1
P 3V 3
104
105
106
107
108
109
159105106107108109
105106107108
109159
43
43
104
43
43
43
43
43
43
43
43
43
43
43
82104105106107108109
104
104 105 106 107 108 109
43
43
43
43
43
43
43
43
43
1K
1/16W
CHIP
0402LF
0.1UF
25V
10%
X 7R
0402
E MP TY
1/16W
1%
1K
0402LF
1%
0402LF
E MP TY
1/16W
1K
10UF
C0805
25V
10%
X 6S X 6S
C0805
25V
10UF
10%
0402LFCHIP
10
P W RG D_CHG L_CP U1
I3C_S P D_DDRG L_CP U1_S CL
I3C_SPD_DDRG_CPU1_SCL
I3C_S P D_DDRG L_CP U1_S DA
I3C_SPD_DDRG_CPU1_SDA
M_G _CP U1_A LE RT_N
M_G _CP U1_RE S E T_N
P D_CHG _CP U1_DIMM0_S A A
P W RG D_CHG _CP U1_DIMM0
49.9
M_G _CP U1_S B _CB <7:0>
M_G _CP U1_S B _P A R
M_G _CP U1_S A _P A R
M_G _CP U1_S B _RS P <0>
M_G _CP U1_S A _RS P <0>
M_G _CP U1_S B _CS _N<1>
M_G _CP U1_S A _CS _N<1>
M_G _CP U1_S B _CS _N<0>
M_G _CP U1_S A _CS _N<0>
M_G _CP U1_CLK _DP <0>
M_G _CP U1_CLK _DN<0>
PWRGD_CHGL_CPU1_R2PWRGD_CHGL_CPU1
P D_CHG _CP U1_DIMM0_S A A
PWRGD_CHGL_CPU1
PWRGD_CHGL_CPU1_R1
M_G _CP U1_S B _CA <6:0>
M_G _CP U1_S A _DQ <31:0>
M_G _CP U1_S B _DQ <31:0>
M_G _CP U1_S A _DQ S _DN<9:0>
M_G _CP U1_S A _DQ S _DP <9:0>
M_G _CP U1_S B _DQ S _DN<9:0>
M_G _CP U1_S B _DQ S _DP <9:0>
M_G _CP U1_S A _CA <6:0>
M_G _CP U1_S A _CB <7:0>
DDR5 - CPU1 CHG
B0530WS7F
SMLF
EMPTY
0402LFCHIP
5%0
1/16W
1/16W
1%10K
0402LFEMPTY
0 5%
0402LF1/16W CHIP
1%
0402LF
10K
CHIP
1/16W
S CO NN288_DDR506112002K Q
IO
SMLF
S CO NN288_DDR506112002K Q
SMLF
IO
SMLF
IO
S CO NN288_DDR506112002K Q
1%
10K
J102
J102
J102
R1586
2
1C531
2
1C530
2
1
R110
2
1
R109
2 1
R1184
2
1C160
2
1
R37
13
7
1
0
3
2
4
6
5
4
3
1
2
0
5
6
3
4
0
1
2
7
6
5
4
29
28
31
30
24
23
27
26
25
19
18
22
21
20
14
12
17
15
16
9
8
7
11
10
4
3
2
6
5
0
1
3
0
7
2
1
6
5
2
3
4
0
0
1
2
0
1
2
3
4
1
5
6
7
3
4
5
6
7
8
9
0
1
2
8
9
0
1
2
3
4
5
6
7
3
5
4
6
7
8
9
8
9
31
26
27
29
28
30
22
21
20
25
23
24
17
16
15
19
18
12
11
10
14
13
5
8
9
6
R1705
DQS7_A _c||TDQS7_A _c
DQS6_A _t||TDQS6_A _t
DQS8_B_t||TDQS8_B_t
DQS8_B_c||TDQS8_B_c
DQS7_B_t||TDQS7_B_t
DQS0_A _c
DQS0_A _t
DQS0_B_c
DQS0_B_t
DQS1_A _c
DQS1_A _t
DQS1_B_c
DQS1_B_t
DQS2_A _c
DQS2_A _t
DQS2_B_c
DQS2_B_t
DQS3_A _c
DQS3_A _t
DQS3_B_c
DQS3_B_t
DQS4_A _c
DQS4_A _t
DQS4_B_c
DQS4_B_t
DQS5_A _c||TDQS5_A _c||DQS5_A _t||TDQS5_A _t
DQS5_A _t||TDQS5_A _t
DQS5_B_c||TDQS5_B_c
DQS5_B_t||TDQS5_B_t
DQS6_A _c||TDQS6_A _c||DQS6_A _t||TDQS6_A _t
DQS6_B_c||TDQS6_B_c
DQS6_B_t||TDQS6_B_t
DQS7_A _t||TDQS7_A _t
DQS7_B_c||TDQS7_B_c
DQS8_A _c||TDQS8_A _c
DQS8_A _t||TDQS8_A _t
DQS9_A _c||TDQS9_A _c
DQS9_A _t||TDQS9_A _t
DQS9_B_c||TDQS9_B_c
DQS9_B_t||TDQS9_B_t||DBI4_B_n
21
93
94
201
200
283
282
190
189
272
271
179
178
261
260
168
167
250
249
157
156
239
238
55
56
137
138
44
45
126
127
33
34
115
116
22
23
104
105
11
12
288
286
284
281
279
277
275
273
270
268
266
264
262
259
257
255
253
251
248
246
244
242
240
237
235
233
230
228
226
224
222
219
216
214
212
210
208
206
204
202
199
197
195
193
191
188
186
184
182
180
177
175
173
171
169
166
164
162
160
158
155
153
151
143
141
139
136
134
132
130
128
125
123
121
119
117
114
112
110
108
106
103
101
99
97
95
92
90
88
85
83
81
79
77
75
73
71
69
67
65
63
61
59
57
54
52
50
48
46
43
41
39
37
35
32
30
28
26
24
21
19
17
15
13
10
8
6
146
145
1
G3
G2
G1
3
232
231
220
150
149
144
2
207
147
227
74
87
86
5
4
148
287
194
285
192
142
49
140
47
280
187
278
185
135
42
133
40
276
183
274
181
131
38
129
36
269
176
267
174
124
31
122
29
265
172
263
170
120
27
118
25
258
165
256
163
113
20
111
18
254
161
252
159
109
16
107
14
247
154
245
152
102
9
100
7
229
209
84
64
217
218
236
205
234
203
91
60
89
58
243
198
241
196
98
53
96
51
82
72
225
215
80
70
223
213
78
68
221
211
76
66
62
D8006
CA
2/3
1/3
PWR_GOOD||FAIL_n
DQ31_A
CB7_A
CB4_A
CB1_A
CB7_B
ALERT_n
CA0_A
CA0_B
CA1_A
CA1_B
CA2_A
CA2_B
CA3_A
CA3_B
CA4_A
CA4_B
CA5_A
CA5_B
CA6_A
CA6_B
CB6_A
CB5_A
CB3_A
CB2_A
CB0_A
CB6_B
CB5_B
CB4_B
CB3_B
CB2_B
CB1_B
CB0_B
CK_c
CK_t
CS0_A_n
CS0_B_n
CS1_A_n
CS1_B_n
DQ30_A
DQ29_A
DQ28_A
DQ27_A
DQ26_A
DQ25_A
DQ24_A
DQ23_A
DQ22_A
DQ21_A
DQ20_A
DQ19_A
DQ18_A
DQ17_A
DQ16_A
DQ15_A
DQ14_A
DQ13_A
DQ12_A
DQ11_A
DQ10_A
DQ9_A
DQ8_A
DQ7_A
DQ6_A
DQ5_A
DQ4_A
DQ3_A
DQ2_A
DQ1_A
DQ0_A
DQ31_B
DQ30_B
DQ29_B
DQ28_B
DQ27_B
DQ26_B
DQ25_B
DQ24_B
DQ23_B
DQ22_B
DQ21_B
DQ20_B
DQ19_B
DQ18_B
DQ17_B
DQ16_B
DQ15_B
DQ14_B
DQ13_B
DQ12_B
DQ11_B
DQ10_B
DQ9_B
DQ8_B
DQ7_B
DQ6_B
DQ5_B
DQ4_B
DQ3_B
DQ2_B
DQ1_B
DQ0_B
HAS
HSCL
HSDA
LBD||RSP_A_n
LBS||RSP_B_n
PAR_A
PAR_B
RESET_n
RFU6
RFU5
RFU4
RFU3
RFU2
RFU1
RFU0
VIN_MGMT
3/3
G3
G2
G1
VSS62
VSS61
VSS60
VSS58
VSS104
VSS102
VSS100
VIN_BULK2
VIN_BULK1
VIN_BULK0
VSS126
VSS125
VSS124
VSS123
VSS122
VSS121
VSS120
VSS119
VSS118
VSS117
VSS116
VSS115
VSS114
VSS113
VSS112
VSS111
VSS110
VSS109
VSS108
VSS107
VSS106
VSS105
VSS103
VSS101
VSS99
VSS98
VSS97
VSS96
VSS95
VSS94
VSS93
VSS92
VSS91
VSS90
VSS89
VSS88
VSS87
VSS86
VSS85
VSS84
VSS83
VSS82
VSS81
VSS80
VSS79
VSS78
VSS77
VSS76
VSS75
VSS74
VSS73
VSS72
VSS71
VSS70
VSS69
VSS68
VSS67
VSS66
VSS65
VSS64
VSS63
VSS59
VSS57
VSS56
VSS55
VSS54
VSS53
VSS52
VSS51
VSS50
VSS49
VSS48
VSS47
VSS46
VSS45
VSS44
VSS43
VSS42
VSS41
VSS40
VSS39
VSS38
VSS37
VSS36
VSS35
VSS34
VSS33
VSS32
VSS31
VSS30
VSS29
VSS28
VSS27
VSS26
VSS25
VSS24
VSS23
VSS22
VSS21
VSS20
VSS19
VSS18
VSS17
VSS16
VSS15
VSS14
VSS13
VSS12
VSS11
VSS10
VSS9
VSS8
VSS7
VSS6
VSS5
VSS4
VSS3
VSS2
VSS1
VSS0
21
21
21
21
2
1
21
1
SHEETDATE
23
7 3 2 16 5 4
E
A
B
C
E
D
C
B
A
7 6 5 4
D
DEPARTMENT
SIZE
PROJECT DOCUMENT NUMBER REV
REVIEWER
DESIGNER
IN
IN
BI
OUT
BI
BIBI
OUT
IN
IN
IN
OUT
OUT
OUT
OUT
OUT
IN
BI
IN
IN
IN
IN
IN
IN
OUT
BI
IN
BI
BI
OUT
R8090
R8091
R8089
R8040
C



Thu Aug 24 14:08:58 2023<NAME_2>
<NAME_1>
MB FABCGTI V02
105 OF 365
P 3V 3
P 12V _ME M_CP U1
P 3V 3_A UX
105
159104106107108109
104106107
108109159
44
44
44
44
44
44
44
44
44
44
104
106
107
108
109
44
44
44
44
44
44
44
44
44
105
44
44
44
1K
X 6S
10%
10UF
25V
C0805
X 6S
10%
10UF
25V
C0805
1K
0402LF
E MP TY
1/16W
1%
X 7R
10%
25V
0.1UF
0402
CHIP 0402LF
10
P D_CHH_CP U1_DIMM_S A A
I3C_SPD_DDRH_CPU1_SCL
I3C_S P D_DDRG L_CP U1_S CL
I3C_S P D_DDRG L_CP U1_S DA
I3C_SPD_DDRH_CPU1_SDA
P W RG D_CHH_CP U1_DIMM
0402LF
15.4K
1%
CHIP
1/16W
S CO NN288_DDR506112002K Q
IO
SMLF
IO
SMLF
S CO NN288_DDR506112002K Q
S CO NN288_DDR506112002K Q
IO
SMLF
DDR5 - CPU1 CHH
M_H_CP U1_S A _DQ <31:0>
M_H_CP U1_S A _CB <7:0>
M_H_CP U1_S A _CA <6:0>
M_H_CP U1_S B _CA <6:0>
M_H_CP U1_S B _CB <7:0>
M_H_CP U1_S B _DQ <31:0>
M_H_CP U1_S A _DQ S _DN<9:0>
M_H_CP U1_S A _DQ S _DP <9:0>
M_H_CP U1_S B _DQ S _DP <9:0>
M_H_CP U1_S B _DQ S _DN<9:0>
P W RG D_CHG L_CP U1
M_H_CP U1_S B _P A R
M_H_CP U1_S A _P A R
M_H_CP U1_S B _RS P <0>
M_H_CP U1_S A _RS P <0>
M_H_CP U1_S B _CS _N<1>
M_H_CP U1_S A _CS _N<1>
M_H_CP U1_S A _CS _N<0>
M_H_CP U1_CLK _DP <0>
M_H_CP U1_CLK _DN<0>
P D_CHH_CP U1_DIMM_S A A
M_H_CP U1_S B _CS _N<0>
M_H_CP U1_A LE RT_N
M_H_CP U1_RE S E T_N
49.9
J27
J27
J27
R1587
2
1C533
2
1C532
2
1
R111
2 1
R310
2
1C164
2
1
R774
7
8
9
11
10
12
13
14
16
15
18
17
19
21
20
22
23
25
24
26
29
28
27
30
31
2
3
4
5
9
8
9
8
7
6
5
4
1
0
8
9
7
6
3
2
1
0
9
8
7
6
5
3
4
2
1
0
2
7
6
5
4
3
2
1
0
3
1
0
4
5
6
7
0
1
2
3
4
0
2
3
1
4
5
6
7
8
9
10
11
13
12
14
15
16
17
18
19
20
21
22
23
24
25
26
27
28
29
31
30
0
7
6
5
3
2
1
0
4
5
6
1
0
2
3
4
6
5
1
2
3
6
4
5
R1707
DQS7_A _c||TDQS7_A _c
DQS6_A _t||TDQS6_A _t
DQS8_B_t||TDQS8_B_t
DQS8_B_c||TDQS8_B_c
DQS7_B_t||TDQS7_B_t
DQS0_A _c
DQS0_A _t
DQS0_B_c
DQS0_B_t
DQS1_A _c
DQS1_A _t
DQS1_B_c
DQS1_B_t
DQS2_A _c
DQS2_A _t
DQS2_B_c
DQS2_B_t
DQS3_A _c
DQS3_A _t
DQS3_B_c
DQS3_B_t
DQS4_A _c
DQS4_A _t
DQS4_B_c
DQS4_B_t
DQS5_A _c||TDQS5_A _c||DQS5_A _t||TDQS5_A _t
DQS5_A _t||TDQS5_A _t
DQS5_B_c||TDQS5_B_c
DQS5_B_t||TDQS5_B_t
DQS6_A _c||TDQS6_A _c||DQS6_A _t||TDQS6_A _t
DQS6_B_c||TDQS6_B_c
DQS6_B_t||TDQS6_B_t
DQS7_A _t||TDQS7_A _t
DQS7_B_c||TDQS7_B_c
DQS8_A _c||TDQS8_A _c
DQS8_A _t||TDQS8_A _t
DQS9_A _c||TDQS9_A _c
DQS9_A _t||TDQS9_A _t
DQS9_B_c||TDQS9_B_c
DQS9_B_t||TDQS9_B_t||DBI4_B_n 93
94
201
200
283
282
190
189
272
271
179
178
261
260
168
167
250
249
157
156
239
238
55
56
137
138
44
45
126
127
33
34
115
116
22
23
104
105
11
12
288
286
284
281
279
277
275
273
270
268
266
264
262
259
257
255
253
251
248
246
244
242
240
237
235
233
230
228
226
224
222
219
216
214
212
210
208
206
204
202
199
197
195
193
191
188
186
184
182
180
177
175
173
171
169
166
164
162
160
158
155
153
151
143
141
139
136
134
132
130
128
125
123
121
119
117
114
112
110
108
106
103
101
99
97
95
92
90
88
85
83
81
79
77
75
73
71
69
67
65
63
61
59
57
54
52
50
48
46
43
41
39
37
35
32
30
28
26
24
21
19
17
15
13
10
8
6
146
145
1
G3
G2
G1
3
232
231
220
150
149
144
2
207
147
227
74
87
86
5
4
148
287
194
285
192
142
49
140
47
280
187
278
185
135
42
133
40
276
183
274
181
131
38
129
36
269
176
267
174
124
31
122
29
265
172
263
170
120
27
118
25
258
165
256
163
113
20
111
18
254
161
252
159
109
16
107
14
247
154
245
152
102
9
100
7
229
209
84
64
217
218
236
205
234
203
91
60
89
58
243
198
241
196
98
53
96
51
82
72
225
215
80
70
223
213
78
68
221
211
76
66
62
2/3
1/3
PWR_GOOD||FAIL_n
DQ31_A
CB7_A
CB4_A
CB1_A
CB7_B
ALERT_n
CA0_A
CA0_B
CA1_A
CA1_B
CA2_A
CA2_B
CA3_A
CA3_B
CA4_A
CA4_B
CA5_A
CA5_B
CA6_A
CA6_B
CB6_A
CB5_A
CB3_A
CB2_A
CB0_A
CB6_B
CB5_B
CB4_B
CB3_B
CB2_B
CB1_B
CB0_B
CK_c
CK_t
CS0_A_n
CS0_B_n
CS1_A_n
CS1_B_n
DQ30_A
DQ29_A
DQ28_A
DQ27_A
DQ26_A
DQ25_A
DQ24_A
DQ23_A
DQ22_A
DQ21_A
DQ20_A
DQ19_A
DQ18_A
DQ17_A
DQ16_A
DQ15_A
DQ14_A
DQ13_A
DQ12_A
DQ11_A
DQ10_A
DQ9_A
DQ8_A
DQ7_A
DQ6_A
DQ5_A
DQ4_A
DQ3_A
DQ2_A
DQ1_A
DQ0_A
DQ31_B
DQ30_B
DQ29_B
DQ28_B
DQ27_B
DQ26_B
DQ25_B
DQ24_B
DQ23_B
DQ22_B
DQ21_B
DQ20_B
DQ19_B
DQ18_B
DQ17_B
DQ16_B
DQ15_B
DQ14_B
DQ13_B
DQ12_B
DQ11_B
DQ10_B
DQ9_B
DQ8_B
DQ7_B
DQ6_B
DQ5_B
DQ4_B
DQ3_B
DQ2_B
DQ1_B
DQ0_B
HAS
HSCL
HSDA
LBD||RSP_A_n
LBS||RSP_B_n
PAR_A
PAR_B
RESET_n
RFU6
RFU5
RFU4
RFU3
RFU2
RFU1
RFU0
VIN_MGMT
3/3
G3
G2
G1
VSS62
VSS61
VSS60
VSS58
VSS104
VSS102
VSS100
VIN_BULK2
VIN_BULK1
VIN_BULK0
VSS126
VSS125
VSS124
VSS123
VSS122
VSS121
VSS120
VSS119
VSS118
VSS117
VSS116
VSS115
VSS114
VSS113
VSS112
VSS111
VSS110
VSS109
VSS108
VSS107
VSS106
VSS105
VSS103
VSS101
VSS99
VSS98
VSS97
VSS96
VSS95
VSS94
VSS93
VSS92
VSS91
VSS90
VSS89
VSS88
VSS87
VSS86
VSS85
VSS84
VSS83
VSS82
VSS81
VSS80
VSS79
VSS78
VSS77
VSS76
VSS75
VSS74
VSS73
VSS72
VSS71
VSS70
VSS69
VSS68
VSS67
VSS66
VSS65
VSS64
VSS63
VSS59
VSS57
VSS56
VSS55
VSS54
VSS53
VSS52
VSS51
VSS50
VSS49
VSS48
VSS47
VSS46
VSS45
VSS44
VSS43
VSS42
VSS41
VSS40
VSS39
VSS38
VSS37
VSS36
VSS35
VSS34
VSS33
VSS32
VSS31
VSS30
VSS29
VSS28
VSS27
VSS26
VSS25
VSS24
VSS23
VSS22
VSS21
VSS20
VSS19
VSS18
VSS17
VSS16
VSS15
VSS14
VSS13
VSS12
VSS11
VSS10
VSS9
VSS8
VSS7
VSS6
VSS5
VSS4
VSS3
VSS2
VSS1
VSS0
21
21
1
SHEETDATE
23
7 3 2 16 5 4
E
A
B
C
E
D
C
B
A
7 6 5 4
D
DEPARTMENT
SIZE
PROJECT DOCUMENT NUMBER REV
REVIEWER
DESIGNER
IN
BI
OUT
IN
BI
IN
IN
OUT
OUT
IN
OUT
OUT
OUT
IN
BI
IN
IN
IN
IN
IN
IN
OUT
BI
BI
IN
BI
OUT
C



Thu Aug 24 14:08:58 2023<NAME_2>
<NAME_1>
MB FABCGTI V02
106 OF 365
P 3V 3
P 12V _ME M_CP U1
P 3V 3_A UX
106
159104105107108109
104105107
108109159
45
45
45
45
45
45
45
45
45
104
105
107
108
109
45
45
106
45
45
45
45
45
45
45
45
45
45
45
1K
X 6S
10%
10UF
25V
C0805
X 6S
10%
25V
C0805
10UF
0402LF
1K
1%
1/16W
E MP TY
0402
25V
0.1UF
X 7R
10%
10
0402LFCHIP
P D_CHI_CP U1_DIMM_S A A
I3C_S P D_DDRG L_CP U1_S CL
P W RG D_CHI_CP U1_DIMM
I3C_S P D_DDRG L_CP U1_S DA
49.9
I3C_SPD_DDRI_CPU1_SCL
I3C_SPD_DDRI_CPU1_SDA
1/16W
CHIP
1%
23.2K
0402LF
S CO NN288_DDR506112002K Q
IO
SMLF
S CO NN288_DDR506112002K Q
IO
SMLF
SMLF
S CO NN288_DDR506112002K Q
IO
DDR5 - CPU1 CHI
M_I_CP U1_S A _CB <7:0>
M_I_CP U1_S A _CA <6:0>
M_I_CP U1_S B _CA <6:0>
M_I_CP U1_S A _DQ <31:0>
M_I_CP U1_S B _DQ <31:0>
M_I_CP U1_S A _DQ S _DN<9:0>
M_I_CP U1_S A _DQ S _DP <9:0>
M_I_CP U1_S B _DQ S _DP <9:0>
M_I_CP U1_S B _DQ S _DN<9:0>
P W RG D_CHG L_CP U1
M_I_CP U1_S A _RS P <0>
M_I_CP U1_S B _RS P <0>
P D_CHI_CP U1_DIMM_S A A
M_I_CP U1_S B _P A R
M_I_CP U1_S A _P A R
M_I_CP U1_S B _CS _N<1>
M_I_CP U1_S A _CS _N<1>
M_I_CP U1_S B _CS _N<0>
M_I_CP U1_S A _CS _N<0>
M_I_CP U1_CLK _DP <0>
M_I_CP U1_CLK _DN<0>
M_I_CP U1_S B _CB <7:0>
M_I_CP U1_RE S E T_N
M_I_CP U1_A LE RT_N
J100
J100
J100
R1588
2
1C535
2
1C534
2
1
R112
2 1
R311
2
1C168
2
1
R775
7
10
9
8
11
12
13
14
15
17
16
20
19
18
22
21
25
24
23
27
28
26
30
29
31
7
9
0
1
3
9
9
8
8
7
6
5
4
2
3
7
6
4
5
2
1
0
8
9
8
6
5
4
3
2
1
0
7
6
0
5
3
4
2
1
0
1
2
3
4
5
6
7
0
1
3
2
0
2
1
4
3
5
6
7
9
8
10
12
11
14
13
15
17
16
20
19
18
21
22
25
24
23
26
27
30
29
28
31
4
5
6
7
0
1
2
3
4
5
6
0
1
2
3
4
5
6
0
2
1
3
4
5
6
R1708
DQS7_A _c||TDQS7_A _c
DQS6_A _t||TDQS6_A _t
DQS8_B_t||TDQS8_B_t
DQS8_B_c||TDQS8_B_c
DQS7_B_t||TDQS7_B_t
DQS0_A _c
DQS0_A _t
DQS0_B_c
DQS0_B_t
DQS1_A _c
DQS1_A _t
DQS1_B_c
DQS1_B_t
DQS2_A _c
DQS2_A _t
DQS2_B_c
DQS2_B_t
DQS3_A _c
DQS3_A _t
DQS3_B_c
DQS3_B_t
DQS4_A _c
DQS4_A _t
DQS4_B_c
DQS4_B_t
DQS5_A _c||TDQS5_A _c||DQS5_A _t||TDQS5_A _t
DQS5_A _t||TDQS5_A _t
DQS5_B_c||TDQS5_B_c
DQS5_B_t||TDQS5_B_t
DQS6_A _c||TDQS6_A _c||DQS6_A _t||TDQS6_A _t
DQS6_B_c||TDQS6_B_c
DQS6_B_t||TDQS6_B_t
DQS7_A _t||TDQS7_A _t
DQS7_B_c||TDQS7_B_c
DQS8_A _c||TDQS8_A _c
DQS8_A _t||TDQS8_A _t
DQS9_A _c||TDQS9_A _c
DQS9_A _t||TDQS9_A _t
DQS9_B_c||TDQS9_B_c
DQS9_B_t||TDQS9_B_t||DBI4_B_n 93
94
201
200
283
282
190
189
272
271
179
178
261
260
168
167
250
249
157
156
239
238
55
56
137
138
44
45
126
127
33
34
115
116
22
23
104
105
11
12
288
286
284
281
279
277
275
273
270
268
266
264
262
259
257
255
253
251
248
246
244
242
240
237
235
233
230
228
226
224
222
219
216
214
212
210
208
206
204
202
199
197
195
193
191
188
186
184
182
180
177
175
173
171
169
166
164
162
160
158
155
153
151
143
141
139
136
134
132
130
128
125
123
121
119
117
114
112
110
108
106
103
101
99
97
95
92
90
88
85
83
81
79
77
75
73
71
69
67
65
63
61
59
57
54
52
50
48
46
43
41
39
37
35
32
30
28
26
24
21
19
17
15
13
10
8
6
146
145
1
G3
G2
G1
3
232
231
220
150
149
144
2
207
147
227
74
87
86
5
4
148
287
194
285
192
142
49
140
47
280
187
278
185
135
42
133
40
276
183
274
181
131
38
129
36
269
176
267
174
124
31
122
29
265
172
263
170
120
27
118
25
258
165
256
163
113
20
111
18
254
161
252
159
109
16
107
14
247
154
245
152
102
9
100
7
229
209
84
64
217
218
236
205
234
203
91
60
89
58
243
198
241
196
98
53
96
51
82
72
225
215
80
70
223
213
78
68
221
211
76
66
62
2/3
1/3
PWR_GOOD||FAIL_n
DQ31_A
CB7_A
CB4_A
CB1_A
CB7_B
ALERT_n
CA0_A
CA0_B
CA1_A
CA1_B
CA2_A
CA2_B
CA3_A
CA3_B
CA4_A
CA4_B
CA5_A
CA5_B
CA6_A
CA6_B
CB6_A
CB5_A
CB3_A
CB2_A
CB0_A
CB6_B
CB5_B
CB4_B
CB3_B
CB2_B
CB1_B
CB0_B
CK_c
CK_t
CS0_A_n
CS0_B_n
CS1_A_n
CS1_B_n
DQ30_A
DQ29_A
DQ28_A
DQ27_A
DQ26_A
DQ25_A
DQ24_A
DQ23_A
DQ22_A
DQ21_A
DQ20_A
DQ19_A
DQ18_A
DQ17_A
DQ16_A
DQ15_A
DQ14_A
DQ13_A
DQ12_A
DQ11_A
DQ10_A
DQ9_A
DQ8_A
DQ7_A
DQ6_A
DQ5_A
DQ4_A
DQ3_A
DQ2_A
DQ1_A
DQ0_A
DQ31_B
DQ30_B
DQ29_B
DQ28_B
DQ27_B
DQ26_B
DQ25_B
DQ24_B
DQ23_B
DQ22_B
DQ21_B
DQ20_B
DQ19_B
DQ18_B
DQ17_B
DQ16_B
DQ15_B
DQ14_B
DQ13_B
DQ12_B
DQ11_B
DQ10_B
DQ9_B
DQ8_B
DQ7_B
DQ6_B
DQ5_B
DQ4_B
DQ3_B
DQ2_B
DQ1_B
DQ0_B
HAS
HSCL
HSDA
LBD||RSP_A_n
LBS||RSP_B_n
PAR_A
PAR_B
RESET_n
RFU6
RFU5
RFU4
RFU3
RFU2
RFU1
RFU0
VIN_MGMT
3/3
G3
G2
G1
VSS62
VSS61
VSS60
VSS58
VSS104
VSS102
VSS100
VIN_BULK2
VIN_BULK1
VIN_BULK0
VSS126
VSS125
VSS124
VSS123
VSS122
VSS121
VSS120
VSS119
VSS118
VSS117
VSS116
VSS115
VSS114
VSS113
VSS112
VSS111
VSS110
VSS109
VSS108
VSS107
VSS106
VSS105
VSS103
VSS101
VSS99
VSS98
VSS97
VSS96
VSS95
VSS94
VSS93
VSS92
VSS91
VSS90
VSS89
VSS88
VSS87
VSS86
VSS85
VSS84
VSS83
VSS82
VSS81
VSS80
VSS79
VSS78
VSS77
VSS76
VSS75
VSS74
VSS73
VSS72
VSS71
VSS70
VSS69
VSS68
VSS67
VSS66
VSS65
VSS64
VSS63
VSS59
VSS57
VSS56
VSS55
VSS54
VSS53
VSS52
VSS51
VSS50
VSS49
VSS48
VSS47
VSS46
VSS45
VSS44
VSS43
VSS42
VSS41
VSS40
VSS39
VSS38
VSS37
VSS36
VSS35
VSS34
VSS33
VSS32
VSS31
VSS30
VSS29
VSS28
VSS27
VSS26
VSS25
VSS24
VSS23
VSS22
VSS21
VSS20
VSS19
VSS18
VSS17
VSS16
VSS15
VSS14
VSS13
VSS12
VSS11
VSS10
VSS9
VSS8
VSS7
VSS6
VSS5
VSS4
VSS3
VSS2
VSS1
VSS0
21
21
1
SHEETDATE
23
7 3 2 16 5 4
E
A
B
C
E
D
C
B
A
7 6 5 4
D
DEPARTMENT
SIZE
PROJECT DOCUMENT NUMBER REV
REVIEWER
DESIGNER
IN
BI
OUT
IN
BI
IN
IN
OUT
IN
OUT
OUT
OUT
OUT
IN
BI
IN
IN
IN
IN
IN
IN
OUT
BI
IN
BI
BI
OUT
C



Thu Aug 24 14:08:59 2023<NAME_2>
<NAME_1>
MB FABCGTI V02
107 OF 365
P 3V 3_A UX
P 12V _ME M_CP U1
P 3V 3
M_J_CP U1_A LE RT_N
107
104105106108
109159
159104105106108109
46
46
46
46
46
46
46
46
46
46
46
107
46
104105
106108
109
46
46
46
46 46
46
46
46
46
46
1K
25V
0402
10%
0.1UF
X 7R
1%
1K
E MP TY
0402LF
1/16W
C0805
25V
10UF
10%
X 6S
C0805
25V
10UF
10%
X 6S
10
CHIP 0402LF
P D_CHJ_CP U1_DIMM_S A A
I3C_S P D_DDRG L_CP U1_S DA
I3C_SPD_DDRJ_CPU1_SDA
I3C_SPD_DDRJ_CPU1_SCL
I3C_S P D_DDRG L_CP U1_S CL
P W RG D_CHJ_CP U1_DIMM
M_J_CP U1_S A _CS _N<0>
49.9
M_J_CP U1_RE S E T_N
M_J_CP U1_S B _P A R
M_J_CP U1_S A _P A R
M_J_CP U1_S B _RS P <0>
M_J_CP U1_S B _CS _N<1>
M_J_CP U1_S A _CS _N<1>
M_J_CP U1_S B _CS _N<0>
M_J_CP U1_CLK _DP <0>
M_J_CP U1_CLK _DN<0>
P D_CHJ_CP U1_DIMM_S A A
M_J_CP U1_S A _RS P <0>
P W RG D_CHG L_CP U1
M_J_CP U1_S B _CA <6:0>
M_J_CP U1_S A _CB <7:0>
M_J_CP U1_S B _CB <7:0>
M_J_CP U1_S A _CA <6:0> M_J_CP U1_S A _DQ <31:0>
M_J_CP U1_S B _DQ S _DN<9:0>
M_J_CP U1_S B _DQ S _DP <9:0>
M_J_CP U1_S A _DQ S _DN<9:0>
M_J_CP U1_S A _DQ S _DP <9:0>
M_J_CP U1_S B _DQ <31:0>
DDR5 - CPU1 CHJ
S CO NN288_DDR506112002K Q
SMLF
IO
SMLF
S CO NN288_DDR506112002K Q
IO
SMLF
S CO NN288_DDR506112002K Q
IO
1/16W
CHIP
1%
35.7K
0402LF
J29
J29
J29
R1709
R1589
2
1C537
2
1C536
2
1
R113
2 1
R312
2
1C172
2
1
R776
6
5
4
3
2
6
5
4
3
2
1
0
6
5
3
4
1
2
0
7
6
1
0
30
31
28
29
27
26
25
23
24
22
21
20
19
18
17
15
16
14
13
12
10
11
9
7
8
5
6
4
3
2
1
0
4
5
3
2
1
0
7
6
5
3
4
2
1
0
1
3
2
4
5
0
6
7
8
0
1
2
3
4
6
5
7
8
0
9
1
2
4
3
5
6
7
9
0
2
1
3
4
5
7
6
8
8
9
9
31
29
30
28
27
26
25
24
23
22
21
20
19
18
17
16
15
14
13
11
12
10
9
8
7
DQS7_A _c||TDQS7_A _c
DQS6_A _t||TDQS6_A _t
DQS8_B_t||TDQS8_B_t
DQS8_B_c||TDQS8_B_c
DQS7_B_t||TDQS7_B_t
DQS0_A _c
DQS0_A _t
DQS0_B_c
DQS0_B_t
DQS1_A _c
DQS1_A _t
DQS1_B_c
DQS1_B_t
DQS2_A _c
DQS2_A _t
DQS2_B_c
DQS2_B_t
DQS3_A _c
DQS3_A _t
DQS3_B_c
DQS3_B_t
DQS4_A _c
DQS4_A _t
DQS4_B_c
DQS4_B_t
DQS5_A _c||TDQS5_A _c||DQS5_A _t||TDQS5_A _t
DQS5_A _t||TDQS5_A _t
DQS5_B_c||TDQS5_B_c
DQS5_B_t||TDQS5_B_t
DQS6_A _c||TDQS6_A _c||DQS6_A _t||TDQS6_A _t
DQS6_B_c||TDQS6_B_c
DQS6_B_t||TDQS6_B_t
DQS7_A _t||TDQS7_A _t
DQS7_B_c||TDQS7_B_c
DQS8_A _c||TDQS8_A _c
DQS8_A _t||TDQS8_A _t
DQS9_A _c||TDQS9_A _c
DQS9_A _t||TDQS9_A _t
DQS9_B_c||TDQS9_B_c
DQS9_B_t||TDQS9_B_t||DBI4_B_n 93
94
201
200
283
282
190
189
272
271
179
178
261
260
168
167
250
249
157
156
239
238
55
56
137
138
44
45
126
127
33
34
115
116
22
23
104
105
11
12
288
286
284
281
279
277
275
273
270
268
266
264
262
259
257
255
253
251
248
246
244
242
240
237
235
233
230
228
226
224
222
219
216
214
212
210
208
206
204
202
199
197
195
193
191
188
186
184
182
180
177
175
173
171
169
166
164
162
160
158
155
153
151
143
141
139
136
134
132
130
128
125
123
121
119
117
114
112
110
108
106
103
101
99
97
95
92
90
88
85
83
81
79
77
75
73
71
69
67
65
63
61
59
57
54
52
50
48
46
43
41
39
37
35
32
30
28
26
24
21
19
17
15
13
10
8
6
146
145
1
G3
G2
G1
3
232
231
220
150
149
144
2
207
147
227
74
87
86
5
4
148
287
194
285
192
142
49
140
47
280
187
278
185
135
42
133
40
276
183
274
181
131
38
129
36
269
176
267
174
124
31
122
29
265
172
263
170
120
27
118
25
258
165
256
163
113
20
111
18
254
161
252
159
109
16
107
14
247
154
245
152
102
9
100
7
229
209
84
64
217
218
236
205
234
203
91
60
89
58
243
198
241
196
98
53
96
51
82
72
225
215
80
70
223
213
78
68
221
211
76
66
62
2/3
1/3
PWR_GOOD||FAIL_n
DQ31_A
CB7_A
CB4_A
CB1_A
CB7_B
ALERT_n
CA0_A
CA0_B
CA1_A
CA1_B
CA2_A
CA2_B
CA3_A
CA3_B
CA4_A
CA4_B
CA5_A
CA5_B
CA6_A
CA6_B
CB6_A
CB5_A
CB3_A
CB2_A
CB0_A
CB6_B
CB5_B
CB4_B
CB3_B
CB2_B
CB1_B
CB0_B
CK_c
CK_t
CS0_A_n
CS0_B_n
CS1_A_n
CS1_B_n
DQ30_A
DQ29_A
DQ28_A
DQ27_A
DQ26_A
DQ25_A
DQ24_A
DQ23_A
DQ22_A
DQ21_A
DQ20_A
DQ19_A
DQ18_A
DQ17_A
DQ16_A
DQ15_A
DQ14_A
DQ13_A
DQ12_A
DQ11_A
DQ10_A
DQ9_A
DQ8_A
DQ7_A
DQ6_A
DQ5_A
DQ4_A
DQ3_A
DQ2_A
DQ1_A
DQ0_A
DQ31_B
DQ30_B
DQ29_B
DQ28_B
DQ27_B
DQ26_B
DQ25_B
DQ24_B
DQ23_B
DQ22_B
DQ21_B
DQ20_B
DQ19_B
DQ18_B
DQ17_B
DQ16_B
DQ15_B
DQ14_B
DQ13_B
DQ12_B
DQ11_B
DQ10_B
DQ9_B
DQ8_B
DQ7_B
DQ6_B
DQ5_B
DQ4_B
DQ3_B
DQ2_B
DQ1_B
DQ0_B
HAS
HSCL
HSDA
LBD||RSP_A_n
LBS||RSP_B_n
PAR_A
PAR_B
RESET_n
RFU6
RFU5
RFU4
RFU3
RFU2
RFU1
RFU0
VIN_MGMT
3/3
G3
G2
G1
VSS62
VSS61
VSS60
VSS58
VSS104
VSS102
VSS100
VIN_BULK2
VIN_BULK1
VIN_BULK0
VSS126
VSS125
VSS124
VSS123
VSS122
VSS121
VSS120
VSS119
VSS118
VSS117
VSS116
VSS115
VSS114
VSS113
VSS112
VSS111
VSS110
VSS109
VSS108
VSS107
VSS106
VSS105
VSS103
VSS101
VSS99
VSS98
VSS97
VSS96
VSS95
VSS94
VSS93
VSS92
VSS91
VSS90
VSS89
VSS88
VSS87
VSS86
VSS85
VSS84
VSS83
VSS82
VSS81
VSS80
VSS79
VSS78
VSS77
VSS76
VSS75
VSS74
VSS73
VSS72
VSS71
VSS70
VSS69
VSS68
VSS67
VSS66
VSS65
VSS64
VSS63
VSS59
VSS57
VSS56
VSS55
VSS54
VSS53
VSS52
VSS51
VSS50
VSS49
VSS48
VSS47
VSS46
VSS45
VSS44
VSS43
VSS42
VSS41
VSS40
VSS39
VSS38
VSS37
VSS36
VSS35
VSS34
VSS33
VSS32
VSS31
VSS30
VSS29
VSS28
VSS27
VSS26
VSS25
VSS24
VSS23
VSS22
VSS21
VSS20
VSS19
VSS18
VSS17
VSS16
VSS15
VSS14
VSS13
VSS12
VSS11
VSS10
VSS9
VSS8
VSS7
VSS6
VSS5
VSS4
VSS3
VSS2
VSS1
VSS0
21
21
1
SHEETDATE
23
7 3 2 16 5 4
E
A
B
C
E
D
C
B
A
7 6 5 4
D
DEPARTMENT
SIZE
PROJECT DOCUMENT NUMBER REV
REVIEWER
DESIGNER
OUT
IN
BI
OUT
OUT
IN
BI
IN
IN
IN
OUT
OUT
OUT
OUT
IN
BI
IN
IN
IN
IN
IN
IN
OUT
BI
IN
BI
BI
C



Thu Aug 24 14:08:59 2023<NAME_2>
<NAME_1>
MB FABCGTI V02
108 OF 365
P 3V 3
P 12V _ME M_CP U1
P 3V 3_A UX
M_K _CP U1_A LE RT_N
108
159104105106107109
104105106
107109159
47
47
47
47
47
47
47
47
47
47
104
105
106
107
109
108
47
47
47
47
47
47
47
47
47
47
47
47
1K
X 6S
10%
10UF
25V
C0805
X 6S
10%
10UF
25V
C0805
1K
0402LF
E MP TY
1/16W
1%
10%
0402
X 7R
25V
0.1UF
CHIP 0402LF
10
P D_CHK _CP U1_DIMM_S A A
I3C_S P D_DDRG L_CP U1_S CL
P W RG D_CHK _CP U1_DIMM
I3C_S P D_DDRG L_CP U1_S DA
I3C_SPD_DDRK_CPU1_SDA
I3C_SPD_DDRK_CPU1_SCL
1/16W
CHIP
1%
54.9K
0402LF
IO
SMLF
S CO NN288_DDR506112002K Q
S CO NN288_DDR506112002K Q
IO
SMLF
SMLF
S CO NN288_DDR506112002K Q
IO
DDR5 - CPU1 CHK
M_K _CP U1_S A _DQ <31:0>
M_K _CP U1_S A _CB <7:0>
M_K _CP U1_S B _CB <7:0>
M_K _CP U1_S A _CA <6:0>
M_K _CP U1_S B _CA <6:0>
M_K _CP U1_S B _DQ <31:0>
M_K _CP U1_S A _DQ S _DN<9:0>
M_K _CP U1_S A _DQ S _DP <9:0>
M_K _CP U1_S B _DQ S _DP <9:0>
M_K _CP U1_S B _DQ S _DN<9:0>
P W RG D_CHG L_CP U1
P D_CHK _CP U1_DIMM_S A A
M_K _CP U1_S B _P A R
M_K _CP U1_S A _P A R
M_K _CP U1_S B _RS P <0>
M_K _CP U1_S A _RS P <0>
M_K _CP U1_S B _CS _N<1>
M_K _CP U1_S A _CS _N<1>
M_K _CP U1_S B _CS _N<0>
M_K _CP U1_S A _CS _N<0>
M_K _CP U1_CLK _DP <0>
M_K _CP U1_CLK _DN<0>
M_K _CP U1_RE S E T_N
49.9
J99
J99
J99
R1710
R1590
2
1C547
2
1C546
2
1
R114
2 1
R313
2
1C176
2
1
R777
8
9
10
12
11
13
14
15
16
18
17
19
20
21
22
23
24
25
26
27
28
30
31
29
8
9
9
8
7
6
7
6
5
5
3
4
4
3
2
1
2
1
0
0
9
9
8
7
8
6
7
6
5
4
4
5
3
2
3
0
1
2
1
0
0
1
2
4
5
3
0
1
6
7
0
1
2
3
4
5
6
7
8
10
9
11
12
13
14
15
16
17
18
19
20
21
22
23
24
25
26
27
28
29
30
2
3
5
6
4
7
0
1
2
3
4
6
5
1
2
3
0
5
6
4
31
0
1
2
3
4
5
6
7
DQS7_A _c||TDQS7_A _c
DQS6_A _t||TDQS6_A _t
DQS8_B_t||TDQS8_B_t
DQS8_B_c||TDQS8_B_c
DQS7_B_t||TDQS7_B_t
DQS0_A _c
DQS0_A _t
DQS0_B_c
DQS0_B_t
DQS1_A _c
DQS1_A _t
DQS1_B_c
DQS1_B_t
DQS2_A _c
DQS2_A _t
DQS2_B_c
DQS2_B_t
DQS3_A _c
DQS3_A _t
DQS3_B_c
DQS3_B_t
DQS4_A _c
DQS4_A _t
DQS4_B_c
DQS4_B_t
DQS5_A _c||TDQS5_A _c||DQS5_A _t||TDQS5_A _t
DQS5_A _t||TDQS5_A _t
DQS5_B_c||TDQS5_B_c
DQS5_B_t||TDQS5_B_t
DQS6_A _c||TDQS6_A _c||DQS6_A _t||TDQS6_A _t
DQS6_B_c||TDQS6_B_c
DQS6_B_t||TDQS6_B_t
DQS7_A _t||TDQS7_A _t
DQS7_B_c||TDQS7_B_c
DQS8_A _c||TDQS8_A _c
DQS8_A _t||TDQS8_A _t
DQS9_A _c||TDQS9_A _c
DQS9_A _t||TDQS9_A _t
DQS9_B_c||TDQS9_B_c
DQS9_B_t||TDQS9_B_t||DBI4_B_n 93
94
201
200
283
282
190
189
272
271
179
178
261
260
168
167
250
249
157
156
239
238
55
56
137
138
44
45
126
127
33
34
115
116
22
23
104
105
11
12
288
286
284
281
279
277
275
273
270
268
266
264
262
259
257
255
253
251
248
246
244
242
240
237
235
233
230
228
226
224
222
219
216
214
212
210
208
206
204
202
199
197
195
193
191
188
186
184
182
180
177
175
173
171
169
166
164
162
160
158
155
153
151
143
141
139
136
134
132
130
128
125
123
121
119
117
114
112
110
108
106
103
101
99
97
95
92
90
88
85
83
81
79
77
75
73
71
69
67
65
63
61
59
57
54
52
50
48
46
43
41
39
37
35
32
30
28
26
24
21
19
17
15
13
10
8
6
146
145
1
G3
G2
G1
3
232
231
220
150
149
144
2
207
147
227
74
87
86
5
4
148
287
194
285
192
142
49
140
47
280
187
278
185
135
42
133
40
276
183
274
181
131
38
129
36
269
176
267
174
124
31
122
29
265
172
263
170
120
27
118
25
258
165
256
163
113
20
111
18
254
161
252
159
109
16
107
14
247
154
245
152
102
9
100
7
229
209
84
64
217
218
236
205
234
203
91
60
89
58
243
198
241
196
98
53
96
51
82
72
225
215
80
70
223
213
78
68
221
211
76
66
62
2/3
1/3
PWR_GOOD||FAIL_n
DQ31_A
CB7_A
CB4_A
CB1_A
CB7_B
ALERT_n
CA0_A
CA0_B
CA1_A
CA1_B
CA2_A
CA2_B
CA3_A
CA3_B
CA4_A
CA4_B
CA5_A
CA5_B
CA6_A
CA6_B
CB6_A
CB5_A
CB3_A
CB2_A
CB0_A
CB6_B
CB5_B
CB4_B
CB3_B
CB2_B
CB1_B
CB0_B
CK_c
CK_t
CS0_A_n
CS0_B_n
CS1_A_n
CS1_B_n
DQ30_A
DQ29_A
DQ28_A
DQ27_A
DQ26_A
DQ25_A
DQ24_A
DQ23_A
DQ22_A
DQ21_A
DQ20_A
DQ19_A
DQ18_A
DQ17_A
DQ16_A
DQ15_A
DQ14_A
DQ13_A
DQ12_A
DQ11_A
DQ10_A
DQ9_A
DQ8_A
DQ7_A
DQ6_A
DQ5_A
DQ4_A
DQ3_A
DQ2_A
DQ1_A
DQ0_A
DQ31_B
DQ30_B
DQ29_B
DQ28_B
DQ27_B
DQ26_B
DQ25_B
DQ24_B
DQ23_B
DQ22_B
DQ21_B
DQ20_B
DQ19_B
DQ18_B
DQ17_B
DQ16_B
DQ15_B
DQ14_B
DQ13_B
DQ12_B
DQ11_B
DQ10_B
DQ9_B
DQ8_B
DQ7_B
DQ6_B
DQ5_B
DQ4_B
DQ3_B
DQ2_B
DQ1_B
DQ0_B
HAS
HSCL
HSDA
LBD||RSP_A_n
LBS||RSP_B_n
PAR_A
PAR_B
RESET_n
RFU6
RFU5
RFU4
RFU3
RFU2
RFU1
RFU0
VIN_MGMT
3/3
G3
G2
G1
VSS62
VSS61
VSS60
VSS58
VSS104
VSS102
VSS100
VIN_BULK2
VIN_BULK1
VIN_BULK0
VSS126
VSS125
VSS124
VSS123
VSS122
VSS121
VSS120
VSS119
VSS118
VSS117
VSS116
VSS115
VSS114
VSS113
VSS112
VSS111
VSS110
VSS109
VSS108
VSS107
VSS106
VSS105
VSS103
VSS101
VSS99
VSS98
VSS97
VSS96
VSS95
VSS94
VSS93
VSS92
VSS91
VSS90
VSS89
VSS88
VSS87
VSS86
VSS85
VSS84
VSS83
VSS82
VSS81
VSS80
VSS79
VSS78
VSS77
VSS76
VSS75
VSS74
VSS73
VSS72
VSS71
VSS70
VSS69
VSS68
VSS67
VSS66
VSS65
VSS64
VSS63
VSS59
VSS57
VSS56
VSS55
VSS54
VSS53
VSS52
VSS51
VSS50
VSS49
VSS48
VSS47
VSS46
VSS45
VSS44
VSS43
VSS42
VSS41
VSS40
VSS39
VSS38
VSS37
VSS36
VSS35
VSS34
VSS33
VSS32
VSS31
VSS30
VSS29
VSS28
VSS27
VSS26
VSS25
VSS24
VSS23
VSS22
VSS21
VSS20
VSS19
VSS18
VSS17
VSS16
VSS15
VSS14
VSS13
VSS12
VSS11
VSS10
VSS9
VSS8
VSS7
VSS6
VSS5
VSS4
VSS3
VSS2
VSS1
VSS0
21
21
1
SHEETDATE
23
7 3 2 16 5 4
E
A
B
C
E
D
C
B
A
7 6 5 4
D
DEPARTMENT
SIZE
PROJECT DOCUMENT NUMBER REV
REVIEWER
DESIGNER
IN
OUT
IN
BI
IN
IN
IN
OUT
OUT
OUT
OUT
OUT
IN
BI
IN
IN
IN
IN
IN
BI
OUT
BI
BI
IN
IN
BI
OUT
C



Thu Aug 24 14:08:59 2023<NAME_2>
<NAME_1>
MB FABCGTI V02
109 OF 365
P 3V 3
P 3V 3_A UX
P 12V _ME M_CP U1
109
104105106
107108159
159104105106107108
48
48
48
48
48
48
109
48
48
48
48
104
105
106
107
108
48
48
48
48
48
48
48
48
48
48
48
48
1K
0.1UF
0402
25V
10%
X 7R
1%
1/16W
E MP TY
1K
0402LF
10UF
10%
X 6S
C0805
25V
10UF
C0805
25V
10%
X 6S
10
0402LFCHIP
P D_CHL_CP U1_DIMM_S A A
I3C_S P D_DDRG L_CP U1_S DA
I3C_S P D_DDRG L_CP U1_S CL
I3C_SPD_DDRL_CPU1_SCL
I3C_SPD_DDRL_CPU1_SDA
M_L_CP U1_S A _P A R
M_L_CP U1_S B _RS P <0>
M_L_CP U1_S A _CS _N<1>
M_L_CP U1_S B _CS _N<0>
M_L_CP U1_CLK _DP <0>
M_L_CP U1_CLK _DN<0>
P D_CHL_CP U1_DIMM_S A A
M_L_CP U1_S B _CS _N<1>
M_L_CP U1_S A _CS _N<0>
M_L_CP U1_S B _P A R
M_L_CP U1_S A _RS P <0>
P W RG D_CHG L_CP U1
M_L_CP U1_S A _CA <6:0>
M_L_CP U1_S B _CA <6:0>
M_L_CP U1_S A _CB <7:0>
M_L_CP U1_S B _CB <7:0>
M_L_CP U1_S B _DQ <31:0>
M_L_CP U1_S A _DQ S _DN<9:0>
M_L_CP U1_S A _DQ S _DP <9:0>
M_L_CP U1_S B _DQ S _DN<9:0>
M_L_CP U1_S B _DQ S _DP <9:0>
M_L_CP U1_S A _DQ <31:0>
DDR5 - CPU1 CHL
SMLF
IO
S CO NN288_DDR506112002K Q
S CO NN288_DDR506112002K Q
SMLF
IO
S CO NN288_DDR506112002K Q
SMLF
IO
1/16W
CHIP
1%
84.5K
0402LF
49.9
P W RG D_CHL_CP U1_DIMM
M_L_CP U1_RE S E T_N
M_L_CP U1_A LE RT_N
J37
J37
J37
R1711
R1591
2
1C549
2
1C548
2
1
R115
2 1
R314
2
1C180
2
1
R778
0
3
4
6
7
5
30
31
2
1
0
6
5
4
3
6
0
2
1
5
4
3
1
2
0
7
6
4
5
3
2
1
25
26
27
29
28
20
21
22
24
23
15
16
17
19
18
10
11
12
14
13
5
6
8
9
7
0
1
4
3
2
6
7
5
3
4
2
1
1
2
0
3
4
0
5
7
6
0
1
2
3
5
4
6
7
8
9
1
0
2
3
4
6
5
8
9
1
0
2
3
4
5
6
7
9
7
8
8
9
28
30
31
29
23
24
25
27
26
18
19
20
22
21
13
14
17
16
15
8
9
10
11
12
DQS7_A _c||TDQS7_A _c
DQS6_A _t||TDQS6_A _t
DQS8_B_t||TDQS8_B_t
DQS8_B_c||TDQS8_B_c
DQS7_B_t||TDQS7_B_t
DQS0_A _c
DQS0_A _t
DQS0_B_c
DQS0_B_t
DQS1_A _c
DQS1_A _t
DQS1_B_c
DQS1_B_t
DQS2_A _c
DQS2_A _t
DQS2_B_c
DQS2_B_t
DQS3_A _c
DQS3_A _t
DQS3_B_c
DQS3_B_t
DQS4_A _c
DQS4_A _t
DQS4_B_c
DQS4_B_t
DQS5_A _c||TDQS5_A _c||DQS5_A _t||TDQS5_A _t
DQS5_A _t||TDQS5_A _t
DQS5_B_c||TDQS5_B_c
DQS5_B_t||TDQS5_B_t
DQS6_A _c||TDQS6_A _c||DQS6_A _t||TDQS6_A _t
DQS6_B_c||TDQS6_B_c
DQS6_B_t||TDQS6_B_t
DQS7_A _t||TDQS7_A _t
DQS7_B_c||TDQS7_B_c
DQS8_A _c||TDQS8_A _c
DQS8_A _t||TDQS8_A _t
DQS9_A _c||TDQS9_A _c
DQS9_A _t||TDQS9_A _t
DQS9_B_c||TDQS9_B_c
DQS9_B_t||TDQS9_B_t||DBI4_B_n 93
94
201
200
283
282
190
189
272
271
179
178
261
260
168
167
250
249
157
156
239
238
55
56
137
138
44
45
126
127
33
34
115
116
22
23
104
105
11
12
288
286
284
281
279
277
275
273
270
268
266
264
262
259
257
255
253
251
248
246
244
242
240
237
235
233
230
228
226
224
222
219
216
214
212
210
208
206
204
202
199
197
195
193
191
188
186
184
182
180
177
175
173
171
169
166
164
162
160
158
155
153
151
143
141
139
136
134
132
130
128
125
123
121
119
117
114
112
110
108
106
103
101
99
97
95
92
90
88
85
83
81
79
77
75
73
71
69
67
65
63
61
59
57
54
52
50
48
46
43
41
39
37
35
32
30
28
26
24
21
19
17
15
13
10
8
6
146
145
1
G3
G2
G1
3
232
231
220
150
149
144
2
207
147
227
74
87
86
5
4
148
287
194
285
192
142
49
140
47
280
187
278
185
135
42
133
40
276
183
274
181
131
38
129
36
269
176
267
174
124
31
122
29
265
172
263
170
120
27
118
25
258
165
256
163
113
20
111
18
254
161
252
159
109
16
107
14
247
154
245
152
102
9
100
7
229
209
84
64
217
218
236
205
234
203
91
60
89
58
243
198
241
196
98
53
96
51
82
72
225
215
80
70
223
213
78
68
221
211
76
66
62
2/3
1/3
PWR_GOOD||FAIL_n
DQ31_A
CB7_A
CB4_A
CB1_A
CB7_B
ALERT_n
CA0_A
CA0_B
CA1_A
CA1_B
CA2_A
CA2_B
CA3_A
CA3_B
CA4_A
CA4_B
CA5_A
CA5_B
CA6_A
CA6_B
CB6_A
CB5_A
CB3_A
CB2_A
CB0_A
CB6_B
CB5_B
CB4_B
CB3_B
CB2_B
CB1_B
CB0_B
CK_c
CK_t
CS0_A_n
CS0_B_n
CS1_A_n
CS1_B_n
DQ30_A
DQ29_A
DQ28_A
DQ27_A
DQ26_A
DQ25_A
DQ24_A
DQ23_A
DQ22_A
DQ21_A
DQ20_A
DQ19_A
DQ18_A
DQ17_A
DQ16_A
DQ15_A
DQ14_A
DQ13_A
DQ12_A
DQ11_A
DQ10_A
DQ9_A
DQ8_A
DQ7_A
DQ6_A
DQ5_A
DQ4_A
DQ3_A
DQ2_A
DQ1_A
DQ0_A
DQ31_B
DQ30_B
DQ29_B
DQ28_B
DQ27_B
DQ26_B
DQ25_B
DQ24_B
DQ23_B
DQ22_B
DQ21_B
DQ20_B
DQ19_B
DQ18_B
DQ17_B
DQ16_B
DQ15_B
DQ14_B
DQ13_B
DQ12_B
DQ11_B
DQ10_B
DQ9_B
DQ8_B
DQ7_B
DQ6_B
DQ5_B
DQ4_B
DQ3_B
DQ2_B
DQ1_B
DQ0_B
HAS
HSCL
HSDA
LBD||RSP_A_n
LBS||RSP_B_n
PAR_A
PAR_B
RESET_n
RFU6
RFU5
RFU4
RFU3
RFU2
RFU1
RFU0
VIN_MGMT
3/3
G3
G2
G1
VSS62
VSS61
VSS60
VSS58
VSS104
VSS102
VSS100
VIN_BULK2
VIN_BULK1
VIN_BULK0
VSS126
VSS125
VSS124
VSS123
VSS122
VSS121
VSS120
VSS119
VSS118
VSS117
VSS116
VSS115
VSS114
VSS113
VSS112
VSS111
VSS110
VSS109
VSS108
VSS107
VSS106
VSS105
VSS103
VSS101
VSS99
VSS98
VSS97
VSS96
VSS95
VSS94
VSS93
VSS92
VSS91
VSS90
VSS89
VSS88
VSS87
VSS86
VSS85
VSS84
VSS83
VSS82
VSS81
VSS80
VSS79
VSS78
VSS77
VSS76
VSS75
VSS74
VSS73
VSS72
VSS71
VSS70
VSS69
VSS68
VSS67
VSS66
VSS65
VSS64
VSS63
VSS59
VSS57
VSS56
VSS55
VSS54
VSS53
VSS52
VSS51
VSS50
VSS49
VSS48
VSS47
VSS46
VSS45
VSS44
VSS43
VSS42
VSS41
VSS40
VSS39
VSS38
VSS37
VSS36
VSS35
VSS34
VSS33
VSS32
VSS31
VSS30
VSS29
VSS28
VSS27
VSS26
VSS25
VSS24
VSS23
VSS22
VSS21
VSS20
VSS19
VSS18
VSS17
VSS16
VSS15
VSS14
VSS13
VSS12
VSS11
VSS10
VSS9
VSS8
VSS7
VSS6
VSS5
VSS4
VSS3
VSS2
VSS1
VSS0
21
21
1
SHEETDATE
23
7 3 2 16 5 4
E
A
B
C
E
D
C
B
A
7 6 5 4
D
DEPARTMENT
SIZE
PROJECT DOCUMENT NUMBER REV
REVIEWER
DESIGNER
IN
BI
OUT
IN
OUT
BI
IN
IN
IN
OUT
OUT
OUT
OUT
OUT
IN
BI
IN
IN
IN
IN
IN
IN
OUT
BI
BI
IN
BI
C



Thu Aug 24 10:14:17 2023<NAME_2>
<NAME_1>
MB FABCGTI V02
110 OF 365
Blank
1
SHEETDATE
23
7 3 2 16 5 4
E
A
B
C
E
D
C
B
A
7 6 5 4
D
DEPARTMENT
SIZE
PROJECT DOCUMENT NUMBER REV
REVIEWER
DESIGNER
C



20210929 MODIFY FOR GT
Thu Aug 24 14:09:22 2023<NAME_2>
<NAME_1>
MB FABCGTI V02
111 OF 365
P3V3_AUX
P3V3_AUX
P3V3_AUX
P3V3_AUX
P3V3_AUX
P3V3_AUXP3V3_AUX
113
113
111
111
111
111
111
111
113
113
111
111
111111
111
234
111
112
111
111
113
111
111
113
113
111
111 234 112
113
111
111
1%
0402LF
PCIE REDRIVER BOM1
68K
1%
P2E_MB_BMC _TX_BU F_D P<0>
P2E_MB_BMC _TX_BU F_D N <0>
10%
25V
PCIE REDRIVER BOM1
04020402
FM_P2E_FGB
FM_P2E_SW A
FM_P2E_SW B
FM_P2E_EQA0
FM_P 2E _E QA 1
FM_P 2E _E QB 1
P2E_MB_BMC _TX_C _R 1_D P<0>
P2E_MB_BMC _R X_R 1_D N <0>
1%
0402LF
EMPTY
1/16W
PC IE R ED R IVERBOM1
FM_P2E_SWA
FM_P2E_SWB
0402LF
EMPTY
1/16W
1%
PC IE R ED R IVERBOM1
IO_SLOT
1K
FM_P2E_EQB1
EMPTY
1/16W
PCIE REDRIVER BOM1
EMPTY
1/16W
1K
1%
FM_P2E_EQA1
FM_P2E_EQA0
0402LF
1%
PC IE R ED R IVERBOM1
PC IE R ED R IVERBOM1
1/16W
EMPTY
0402LF
0402LF
IO_SLOT
0402LF
EMPTY
1/16W
1%
0402LF
0402LF
68K
IO_SLOT
68K
PCIE REDRIVER BOM1
1/16W
CLK_GEN2_GPU_FPGA_OE_OR_N
PCIE REDRIVER BOM1
PCIE REDRIVER BOM1
4.7K
1%
PC IE R ED R IVERBOM1
0402LF
0402LF
FM_P2E_MODE
PCIE REDRIVER BOM1
EMPTY
1/16W
P U_TE S T
IO_SLOT
PCIE REDRIVER BOM1
PCIE REDRIVER BOM1
0.1UF
PI3EQX12902AZLEX
P CIE RE DRIV E R B O M1P CIE RE DRIV E R B O M1
1%
1/16W
68K
0402LF
EMPTY
0402LF
1K
1/16W
CHIP
1%
1K
EMPTY
0402LF
1/16W
0402LF
1%
68K
EMPTY
1%
1K
EMPTY
1/16W
0402LF 0402LF
1K
1%
CHIP
1/16W
1K
1%
EMPTY
1/16W
0402LF
1%
1K
1%
EMPTY
0402LF
1/16W
1/16W
1K
EMPTY
0402LF
1%
68K
1/16W
0402LF
1%
4.7K
1/16W
EMPTY
1%
0402LF
4.7K
CHIP
4.7K
1%
1/16W
1/16W
CHIP
4.7K
0402LF
0402LF
1/16W
EMPTY
1%
1K
1/16W
IO_SLOT
FM_P2E_EQB0
P2E_MB_BMC _R X_R 1_D P<0>
FM_P2E_FGA
FM_P2E_FGB
P2E_MB_BMC _R X_BU F_C _D N <0>
P2E_MB_BMC _R X_BU F_C _D P<0>
BMC - GPU FPGA PCIE - RE-DRIVER (main)
IO_SLOTIO_SLOT
IO_SLOTIO_SLOT IO_SLOTIO_SLOTIO_SLOTIO_SLOT
C0805
10UF
25V
X6S
10%
X7R
0402
25V
10%
PC IE R ED R IVERBOM1
0.1UF
25V
0.1UF
X7R
0402
10%
X7R
10%
25V
X7R
SMLF
0.1UF
IC
FM_P2E_MOD E
FM_P2E_EN _N 0 CHIP 0402LF
PC IE R ED R IVERBOM1
IO_SLOT
EMPTY
CLK_GEN2_GPU_FPGA_OE_OR_N
P2E_MB_BMC _TX_C _R 1_D N <0>
1%
1K
1%
1%
1/16W
EMPTY
IO_SLOT IO_SLOT
0402LF
FM_P2E_FGA
0402LF
1%
1/16W
EMPTY
EMPTY
PCIE REDRIVER BOM1
PCIE REDRIVER BOM1PC IE R ED R IVERBOM1
PCIE REDRIVER BOM1
1K
PCIE REDRIVER BOM1
1/16W
EMPTY
PCIE REDRIVER BOM1
1K
1%
PCIE REDRIVER BOM1
68K
1%
1/16W
1/16W
EMPTY
PCIE REDRIVER BOM1 PCIE REDRIVER BOM1
PCIE REDRIVER BOM1
IO_SLOT
0402LF
PCIE REDRIVER BOM1
1K
EMPTY
1/16W
68K
1%1%
1K
PCIE REDRIVER BOM1
0402LF
PCIE REDRIVER BOM1
PCIE REDRIVER BOM1
PC IE R ED R IVERBOM1
FM_P2E_EQB0
IO_SLOT
0402LF
IO_SLOT
EMPTY
1/16W
PCIE REDRIVER BOM1
1K
PCIE REDRIVER BOM1
PCIE REDRIVER BOM1
EMPTY
R3286
R3285
R3280
R3279
R3269
R3267
R3271
R3268
25
16
10
1
512
29
30
TH
28
22
19
13
7
6
4
14
27
15
20
26
21
11
9
8
17
18
24
23
2
3
U237
GND_TH
MODE
SWA
GND7
FGA
EQA1
VDD4
AOP
AON
GND6
EQA0
EQB0
GND5
BIN
BIP
VDD3
EQB1
FGB
GND4
SWB
EN#
VDD2
BOP
BON
GND3
GND2
TEST#
GND1
AIN
AIP
VDD1
2
1
2
1
2
1
2
1
2
1
2
1
2
1
2
1
21
2
1
2
1 C1865
2
1 C1864
2
1 C1863
2
1
2
1
2
1
2
1
2
1
2
1
2
1
2
1
2
1
2
1
2
1
2
1
2
1
2
1
2
1
2
1
2
1
2
1
2
1
2
1
2
1
2
1
1
SHEETDATE
23
7 3 2 16 5 4
E
A
B
C
E
D
C
B
A
7 6 5 4
D
DEPARTMENT
SIZE
PROJECT DOCUMENT NUMBER REV
REVIEWER
DESIGNER
OUT
OUT
OUT
OUT
OUT
OUT
IN
OUT
OUT
IN
IN
IN
IN
IN
IN
IN
IN
IN
IN
IN
IN
IN
OUT
OUT
OUT
OUT
OUT
OUT
R3266
R3293
R3292
R3291
R3265
R3289
R3290R3288
R4537
C1866C1867
R3287
R3283
R3284R3282
R3275
R3276
R3281
R3277
R3278R3274
R3273
R3270
R3272
C



20220426 MODIFY FOR GTI
TBC
TBC
Thu Aug 24 14:09:30 2023<NAME_2>
<NAME_1>
MB FABCGTI V02
112 OF 365
P3V3_AUXP3V3_AUX
P3V3_AUX
P3V3_AUX P3V3_AUX
P3V3_AUX
P3V3_AUX
112112112
112
112
112
112
112
113
113
113
113
112
112
112
112
112
112
111 234
112
112
113
113
113
113
112
112
PCIE REDRIVER BOM2
FM_P2E_BUF2_VOD_SEL
PCIE REDRIVER BOM2
PCIE REDRIVER BOM2
FM_P2E_BUF2_SD_TH
PCIE REDRIVER BOM2
PCIE REDRIVER BOM2
FM_P2E_BUF2_RXDET
PCIE REDRIVER BOM2
1K
1%
EMPTY
PC IE R ED R IVERBOM2
1K
EMPTY
1/16W
PCIE REDRIVER BOM2
CHIP
0402LF
PC IE R ED R IVERBOM2PCIE REDRIVER BOM2
FM_P2E_BUF2_EQB0
PCIE REDRIVER BOM2
1/16W
1K
1%
1/16W
EMPTY
0402LF
FM_P2E_BUF2_VODB_DB
FM_P2E_BUF2_VODA_DB
PC IE R ED R IVERBOM2
1/16W
CHIP
1%
1K
0402LF
PCIE REDRIVER BOM2
1/16W
EMPTY
0402LF
1%
FM_P2E_BUF2_RXDET
PC IE R ED R IVERBOM2
PC IE R ED R IVERBOM2
0.1UF
25V
X 7R
1%
0402LF
CHIP
1K
1/16W
IC
DS125BR111RTWR
SMLF
PC IE R ED R IVERBOM2
PCIE REDRIVER BOM2
0402LF
1/16W
CHIP
1K
1%
1K
1K
EMPTY
1K
1%
EMPTY
1K
1%
1%
0402LF
1K
1K
0402LF
EMPTY
1/16W
1%
1K
1%
1K
1/16W
CHIP
0402LF 0402LF
1/16W
1%
EMPTY
0402LF
1K
1/16W
1%
EMPTY
0402LF
1%
0402LF
1/16W
EMPTY
1K
1/16W
1%
EMPTY
1K
0402LF
1/16W
1K
1%
0402LF 0402LF
1/16W
1K
1%
CHIP
BMC-GPU FPGA PCIE - RE-DRIVER (2nd)
FM_P2E_BUF2_VOD_SEL
NC_RES
CHIP
1%
X 7R
0402
10%
25V
0.1UF
10%
BUF2_VDD
16V
X 6S
C0805
10UF
PC IE R ED R IVERBOM2
25V
X 6S
C0402
1UF
10% 10%
PC IE R ED R IVERBOM2
0402
P2E_MB_BMC_RX_R2_DN<0>
P2E_MB_BMC_RX_R2_DP<0>
PD_P2E_BUF2_ENSMB
P2E_MB_BMC_TX_C_R2_DN<0>
P2E_MB_BMC_TX_C_R2_DP<0>
FM_P2E_BUF2_VODB_DB
FM_P2E_BUF2_VODA_DB
FM_P2E_BUF2_EQB0
FM_P2E_BUF2_EQB1
FM_P2E_BUF2_EQA1
FM_P2E_BUF2_EQA0
0 5%
0402LF
CLK_GEN2_GPU_FPGA_OE_OR_N
FM_P2E_BUF2_SD_TH
PCIE REDRIVER BOM2
1/16W
PCIE REDRIVER BOM2
FM_P2E_BUF2_EQB1
0402LF
PCIE REDRIVER BOM2
1%
1/16W
0402LF
1/16W
FM_P2E_EN2_N
PC IE R ED R IVERBOM2
1/16WCHIP
P2E_MB_BMC_TX_BUF2_DP<0>
P2E_MB_BMC_TX_BUF2_DN<0>
P2E_MB_BMC_RX_BUF2_C_DP<0>
P2E_MB_BMC_RX_BUF2_C_DN<0>
PCIE REDRIVER BOM2
0402LF
EMPTY
PCIE REDRIVER BOM2
FM_P2E_BUF2_EQA0
FM_P2E_BUF2_EQA1
1/16W
C6010C6009
R6163
R6162
R6160
C6012C6011
17
15
16
22
21
25
4
14
5
18
13
6
19
20
8
7
12
11
23
24
2
1
9
10
3
U6000
TH_GND
INA+
INA-
VDD_22
VDD_21
OUTB+
OUTB-
RXDET||DONE#
VOD_SEL||READEN#
VDD_SEL
VIN
SD_TH
RES
INB-
INB+
EQA0||AD0
EQA1||AD1
OUTA-
OUTA+
PWDN
SCL||VODB_DB
SDA||VODA_DB
ENSMB
EQB1||AD2
EQB0||AD3
2
1
2
1
2
1
2
1
2
1
2
1
2
1
2
1
2
1
2
1
2
1
2
1
2
1
2
1
2
1
2
1
2
1
2
1
21
2
1
2
1
2
1
2
1
2
1
1
SHEETDATE
23
7 3 2 16 5 4
E
A
B
C
E
D
C
B
A
7 6 5 4
D
DEPARTMENT
SIZE
PROJECT DOCUMENT NUMBER REV
REVIEWER
DESIGNER
IN
IN
OUTOUTOUT
OUT
OUT
OUT
OUT
OUT
OUT
OUT
OUT
OUT
OUT
IN
IN
IN
IN
IN
IN
IN
IN
IN
IN
IN
IN
R6179R6177
R6180R6178R6176
R6175
R6170R6168
R6167 R6169
R6172
R6171
R6174
R6173R6165
R6166R6164
C



FROM BMC
TO BMC
TO 2ND REDRIVER
FROM FPGA
20220426 MODIFY FOR GTI
TO 1ST REDRIVER
TO 2ND REDRIVER
TO 1ST REDRIVER
FROM 1ST REDRIVER
FROM 2ND REDRIVER
FROM 2ND REDRIVER
FROM 1ST REDRIVER TO GPU FPGA
Thu Aug 24 14:09:30 2023<NAME_2>
<NAME_1>
MB FABCGTI V02
113 OF 365
112
112
150
122
122
111
112
112
150
111
111
111
111
111
150
150
122
112
122
112
112
112
111
111
P2E_MB_BMC_TX_BUF2_DP<0>
P2E_MB_BMC_TX_BUF2_DN<0>
PCIE REDRIVER BOM2
PCIE REDRIVER BOM2
PCIE REDRIVER BOM2
P2E_MB_BMC_RX_BUF_DP<0>
PCIE REDRIVER BOM1
P2E_MB_BMC_TX_BUF_C_DP<0>
P2E_MB_BMC_TX_BUF_C_DN<0>
0.1UF
PCIE REDRIVER BOM1
PCIE REDRIVER BOM2
PCIE REDRIVER BOM1
P2E_MB_BMC_TX_BUF_DP<0>
P2E_MB_BMC_RX_BUF2_C_DP<0>
P2E_MB_BMC_RX_BUF2_C_DN<0>
P2E_MB_BMC_RX_BUF_DN<0>
P2E_MB_BMC_TX_BUF_DN<0>
C1870/C6005 C1871/C6006 CO-LAYOUT
0402
PCIE REDRIVER BOM1
X7R
P2E_MB_BMC_RX_R1_DP<0>
P2E_MB_BMC_RX_R1_DN<0>
CHIP
0201LF
PCIE REDRIVER BOM2
PCIE REDRIVER BOM1
0 CHIP
1/20W5%
0
PCIE REDRIVER BOM1
CHIP
0
PCIE REDRIVER BOM2
0
P2E_MB_BMC_TX_C_R1_DP<0>
P2E_MB_BMC_TX_C_R1_DN<0>0201LF
0201LF
0
0
BMC-GPU FPGA PCIE RE-DRIVER SELECT
R6152/R6154 R6153/R6155 CO-LAYOUT
1/20W
CHIP
P2E_MB_BMC_TX_C_DP<0>
P2E_MB_BMC_TX_C_DN<0>
CHIP
5%
0201LFP2E_MB_BMC_RX_DP<0>
P2E_MB_BMC_RX_R2_DN<0>0
P2E_MB_BMC_RX_DN<0>
P2E_MB_BMC_TX_C_R2_DN<0>
PCIE REDRIVER BOM1
P2E_MB_BMC_TX_C_R2_DP<0>0201LFCHIP
0201LF
R6156/R6158 R6157/R6159 CO-LAYOUT
CHIP
PCIE REDRIVER BOM1
P2E_MB_BMC_RX_R2_DP<0>0
0201LF
PCIE REDRIVER BOM2
CHIP
0201LF
PCIE REDRIVER BOM2
0.1UF 25V
25V
10%
0.1UF
C1868/C6007 C1869/C6008 CO-LAYOUT
P2E_MB_BMC_RX_BUF_C_DN<0>
P2E_MB_BMC_RX_BUF_C_DP<0>
0402
C6005
C6006
C1871
C1870
C1869
C1868
C6008
C6007
CAD NOTE: CAD NOTE:
CAD NOTE:
CAD NOTE:
21
21
21
21
21R6158
21R6159
21R6157
21R6156
21
21
21
21
21R6152 21R6153
21R6155
21R6154
1
SHEETDATE
23
7 3 2 16 5 4
E
A
B
C
E
D
C
B
A
7 6 5 4
D
DEPARTMENT
SIZE
PROJECT DOCUMENT NUMBER REV
REVIEWER
DESIGNER
IN OUT
OUT
OUT
IN
IN
IN
IN
OUT
OUT
OUT
IN
IN
IN
IN
OUT
OUT
OUT
OUT
OUT
OUT
IN
IN
IN
C



Thu Aug 24 10:14:19 2023<NAME_2>
<NAME_1>
MB FABCGTI V02
114 OF 365Blank
1
SHEETDATE
23
7 3 2 16 5 4
E
A
B
C
E
D
C
B
A
7 6 5 4
D
DEPARTMENT
SIZE
PROJECT DOCUMENT NUMBER REV
REVIEWER
DESIGNER
C



CPU0_P3_TX/RX<0-15> LANE REVERSAL
CPU0_P2_TX/RX<0-15> LANE REVERSAL
Thu Aug 24 14:09:44 2023
GTI
<NAME_2>
V02
<NAME_1>
MB FABC
115 OF 365
P5E_CPU0_P3_RX_BUF_DP<13>
127
126
297
297
309
309
308
309
309
298
298
308
308
297
124
309
308
298
298
309
309
309
298
298
308
297
297
124
130
309
309
298
298
308
297
297
308
298
298
308
309
309
298
308
308
297
297
309
309
127
298
298
308
308
298
124
297
297
297
308
297
297
128
308
298
308
297
297
308
298
309
309
FM_SWB_BIC_READY_N
GPU_WP_HW_CTRL_ISO_N
P5E_CPU0_P2_RX_BUF_DP<10>
P5E_CPU0_P2_RX_BUF_DN<10>
P5E_CPU0_P3_TX_BUF_C_DN<11>
P5E_CPU0_P3_TX_BUF_C_DP<11>
P5E_CPU0_P3_RX_BUF_DN<10>
P5E_CPU0_P3_TX_BUF_C_DP<8>
P5E_CPU0_P3_TX_BUF_C_DN<8>
P5E_CPU0_P2_TX_BUF_C_DP<8>
P5E_CPU0_P2_TX_BUF_C_DN<8>
P5E_CPU0_P3_RX_BUF_DP<8>
P5E_CPU0_P3_RX_BUF_DN<8>
P5E_CPU0_P2_RX_BUF_DN<8>
GPU_3V3IO_RSVD4
P5E_CPU0_P3_TX_BUF_C_DP<9>
P5E_CPU0_P3_RX_BUF_DP<9>
P5E_CPU0_P2_TX_BUF_C_DN<9>
P5E_CPU0_P2_TX_BUF_C_DP<9>
P5E_CPU0_P3_TX_BUF_C_DN<9>
P5E_CPU0_P3_TX_BUF_C_DP<10>
P5E_CPU0_P3_TX_BUF_C_DN<10>
P5E_CPU0_P2_TX_BUF_C_DP<10>
P5E_CPU0_P2_TX_BUF_C_DN<10>
P5E_CPU0_P3_RX_BUF_DP<10>
P5E_CPU0_P2_RX_BUF_DP<12>
P5E_CPU0_P2_RX_BUF_DN<12>
GPU_3V3IO_RSVD3
RST_SWB_BIC_BUF_N
P5E_CPU0_P3_TX_BUF_C_DP<13>
P5E_CPU0_P3_TX_BUF_C_DN<13>
P5E_CPU0_P2_TX_BUF_C_DP<13>
P5E_CPU0_P2_TX_BUF_C_DN<13>
P5E_CPU0_P2_RX_BUF_DP<13>
P5E_CPU0_P2_RX_BUF_DN<13>
P5E_CPU0_P3_RX_BUF_DP<11>
P5E_CPU0_P2_TX_BUF_C_DP<11>
P5E_CPU0_P2_TX_BUF_C_DN<11>
P5E_CPU0_P3_RX_BUF_DN<13>
P5E_CPU0_P3_TX_BUF_C_DP<14>
P5E_CPU0_P3_TX_BUF_C_DN<14>
P5E_CPU0_P2_TX_BUF_C_DN<14>
P5E_CPU0_P3_RX_BUF_DP<14>
P5E_CPU0_P3_RX_BUF_DN<14>
P5E_CPU0_P2_RX_BUF_DP<14>
P5E_CPU0_P2_RX_BUF_DN<14>
P5E_CPU0_P3_TX_BUF_C_DN<15>
P5E_CPU0_P3_TX_BUF_C_DP<15>
RST_BMC_FROM_SWB_N
P5E_CPU0_P2_TX_BUF_C_DP<15>
P5E_CPU0_P2_TX_BUF_C_DN<15>
P5E_CPU0_P3_RX_BUF_DP<15>
P5E_CPU0_P3_RX_BUF_DN<15>
P5E_CPU0_P2_TX_BUF_C_DP<14>
GPU_3V3IO_RSVD1
P5E_CPU0_P2_RX_BUF_DP<9>
P5E_CPU0_P2_RX_BUF_DN<9>
P5E_CPU0_P2_RX_BUF_DP<11>
P5E_CPU0_P3_RX_BUF_DN<11>
P5E_CPU0_P2_RX_BUF_DP<15>
P5E_CPU0_P2_RX_BUF_DN<11>
IO
THLFTHLF
IO
PCIE - CPU0_EXAMAX_P2/P3_X16
FM_SWB_PWR_EN_R_BUF
P5E_CPU0_P3_RX_BUF_DN<9>
P5E_CPU0_P2_TX_BUF_C_DP<12>
P5E_CPU0_P3_RX_BUF_DP<12>
P5E_CPU0_P2_RX_BUF_DP<8>
P5E_CPU0_P2_RX_BUF_DN<15>
P5E_CPU0_P3_RX_BUF_DN<12>
P5E_CPU0_P2_TX_BUF_C_DN<12>
P5E_CPU0_P3_TX_BUF_C_DN<12>
P5E_CPU0_P3_TX_BUF_C_DP<12>
N8
N7
N6
N5
M8
M7
M6
M5
L8
L7
L6
L5
K8
K7
K6
K5
J8
J7
J6
J5
I8
I7
I6
I5
H8
H7
H6
H5
G8
G7
G6
G5
F8
F7
F6
F5
E8
E7
E6
E5
D8
D7
D6
D5
C8
C7
C6
C5
B8
B7
B6
B5
A8
A7
A6
A5
N4
N3
N2
N1
M4
M3
M2
M1
L4
L3
L2
L1
K4
K3
K2
K1
J4
J3
J2
J1
I4
I3
I2
I1
H4
H3
H2
H1
G4
G3
G2
G1
F4
F3
F2
F1
E4
E3
E2
E1
D4
D3
D2
D1
C4
C3
C2
C1
B4
B3
B2
B1
A4
A3
A2
A1
J105 J105
1/2
NM
5
LKJC D E F G H IA B
6
7
8
N8
M8
N7
M7
N6
M6
N5
M5
L5
L6
L7
L8
K5
K6
K7
K8
J5
J6
J7
J8
I5
I6
I7
I8
H5
H6
H7
H8
G5
G6
G7
G8
F5
F6
F7
F8
E5
E6
E7
E8
D5
D6
D7
D8
C5
C6
C7
C8
B5
B6
B7
B8
A5
A6
A7
A8
2/2
NM
1
LKJC D E F G H IA B
2
3
4
N4
M4
N3
M3
N2
M2
N1
M1
L1
L2
L3
L4
K1
K2
K3
K4
J1
J2
J3
J4
I1
I2
I3
I4
H1
H2
H3
H4
G1
G2
G3
G4
F1
F2
F3
F4
E1
E2
E3
E4
D1
D2
D3
D4
C1
C2
C3
C4
B1
B2
B3
B4
A1
A2
A3
A4
1
SHEETDATE
23
7 3 2 16 5 4
E
A
B
C
E
D
C
B
A
7 6 5 4
D
DEPARTMENT
SIZE
PROJECT DOCUMENT NUMBER REV
REVIEWER
DESIGNER
OUT
OUT
OUT
OUT
OUT
OUT
OUT
IN
IN
IN
IN
IN
OUT
OUT
OUT
OUT
IN
IN
IN
OUT
IN
IN
OUT
OUT
OUT
OUT
IN
IN
IN
IN
IN
IN
OUT
OUT
OUT
OUT
OUT
IN
IN
OUT
IN
IN
OUT
OUT
OUT
OUT
IN
IN
IN
IN
OUT
OUT
OUT
OUT
OUT
OUT
OUT
IN
IN
IN
IN
IN
OUT
OUT
OUT
OUT
IN
IN
IN
IN
IN
IN
C



CPU0_P3_TX/RX<0-15> LANE REVERSAL
CPU0_P2_TX/RX<0-15> LANE REVERSAL
Thu Aug 24 14:09:43 2023 116 OF 365
MB FABC V02GTI
<NAME_1>
<NAME_2>
P5E_CPU0_P2_TX_BUF_C_DN<5>
UART_BMC_BIC_RX
309
309
125
150
297
297
308
309
297
297
308
308
298
298
298
308
123
309
309
308
127
298
309
309
297
297
297
309
309
298
298
297
309
249
298
309
309
309
130
298
298
298
308
308
297
297
249
308
297
297
308
308
308
297
297
309
309
308
308
297
298
298
298
309
297
308
298
298
298
308
308
P5E_CPU0_P3_TX_BUF_C_DN<7>
P5E_CPU0_P3_TX_BUF_C_DP<7>
PRSNT_CABLE_GPU_A1_N
UART_BMC_BIC_TX
P5E_CPU0_P2_RX_BUF_DN<6>
P5E_CPU0_P2_RX_BUF_DP<3>
P5E_CPU0_P3_RX_BUF_DP<3>
P5E_CPU0_P3_TX_BUF_C_DP<3>
P5E_CPU0_P2_RX_BUF_DN<2>
P5E_CPU0_P2_RX_BUF_DP<2>
P5E_CPU0_P3_RX_BUF_DN<2>
P5E_CPU0_P3_RX_BUF_DP<2>
P5E_CPU0_P2_TX_BUF_C_DN<2>
P5E_CPU0_P2_TX_BUF_C_DP<0>
P5E_CPU0_P2_TX_BUF_C_DN<0>
P5E_CPU0_P3_RX_BUF_DP<0>
PRSNT_CABLE_SWB_B1_N
P5E_CPU0_P3_TX_BUF_C_DP<0>
P5E_CPU0_P3_TX_BUF_C_DN<0>
P5E_CPU0_P3_RX_BUF_DN<0>
FM_SWB_PWRGD
P5E_CPU0_P2_TX_BUF_C_DP<2>
P5E_CPU0_P3_TX_BUF_C_DN<2>
P5E_CPU0_P3_TX_BUF_C_DP<2>
P5E_CPU0_P2_RX_BUF_DN<1>
P5E_CPU0_P2_RX_BUF_DP<0>
P5E_CPU0_P2_RX_BUF_DN<0>
P5E_CPU0_P3_TX_BUF_C_DP<1>
P5E_CPU0_P3_TX_BUF_C_DN<1>
P5E_CPU0_P2_TX_BUF_C_DP<1>
P5E_CPU0_P2_TX_BUF_C_DN<1>
P5E_CPU0_P2_RX_BUF_DP<1>
P5E_CPU0_P3_TX_BUF_C_DN<3>
I3C_BMC_SWB_BUF_SCL
P5E_CPU0_P2_TX_BUF_C_DP<4>
P5E_CPU0_P3_TX_BUF_C_DN<4>
P5E_CPU0_P3_TX_BUF_C_DP<4>
P5E_CPU0_P3_TX_BUF_C_DP<5>
P5E_CPU0_P2_TX_BUF_C_DP<6>
P5E_CPU0_P2_TX_BUF_C_DP<7>
P5E_CPU0_P2_TX_BUF_C_DN<7>
P5E_CPU0_P3_RX_BUF_DP<7>
P5E_CPU0_P3_RX_BUF_DN<7>
P5E_CPU0_P2_RX_BUF_DP<7>
P5E_CPU0_P2_RX_BUF_DN<7>
NC_J106_A5
I3C_BMC_SWB_BUF_SDA
P5E_CPU0_P3_RX_BUF_DN<1>
IO
THLF
IO
THLF
PCIE - CPU0_EXAMAX_P2/P3_X16
P5E_CPU0_P2_RX_BUF_DP<4>
P5E_CPU0_P2_RX_BUF_DN<4>
P5E_CPU0_P3_RX_BUF_DP<1>
P5E_CPU0_P3_RX_BUF_DP<5>
P5E_CPU0_P3_RX_BUF_DN<5>
P5E_CPU0_P2_RX_BUF_DP<5>
P5E_CPU0_P2_RX_BUF_DN<5>
P5E_CPU0_P3_TX_BUF_C_DP<6>
P5E_CPU0_P3_TX_BUF_C_DN<6>
P5E_CPU0_P3_RX_BUF_DP<6>
P5E_CPU0_P3_RX_BUF_DN<6>
P5E_CPU0_P2_RX_BUF_DP<6>
P5E_CPU0_P2_TX_BUF_C_DN<6>
P5E_CPU0_P2_TX_BUF_C_DP<5>
P5E_CPU0_P3_TX_BUF_C_DN<5>
P5E_CPU0_P2_RX_BUF_DN<3>
P5E_CPU0_P3_RX_BUF_DN<3>
P5E_CPU0_P2_TX_BUF_C_DN<3>
P5E_CPU0_P2_TX_BUF_C_DP<3>
P5E_CPU0_P2_TX_BUF_C_DN<4>
P5E_CPU0_P3_RX_BUF_DP<4>
P5E_CPU0_P3_RX_BUF_DN<4>
N4
N3
N2
N1
M4
M3
M2
M1
L4
L3
L2
L1
K4
K3
K2
K1
J4
J3
J2
J1
I4
I3
I2
I1
H4
H3
H2
H1
G4
G3
G2
G1
F4
F3
F2
F1
E4
E3
E2
E1
D4
D3
D2
D1
C4
C3
C2
C1
B4
B3
B2
B1
A4
A3
A2
A1
N8
N7
N6
N5
M8
M7
M6
M5
L8
L7
L6
L5
K8
K7
K6
K5
J8
J7
J6
J5
I8
I7
I6
I5
H8
H7
H6
H5
G8
G7
G6
G5
F8
F7
F6
F5
E8
E7
E6
E5
D8
D7
D6
D5
C8
C7
C6
C5
B8
B7
B6
B5
A8
A7
A6
A5
J106
J106
2/2
NM
1
LKJC D E F G H IA B
2
3
4
N4
M4
N3
M3
N2
M2
N1
M1
L1
L2
L3
L4
K1
K2
K3
K4
J1
J2
J3
J4
I1
I2
I3
I4
H1
H2
H3
H4
G1
G2
G3
G4
F1
F2
F3
F4
E1
E2
E3
E4
D1
D2
D3
D4
C1
C2
C3
C4
B1
B2
B3
B4
A1
A2
A3
A4
1/2
NM
5
LKJC D E F G H IA B
6
7
8
N8
M8
N7
M7
N6
M6
N5
M5
L5
L6
L7
L8
K5
K6
K7
K8
J5
J6
J7
J8
I5
I6
I7
I8
H5
H6
H7
H8
G5
G6
G7
G8
F5
F6
F7
F8
E5
E6
E7
E8
D5
D6
D7
D8
C5
C6
C7
C8
B5
B6
B7
B8
A5
A6
A7
A8
1
SHEETDATE
23
7 3 2 16 5 4
E
A
B
C
E
D
C
B
A
7 6 5 4
D
DEPARTMENT
SIZE
PROJECT DOCUMENT NUMBER REV
REVIEWER
DESIGNER
IN
OUT OUT
OUT
OUT
OUT
OUT
OUT
IN
IN
BI
IN
IN
OUT
OUT
OUT
OUT
OUT
OUT
IN
IN
IN
IN
OUT
OUT
OUT
OUT
IN
OUT
IN
IN
IN
IN
OUT
OUT
OUT
OUT
IN
IN
IN
IN
IN
OUT
OUT
OUT
IN
IN
OUT
IN
IN
IN
IN
OUT
OUT
OUT
OUT
OUT
IN
IN
IN
IN
IN
OUT
OUT
OUT
OUT
IN
IN
OUT
IN
IN
C



CPU0_P0_TX/RX<0-15> LANE REVERSAL
CPU0_P1_TX/RX<0-15> LANE REVERSAL
Thu Aug 24 14:09:44 2023
MB FABC V02
<NAME_2>
<NAME_1>
GTI
117 OF 365
P5E_CPU0_P0_TX_BUF_C_DN<13>
123
287
287
276
276
286
275
275
276
286
286
275
287
287
287
276
287
287
276
276
287
286
287
276
276
287
287
287
287
276
276
286
286
275
275
287
276
276
286
286
275
287
276
276
286
275
275
275
275
286
286
275
275
275
275
286
286
125
124
286
287
275
286
276
276
286
275
PRSNT_CABLE_SWB_B2_N
NC_J107_A1
P5E_CPU0_P1_TX_BUF_C_DP<9>
P5E_CPU0_P1_TX_BUF_C_DN<9>
P5E_CPU0_P0_TX_BUF_C_DP<9>
P5E_CPU0_P0_TX_BUF_C_DN<9>
P5E_CPU0_P1_RX_BUF_DP<9>
P5E_CPU0_P0_RX_BUF_DP<8>
P5E_CPU0_P0_RX_BUF_DN<8>
P5E_CPU0_P0_TX_BUF_C_DN<10>
P5E_CPU0_P1_RX_BUF_DP<10>
P5E_CPU0_P1_RX_BUF_DN<10>
P5E_CPU0_P0_RX_BUF_DN<14>
P5E_CPU0_P1_TX_BUF_C_DN<15>
NC_J107_N4
P5E_CPU0_P1_TX_BUF_C_DP<11>
P5E_CPU0_P1_TX_BUF_C_DN<11>
P5E_CPU0_P0_TX_BUF_C_DP<11>
P5E_CPU0_P1_TX_BUF_C_DP<8>
P5E_CPU0_P1_TX_BUF_C_DN<8>
P5E_CPU0_P0_TX_BUF_C_DP<8>
P5E_CPU0_P0_TX_BUF_C_DN<8>
P5E_CPU0_P1_TX_BUF_C_DP<10>
P5E_CPU0_P1_RX_BUF_DN<9>
P5E_CPU0_P1_TX_BUF_C_DN<10>
P5E_CPU0_P0_TX_BUF_C_DP<10>
P5E_CPU0_P0_TX_BUF_C_DN<11>
NC_J107_A5
P5E_CPU0_P1_TX_BUF_C_DP<12>
P5E_CPU0_P1_TX_BUF_C_DN<12>
P5E_CPU0_P1_TX_BUF_C_DP<13>
P5E_CPU0_P1_TX_BUF_C_DN<13>
P5E_CPU0_P0_TX_BUF_C_DP<13>
P5E_CPU0_P1_RX_BUF_DP<13>
P5E_CPU0_P1_RX_BUF_DN<13>
P5E_CPU0_P0_RX_BUF_DN<13>
P5E_CPU0_P0_RX_BUF_DP<13>
P5E_CPU0_P1_TX_BUF_C_DN<14>
P5E_CPU0_P0_TX_BUF_C_DP<14>
P5E_CPU0_P0_TX_BUF_C_DN<14>
P5E_CPU0_P1_RX_BUF_DP<14>
P5E_CPU0_P1_RX_BUF_DN<14>
P5E_CPU0_P0_RX_BUF_DP<14>
P5E_CPU0_P1_TX_BUF_C_DP<15>
P5E_CPU0_P0_TX_BUF_C_DP<15>
P5E_CPU0_P0_TX_BUF_C_DN<15>
P5E_CPU0_P1_RX_BUF_DP<15>
PCIE - CPU0_EXAMAX_P0/P1_X16
IO
THLFTHLF
IO
NC_J107_A3
NC_J107_N6
P5E_CPU0_P0_RX_BUF_DP<11>
P5E_CPU0_P0_RX_BUF_DN<11>
P5E_CPU0_P0_RX_BUF_DP<15>
P5E_CPU0_P0_RX_BUF_DN<15>
P5E_CPU0_P1_RX_BUF_DN<11>
P5E_CPU0_P1_RX_BUF_DP<11>
P5E_CPU0_P0_RX_BUF_DN<10>
P5E_CPU0_P0_RX_BUF_DP<10>
P5E_CPU0_P0_RX_BUF_DN<9>
P5E_CPU0_P0_RX_BUF_DP<9>
P5E_CPU0_P1_RX_BUF_DN<8>
P5E_CPU0_P1_RX_BUF_DP<8>
SWB_HSC_PWRGD
SWB_HSC_EN_BUF
P5E_CPU0_P1_RX_BUF_DN<15>
P5E_CPU0_P1_TX_BUF_C_DP<14>
P5E_CPU0_P0_RX_BUF_DN<12>
P5E_CPU0_P1_RX_BUF_DP<12>
P5E_CPU0_P0_TX_BUF_C_DN<12>
P5E_CPU0_P0_TX_BUF_C_DP<12>
P5E_CPU0_P1_RX_BUF_DN<12>
P5E_CPU0_P0_RX_BUF_DP<12>
N8
N7
N6
N5
M8
M7
M6
M5
L8
L7
L6
L5
K8
K7
K6
K5
J8
J7
J6
J5
I8
I7
I6
I5
H8
H7
H6
H5
G8
G7
G6
G5
F8
F7
F6
F5
E8
E7
E6
E5
D8
D7
D6
D5
C8
C7
C6
C5
B8
B7
B6
B5
A8
A7
A6
A5
N4
N3
N2
N1
M4
M3
M2
M1
L4
L3
L2
L1
K4
K3
K2
K1
J4
J3
J2
J1
I4
I3
I2
I1
H4
H3
H2
H1
G4
G3
G2
G1
F4
F3
F2
F1
E4
E3
E2
E1
D4
D3
D2
D1
C4
C3
C2
C1
B4
B3
B2
B1
A4
A3
A2
A1
J107 J107
1/2
NM
5
LKJC D E F G H IA B
6
7
8
N8
M8
N7
M7
N6
M6
N5
M5
L5
L6
L7
L8
K5
K6
K7
K8
J5
J6
J7
J8
I5
I6
I7
I8
H5
H6
H7
H8
G5
G6
G7
G8
F5
F6
F7
F8
E5
E6
E7
E8
D5
D6
D7
D8
C5
C6
C7
C8
B5
B6
B7
B8
A5
A6
A7
A8
2/2
NM
1
LKJC D E F G H IA B
2
3
4
N4
M4
N3
M3
N2
M2
N1
M1
L1
L2
L3
L4
K1
K2
K3
K4
J1
J2
J3
J4
I1
I2
I3
I4
H1
H2
H3
H4
G1
G2
G3
G4
F1
F2
F3
F4
E1
E2
E3
E4
D1
D2
D3
D4
C1
C2
C3
C4
B1
B2
B3
B4
A1
A2
A3
A4
1
SHEETDATE
23
7 3 2 16 5 4
E
A
B
C
E
D
C
B
A
7 6 5 4
D
DEPARTMENT
SIZE
PROJECT DOCUMENT NUMBER REV
REVIEWER
DESIGNER
IN
OUT
OUT
OUT
IN
OUT
OUT
OUT
OUT
IN
IN
IN
OUT
OUT
OUT
OUT
OUT
IN
IN
IN
IN
OUT
OUT
OUT
OUT
IN
IN
IN
IN
IN
OUT
OUT
OUT
OUTOUT
IN
IN
IN
IN
OUT
OUT
OUT
OUT
IN
IN
IN
IN
IN
IN
OUT
OUT
OUT
OUT
OUT
IN
IN
IN
IN
IN
OUT
OUT
OUT
OUT
IN
IN
IN
IN
C



CPU0_P1_TX/RX<0-15> LANE REVERSAL
CPU0_P0_TX/RX<0-15> LANE REVERSAL
Thu Aug 24 14:09:44 2023
GTI
<NAME_1>
<NAME_2>
V02MB FABC
118 OF 365
P5E_CPU0_P1_TX_BUF_C_DP<5>
123
287
276
276
275
286
125
275
286
276
287
287
286 286
286
286
275
275
275
286
275
276
286
275
276
287
287
275
275
286
276
287
276
276
287
287
276
287
287
286
286
276
276
287
287
275
286
286
276
275
275
125
275
287
276
286
286
276
287
275
125
126
287
275
275
286
276
276
287
PRSNT_CABLE_GPU_A3_N
P5E_CPU0_P1_TX_BUF_C_DP<0>
P5E_CPU0_P0_TX_BUF_C_DP<0>
P5E_CPU0_P0_TX_BUF_C_DN<1>
P5E_CPU0_P0_RX_BUF_DP<5>
P5E_CPU0_P1_RX_BUF_DN<5>
GPU_3V3IO_RSVD5_FFU
P5E_CPU0_P0_RX_BUF_DP<4>
P5E_CPU0_P1_RX_BUF_DP<4>
P5E_CPU0_P0_TX_BUF_C_DN<4>
P5E_CPU0_P1_TX_BUF_C_DN<4>
P5E_CPU0_P1_TX_BUF_C_DP<4>
P5E_CPU0_P1_RX_BUF_DP<5> P5E_CPU0_P1_RX_BUF_DN<1>
P5E_CPU0_P1_RX_BUF_DP<1>
P5E_CPU0_P1_RX_BUF_DN<7>
P5E_CPU0_P0_RX_BUF_DP<3>
NC_J108_N6
P5E_CPU0_P0_RX_BUF_DN<1>
P5E_CPU0_P0_RX_BUF_DN<3>
THLF
IO IO
THLF
PCIE - CPU0_EXAMAX_P0/P1_X16
P5E_CPU0_P1_RX_BUF_DN<3>
P5E_CPU0_P0_RX_BUF_DP<1>
P5E_CPU0_P0_TX_BUF_C_DP<4>
P5E_CPU0_P1_RX_BUF_DN<4>
P5E_CPU0_P0_RX_BUF_DN<4>
P5E_CPU0_P0_TX_BUF_C_DP<1>
P5E_CPU0_P1_TX_BUF_C_DN<1>
P5E_CPU0_P1_TX_BUF_C_DP<1>
NC_J108_N2
P5E_CPU0_P0_RX_BUF_DN<6>
P5E_CPU0_P0_RX_BUF_DP<6>
P5E_CPU0_P1_RX_BUF_DN<6>
P5E_CPU0_P0_TX_BUF_C_DP<6>
P5E_CPU0_P1_TX_BUF_C_DP<6>
P5E_CPU0_P0_TX_BUF_C_DN<5>
P5E_CPU0_P0_TX_BUF_C_DP<5>
P5E_CPU0_P1_TX_BUF_C_DN<5>
NC_J108_N4
P5E_CPU0_P0_TX_BUF_C_DP<3>
P5E_CPU0_P1_TX_BUF_C_DN<3>
P5E_CPU0_P1_TX_BUF_C_DP<3>
P5E_CPU0_P1_RX_BUF_DN<2>
P5E_CPU0_P1_RX_BUF_DP<2>
P5E_CPU0_P0_TX_BUF_C_DN<2>
P5E_CPU0_P0_TX_BUF_C_DP<2>
P5E_CPU0_P1_TX_BUF_C_DN<2>
P5E_CPU0_P1_TX_BUF_C_DP<2>
P5E_CPU0_P0_RX_BUF_DP<0>
P5E_CPU0_P1_RX_BUF_DN<0>
P5E_CPU0_P1_RX_BUF_DP<0>
P5E_CPU0_P0_TX_BUF_C_DN<0>
P5E_CPU0_P0_RX_BUF_DP<2>
P5E_CPU0_P0_RX_BUF_DN<2>
PRSNT_CABLE_GPU_A2_N
P5E_CPU0_P0_RX_BUF_DN<5>
P5E_CPU0_P1_TX_BUF_C_DN<6>
P5E_CPU0_P0_TX_BUF_C_DN<6>
P5E_CPU0_P1_RX_BUF_DP<6>
P5E_CPU0_P1_RX_BUF_DP<3>
P5E_CPU0_P0_TX_BUF_C_DN<3>
P5E_CPU0_P1_TX_BUF_C_DN<0>
P5E_CPU0_P0_RX_BUF_DN<0>
GPU_3V3IO_RSVD3_FFU
GPU_FPGA_OVERT_N
P5E_CPU0_P1_TX_BUF_C_DP<7>
P5E_CPU0_P0_RX_BUF_DP<7>
P5E_CPU0_P0_RX_BUF_DN<7>
P5E_CPU0_P1_RX_BUF_DP<7>
P5E_CPU0_P0_TX_BUF_C_DN<7>
P5E_CPU0_P0_TX_BUF_C_DP<7>
P5E_CPU0_P1_TX_BUF_C_DN<7>
N4
N3
N2
N1
M4
M3
M2
M1
L4
L3
L2
L1
K4
K3
K2
K1
J4
J3
J2
J1
I4
I3
I2
I1
H4
H3
H2
H1
G4
G3
G2
G1
F4
F3
F2
F1
E4
E3
E2
E1
D4
D3
D2
D1
C4
C3
C2
C1
B4
B3
B2
B1
A4
A3
A2
A1
N8
N7
N6
N5
M8
M7
M6
M5
L8
L7
L6
L5
K8
K7
K6
K5
J8
J7
J6
J5
I8
I7
I6
I5
H8
H7
H6
H5
G8
G7
G6
G5
F8
F7
F6
F5
E8
E7
E6
E5
D8
D7
D6
D5
C8
C7
C6
C5
B8
B7
B6
B5
A8
A7
A6
A5
J108J108
2/2
NM
1
LKJC D E F G H IA B
2
3
4
N4
M4
N3
M3
N2
M2
N1
M1
L1
L2
L3
L4
K1
K2
K3
K4
J1
J2
J3
J4
I1
I2
I3
I4
H1
H2
H3
H4
G1
G2
G3
G4
F1
F2
F3
F4
E1
E2
E3
E4
D1
D2
D3
D4
C1
C2
C3
C4
B1
B2
B3
B4
A1
A2
A3
A4
1/2
NM
5
LKJC D E F G H IA B
6
7
8
N8
M8
N7
M7
N6
M6
N5
M5
L5
L6
L7
L8
K5
K6
K7
K8
J5
J6
J7
J8
I5
I6
I7
I8
H5
H6
H7
H8
G5
G6
G7
G8
F5
F6
F7
F8
E5
E6
E7
E8
D5
D6
D7
D8
C5
C6
C7
C8
B5
B6
B7
B8
A5
A6
A7
A8
1
SHEETDATE
23
7 3 2 16 5 4
E
A
B
C
E
D
C
B
A
7 6 5 4
D
DEPARTMENT
SIZE
PROJECT DOCUMENT NUMBER REV
REVIEWER
DESIGNER
OUT
OUT
OUT
OUT
OUT
OUT
OUT
OUT
IN
IN
IN
IN
OUT
OUT
OUT
OUT
OUT
OUT
IN
IN
IN
IN
OUT
OUT
OUT
OUT
OUT
IN
IN
IN
IN
OUT
OUT
OUT
OUT
OUT
IN
IN
IN
IN
IN
OUT
OUT
OUT
OUT
IN
IN
IN
IN
IN
OUT
OUT
OUT
OUT
OUT
IN
IN
IN
IN
IN
OUT
OUT
OUT
OUT
IN
IN
IN
IN
IN
C



CPU1_P2_TX/RX<0-15> LANE REVERSAL
CPU1_P3_TX/RX<0-15> LANE REVERSAL
Thu Aug 24 14:09:44 2023 119 OF 365
MB FABC V02
<NAME_2>
<NAME_1>
GTI
SMB_BMC_SWB_BUF_SCL
P5E_CPU1_P3_RX_BUF_DP<12>
341
341
125
342
342
353
353
249
341
341
352
342
353
341
352
341
353
353
342
342
352
352
341
341
353
126
353
342
342
352
352
353
353
342
342
352
352
341
353
353
342
342
352
341
341
352
125
352
341
341
353
353
352
342
353
353
249
125
342
352
341
341
341
127
130
352
352
342
353
352
342
342
P5E_CPU1_P2_RX_BUF_DN<15>
P5E_CPU1_P2_RX_BUF_DP<15>
PRSNT_CABLE_GPU_B3_N
P5E_CPU1_P2_TX_BUF_C_DP<15>
P5E_CPU1_P2_TX_BUF_C_DN<15>
P5E_CPU1_P3_TX_BUF_C_DN<15>
P5E_CPU1_P3_TX_BUF_C_DP<15>
SMB_BMC_SWB_BUF_SDA
P5E_CPU1_P2_RX_BUF_DN<14>
P5E_CPU1_P2_RX_BUF_DP<14>
P5E_CPU1_P3_RX_BUF_DN<14>
P5E_CPU1_P2_TX_BUF_C_DN<14>
P5E_CPU1_P3_TX_BUF_C_DN<14>
P5E_CPU1_P2_RX_BUF_DN<13>
P5E_CPU1_P3_RX_BUF_DN<13>
P5E_CPU1_P2_RX_BUF_DP<13>
P5E_CPU1_P3_TX_BUF_C_DP<8>
P5E_CPU1_P3_TX_BUF_C_DN<8>
P5E_CPU1_P2_TX_BUF_C_DP<8>
P5E_CPU1_P2_TX_BUF_C_DN<8>
P5E_CPU1_P3_RX_BUF_DP<8>
P5E_CPU1_P3_RX_BUF_DN<8>
P5E_CPU1_P2_RX_BUF_DP<8>
P5E_CPU1_P2_RX_BUF_DN<8>
P5E_CPU1_P3_TX_BUF_C_DP<9>
GPU_FPGA_EROT_FATALERR_N
P5E_CPU1_P3_TX_BUF_C_DN<9>
P5E_CPU1_P2_TX_BUF_C_DP<9>
P5E_CPU1_P2_TX_BUF_C_DN<9>
P5E_CPU1_P3_RX_BUF_DP<9>
P5E_CPU1_P3_RX_BUF_DN<9>
P5E_CPU1_P3_TX_BUF_C_DP<10>
P5E_CPU1_P3_TX_BUF_C_DN<10>
P5E_CPU1_P2_TX_BUF_C_DP<10>
P5E_CPU1_P2_TX_BUF_C_DN<10>
P5E_CPU1_P3_RX_BUF_DP<10>
P5E_CPU1_P3_RX_BUF_DN<10>
P5E_CPU1_P2_RX_BUF_DN<10>
P5E_CPU1_P3_TX_BUF_C_DP<11>
P5E_CPU1_P3_TX_BUF_C_DN<11>
P5E_CPU1_P2_TX_BUF_C_DP<11>
P5E_CPU1_P2_TX_BUF_C_DN<11>
P5E_CPU1_P3_RX_BUF_DN<11>
P5E_CPU1_P2_RX_BUF_DP<11>
P5E_CPU1_P2_RX_BUF_DN<11>
P5E_CPU1_P3_RX_BUF_DP<11>
GPU_3V3IO_RSVD0_FFU
P5E_CPU1_P3_RX_BUF_DN<12>
P5E_CPU1_P2_RX_BUF_DP<12>
P5E_CPU1_P2_RX_BUF_DN<12>
P5E_CPU1_P3_TX_BUF_C_DP<13>
P5E_CPU1_P3_TX_BUF_C_DN<13>
P5E_CPU1_P2_TX_BUF_C_DN<12>
P5E_CPU1_P3_TX_BUF_C_DN<12>
P5E_CPU1_P3_TX_BUF_C_DP<12>
GPU_3V3IO_RSVD1_FFU
P5E_CPU1_P2_TX_BUF_C_DP<13>
P5E_CPU1_P3_RX_BUF_DP<14>
P5E_CPU1_P2_RX_BUF_DP<9>
P5E_CPU1_P2_RX_BUF_DN<9>
P5E_CPU1_P2_RX_BUF_DP<10>
BIC_MONITER
BMC_MONITER_BUF
THLF
IO
IO
THLF
PCIE - CPU1_EXAMAX_P2/P3_X16
P5E_CPU1_P3_RX_BUF_DN<15>
P5E_CPU1_P3_RX_BUF_DP<15>
P5E_CPU1_P2_TX_BUF_C_DP<14>
P5E_CPU1_P3_TX_BUF_C_DP<14>
P5E_CPU1_P3_RX_BUF_DP<13>
P5E_CPU1_P2_TX_BUF_C_DN<13>
P5E_CPU1_P2_TX_BUF_C_DP<12>
N4
N3
N2
N1
M4
M3
M2
M1
L4
L3
L2
L1
K4
K3
K2
K1
J4
J3
J2
J1
I4
I3
I2
I1
H4
H3
H2
H1
G4
G3
G2
G1
F4
F3
F2
F1
E4
E3
E2
E1
D4
D3
D2
D1
C4
C3
C2
C1
B4
B3
B2
B1
A4
A3
A2
A1
N8
N7
N6
N5
M8
M7
M6
M5
L8
L7
L6
L5
K8
K7
K6
K5
J8
J7
J6
J5
I8
I7
I6
I5
H8
H7
H6
H5
G8
G7
G6
G5
F8
F7
F6
F5
E8
E7
E6
E5
D8
D7
D6
D5
C8
C7
C6
C5
B8
B7
B6
B5
A8
A7
A6
A5
J109
J109
2/2
NM
1
LKJC D E F G H IA B
2
3
4
N4
M4
N3
M3
N2
M2
N1
M1
L1
L2
L3
L4
K1
K2
K3
K4
J1
J2
J3
J4
I1
I2
I3
I4
H1
H2
H3
H4
G1
G2
G3
G4
F1
F2
F3
F4
E1
E2
E3
E4
D1
D2
D3
D4
C1
C2
C3
C4
B1
B2
B3
B4
A1
A2
A3
A4
1/2
NM
5
LKJC D E F G H IA B
6
7
8
N8
M8
N7
M7
N6
M6
N5
M5
L5
L6
L7
L8
K5
K6
K7
K8
J5
J6
J7
J8
I5
I6
I7
I8
H5
H6
H7
H8
G5
G6
G7
G8
F5
F6
F7
F8
E5
E6
E7
E8
D5
D6
D7
D8
C5
C6
C7
C8
B5
B6
B7
B8
A5
A6
A7
A8
1
SHEETDATE
23
7 3 2 16 5 4
E
A
B
C
E
D
C
B
A
7 6 5 4
D
DEPARTMENT
SIZE
PROJECT DOCUMENT NUMBER REV
REVIEWER
DESIGNER
OUT
OUT
OUT
OUT
OUT
OUT
IN
IN
OUT
IN
IN
OUT
OUT
OUT
OUT
OUT
OUT
IN
IN
OUT
IN
IN
OUT
OUT
OUT
OUT
IN
IN
IN
IN
IN
OUT
IN
OUT
OUT
OUT
OUT
IN
IN
IN
OUT
IN
OUT
OUT
OUT
OUT
IN
IN
IN
IN
OUT
IN
IN
OUT
OUT
OUT
OUT
IN
IN
IN
IN
OUT
IN
OUT
OUT
OUT
IN
IN
IN
IN
BI
IN
C



CPU1_P3_TX/RX<0-15> LANE REVERSAL
CPU1_P2_TX/RX<0-15> LANE REVERSAL
Thu Aug 24 14:09:45 2023 120 OF 365
MB FABCGTI
<NAME_1>
<NAME_2>
V02
P5E_CPU1_P3_RX_BUF_DN<5>
P5E_CPU1_P3_TX_BUF_C_DN<5>
353
342
342
352
353
341
341
129
128
353
353
342
342
352
352
353
341
341
353
342
342
353
353
342
342
352
353
353
342
342
353
353
129
128
341
341
352
352
342
342
353
353
341
341
352
352
342
342
352
352
341
341
352
341
341
127
126
341
341
352
352
352
127
126
341
341
352
352
342
342
353
353
P5E_CPU1_P3_TX_BUF_C_DP<0>
P5E_CPU1_P2_TX_BUF_C_DP<0>
P5E_CPU1_P2_TX_BUF_C_DN<0>
P5E_CPU1_P3_RX_BUF_DP<0>
P5E_CPU1_P3_TX_BUF_C_DN<0>
P5E_CPU1_P2_RX_BUF_DP<0>
P5E_CPU1_P2_RX_BUF_DN<0>
GPU_FPGA_EROT_RECOV_BUF_N
GPU_FPGA_BOOT_EN_BUF
P5E_CPU1_P3_TX_BUF_C_DP<1>
P5E_CPU1_P3_TX_BUF_C_DN<1>
P5E_CPU1_P2_TX_BUF_C_DP<1>
P5E_CPU1_P2_TX_BUF_C_DN<1>
P5E_CPU1_P3_RX_BUF_DP<1>
P5E_CPU1_P3_RX_BUF_DN<1>
P5E_CPU1_P3_TX_BUF_C_DP<2>
P5E_CPU1_P2_RX_BUF_DN<1>
P5E_CPU1_P2_RX_BUF_DP<1>
P5E_CPU1_P3_TX_BUF_C_DN<2>
P5E_CPU1_P2_TX_BUF_C_DP<2>
P5E_CPU1_P2_TX_BUF_C_DN<2>
P5E_CPU1_P3_TX_BUF_C_DP<3>
P5E_CPU1_P3_TX_BUF_C_DN<3>
P5E_CPU1_P2_TX_BUF_C_DP<3>
P5E_CPU1_P2_TX_BUF_C_DN<3>
P5E_CPU1_P3_RX_BUF_DP<3>
P5E_CPU1_P3_TX_BUF_C_DP<5>
P5E_CPU1_P2_TX_BUF_C_DP<5>
P5E_CPU1_P2_TX_BUF_C_DN<5>
P5E_CPU1_P3_TX_BUF_C_DP<7>
P5E_CPU1_P3_TX_BUF_C_DN<7>
GPU_FPGA_EROT_RST_BUF_N
GPU_BASE_STBY_EN_BUF
P5E_CPU1_P2_RX_BUF_DN<6>
P5E_CPU1_P2_RX_BUF_DP<6>
P5E_CPU1_P3_RX_BUF_DN<6>
P5E_CPU1_P3_RX_BUF_DP<6>
P5E_CPU1_P2_TX_BUF_C_DN<6>
P5E_CPU1_P2_TX_BUF_C_DP<6>
P5E_CPU1_P3_TX_BUF_C_DN<6>
P5E_CPU1_P3_TX_BUF_C_DP<6>
P5E_CPU1_P2_RX_BUF_DN<5>
P5E_CPU1_P2_RX_BUF_DP<5>
P5E_CPU1_P3_RX_BUF_DP<5>
P5E_CPU1_P2_TX_BUF_C_DP<7>
P5E_CPU1_P2_TX_BUF_C_DN<7>
P5E_CPU1_P3_RX_BUF_DP<7>
P5E_CPU1_P3_RX_BUF_DN<7>
PCIE - CPU1_EXAMAX_P2/P3_X16
IO
THLF
THLF
IO
P5E_CPU1_P2_RX_BUF_DP<7>
P5E_CPU1_P2_RX_BUF_DN<7>
P5E_CPU1_P3_RX_BUF_DN<3>
P5E_CPU1_P2_RX_BUF_DP<3>
P5E_CPU1_P2_RX_BUF_DN<3>
FM_SMB_1_ALERT_GPU_N
GPU_HMC_PRSNT_N
P5E_CPU1_P2_RX_BUF_DN<2>
P5E_CPU1_P2_RX_BUF_DP<2>
P5E_CPU1_P3_RX_BUF_DN<2>
P5E_CPU1_P3_RX_BUF_DP<2>
P5E_CPU1_P3_RX_BUF_DN<0>
FM_SMB_2_ALERT_GPU_N
GPU_BASE_HMC_READY
P5E_CPU1_P2_RX_BUF_DN<4>
P5E_CPU1_P2_RX_BUF_DP<4>
P5E_CPU1_P3_RX_BUF_DN<4>
P5E_CPU1_P3_RX_BUF_DP<4>
P5E_CPU1_P2_TX_BUF_C_DN<4>
P5E_CPU1_P2_TX_BUF_C_DP<4>
P5E_CPU1_P3_TX_BUF_C_DN<4>
P5E_CPU1_P3_TX_BUF_C_DP<4>
N4
N3
N2
N1
M4
M3
M2
M1
L4
L3
L2
L1
K4
K3
K2
K1
J4
J3
J2
J1
I4
I3
I2
I1
H4
H3
H2
H1
G4
G3
G2
G1
F4
F3
F2
F1
E4
E3
E2
E1
D4
D3
D2
D1
C4
C3
C2
C1
B4
B3
B2
B1
A4
A3
A2
A1
N8
N7
N6
N5
M8
M7
M6
M5
L8
L7
L6
L5
K8
K7
K6
K5
J8
J7
J6
J5
I8
I7
I6
I5
H8
H7
H6
H5
G8
G7
G6
G5
F8
F7
F6
F5
E8
E7
E6
E5
D8
D7
D6
D5
C8
C7
C6
C5
B8
B7
B6
B5
A8
A7
A6
A5
J110
J110
2/2
NM
1
LKJC D E F G H IA B
2
3
4
N4
M4
N3
M3
N2
M2
N1
M1
L1
L2
L3
L4
K1
K2
K3
K4
J1
J2
J3
J4
I1
I2
I3
I4
H1
H2
H3
H4
G1
G2
G3
G4
F1
F2
F3
F4
E1
E2
E3
E4
D1
D2
D3
D4
C1
C2
C3
C4
B1
B2
B3
B4
A1
A2
A3
A4
1/2
NM
5
LKJC D E F G H IA B
6
7
8
N8
M8
N7
M7
N6
M6
N5
M5
L5
L6
L7
L8
K5
K6
K7
K8
J5
J6
J7
J8
I5
I6
I7
I8
H5
H6
H7
H8
G5
G6
G7
G8
F5
F6
F7
F8
E5
E6
E7
E8
D5
D6
D7
D8
C5
C6
C7
C8
B5
B6
B7
B8
A5
A6
A7
A8
1
SHEETDATE
23
7 3 2 16 5 4
E
A
B
C
E
D
C
B
A
7 6 5 4
D
DEPARTMENT
SIZE
PROJECT DOCUMENT NUMBER REV
REVIEWER
DESIGNER
OUT
OUT
OUT
OUT
OUT
OUT
IN
IN
OUT
IN
IN
OUT
OUT
OUT
OUT
OUT
OUT
IN
IN
OUT
IN
IN
OUT
OUT
OUT
OUT
IN
IN
IN
IN
IN
IN
IN
OUT
OUT
OUT
OUT
IN
IN
IN
IN
IN
OUT
OUT
OUT
OUT
IN
IN
IN
IN
IN
OUT
IN
OUT
OUT
OUT
OUT
IN
IN
IN
IN
OUT
IN
OUT
OUT
OUT
IN
IN
IN
IN
OUT
IN
C



CPU1_P1_TX/RX<0-15> LANE REVERSAL
CPU1_P0_TX/RX<0-15> LANE REVERSAL
Thu Aug 24 14:09:45 2023
MB FABC
121 OF 365
<NAME_1>
<NAME_2>
GTI V02
331
331
320
320
330
319
319
331
331
320
320
330
330
319
126
319
331
331
320
320
330
319
123246
130
331
331
320
320
123246
330
319
330
330
320
319
330
330
330
123246
123246
319
319
319
319
330
330
320
320
331
331
319
319
330
330
320
320
127
319
331
331
320
331
331
130
319
319
330
330
320
320
331
331
P5E_CPU1_P1_TX_BUF_C_DP<8>
P5E_CPU1_P1_TX_BUF_C_DN<8>
P5E_CPU1_P0_TX_BUF_C_DP<8>
P5E_CPU1_P0_TX_BUF_C_DN<8>
P5E_CPU1_P1_RX_BUF_DN<8>
P5E_CPU1_P0_RX_BUF_DP<8>
P5E_CPU1_P0_RX_BUF_DN<8>
P5E_CPU1_P1_TX_BUF_C_DP<9>
P5E_CPU1_P1_TX_BUF_C_DN<9>
P5E_CPU1_P0_TX_BUF_C_DP<9>
P5E_CPU1_P0_TX_BUF_C_DN<9>
P5E_CPU1_P1_RX_BUF_DP<9>
P5E_CPU1_P1_RX_BUF_DN<9>
P5E_CPU1_P0_RX_BUF_DP<9>
GPU_PRSNT_N
P5E_CPU1_P0_RX_BUF_DN<9>
P5E_CPU1_P1_TX_BUF_C_DP<12>
P5E_CPU1_P1_TX_BUF_C_DN<12>
P5E_CPU1_P0_TX_BUF_C_DP<12>
P5E_CPU1_P0_TX_BUF_C_DN<12>
P5E_CPU1_P1_RX_BUF_DN<12>
P5E_CPU1_P0_RX_BUF_DP<12>
GPU_PEX_STRAP0
GPU_FPGA_RST_R_BUF_N
P5E_CPU1_P1_TX_BUF_C_DP<15>
P5E_CPU1_P1_TX_BUF_C_DN<15>
P5E_CPU1_P0_TX_BUF_C_DP<15>
P5E_CPU1_P0_TX_BUF_C_DN<15>
GPU_BASE_ID1
P5E_CPU1_P1_RX_BUF_DP<8>
P5E_CPU1_P0_RX_BUF_DN<11>
P5E_CPU1_P1_RX_BUF_DN<11>
P5E_CPU1_P1_RX_BUF_DP<11>
P5E_CPU1_P0_TX_BUF_C_DN<11>
P5E_CPU1_P0_RX_BUF_DP<11>
P5E_CPU1_P1_RX_BUF_DP<12>
P5E_CPU1_P1_RX_BUF_DP<15>
P5E_CPU1_P1_RX_BUF_DN<15>
PCIE - CPU1_EXAMAX_P0/P1_X16
THLF
IO
THLF
IO
GPU_BASE_ID0
GPU_PEX_STRAP1
P5E_CPU1_P0_RX_BUF_DN<15>
P5E_CPU1_P0_RX_BUF_DP<15>
P5E_CPU1_P0_RX_BUF_DN<14>
P5E_CPU1_P0_RX_BUF_DP<14>
P5E_CPU1_P1_RX_BUF_DN<14>
P5E_CPU1_P1_RX_BUF_DP<14>
P5E_CPU1_P0_TX_BUF_C_DN<14>
P5E_CPU1_P0_TX_BUF_C_DP<14>
P5E_CPU1_P1_TX_BUF_C_DN<14>
P5E_CPU1_P1_TX_BUF_C_DP<14>
P5E_CPU1_P0_RX_BUF_DN<13>
P5E_CPU1_P0_RX_BUF_DP<13>
P5E_CPU1_P1_RX_BUF_DN<13>
P5E_CPU1_P1_RX_BUF_DP<13>
P5E_CPU1_P0_TX_BUF_C_DN<13>
P5E_CPU1_P0_TX_BUF_C_DP<13>
FM_GPU_PWRGD
P5E_CPU1_P0_RX_BUF_DN<12>
P5E_CPU1_P1_TX_BUF_C_DP<13>
P5E_CPU1_P1_TX_BUF_C_DN<13>
P5E_CPU1_P0_TX_BUF_C_DP<11>
P5E_CPU1_P1_TX_BUF_C_DN<11>
P5E_CPU1_P1_TX_BUF_C_DP<11>
FM_GPU_PWR_EN_R_BUF
P5E_CPU1_P0_RX_BUF_DN<10>
P5E_CPU1_P0_RX_BUF_DP<10>
P5E_CPU1_P1_RX_BUF_DN<10>
P5E_CPU1_P1_RX_BUF_DP<10>
P5E_CPU1_P0_TX_BUF_C_DN<10>
P5E_CPU1_P0_TX_BUF_C_DP<10>
P5E_CPU1_P1_TX_BUF_C_DN<10>
P5E_CPU1_P1_TX_BUF_C_DP<10>
N4
N3
N2
N1
M4
M3
M2
M1
L4
L3
L2
L1
K4
K3
K2
K1
J4
J3
J2
J1
I4
I3
I2
I1
H4
H3
H2
H1
G4
G3
G2
G1
F4
F3
F2
F1
E4
E3
E2
E1
D4
D3
D2
D1
C4
C3
C2
C1
B4
B3
B2
B1
A4
A3
A2
A1
N8
N7
N6
N5
M8
M7
M6
M5
L8
L7
L6
L5
K8
K7
K6
K5
J8
J7
J6
J5
I8
I7
I6
I5
H8
H7
H6
H5
G8
G7
G6
G5
F8
F7
F6
F5
E8
E7
E6
E5
D8
D7
D6
D5
C8
C7
C6
C5
B8
B7
B6
B5
A8
A7
A6
A5
J111J111
2/2
NM
1
LKJC D E F G H IA B
2
3
4
N4
M4
N3
M3
N2
M2
N1
M1
L1
L2
L3
L4
K1
K2
K3
K4
J1
J2
J3
J4
I1
I2
I3
I4
H1
H2
H3
H4
G1
G2
G3
G4
F1
F2
F3
F4
E1
E2
E3
E4
D1
D2
D3
D4
C1
C2
C3
C4
B1
B2
B3
B4
A1
A2
A3
A4
1/2
NM
5
LKJC D E F G H IA B
6
7
8
N8
M8
N7
M7
N6
M6
N5
M5
L5
L6
L7
L8
K5
K6
K7
K8
J5
J6
J7
J8
I5
I6
I7
I8
H5
H6
H7
H8
G5
G6
G7
G8
F5
F6
F7
F8
E5
E6
E7
E8
D5
D6
D7
D8
C5
C6
C7
C8
B5
B6
B7
B8
A5
A6
A7
A8
1
SHEETDATE
23
7 3 2 16 5 4
E
A
B
C
E
D
C
B
A
7 6 5 4
D
DEPARTMENT
SIZE
PROJECT DOCUMENT NUMBER REV
REVIEWER
DESIGNER
OUT
OUT
OUT
OUT
OUT
IN
OUT
IN
OUT
IN
IN
IN
OUT
OUT
OUT
OUT
OUT
IN
IN
OUT
IN
IN
OUT
OUT
OUT
OUT
IN
IN
IN
IN
IN
OUT
OUT
OUT
OUT
OUT
OUT
IN
IN
IN
IN
IN
OUT
OUT
OUT
IN
OUT
IN
IN
IN
IN
OUT
OUT
IN
OUT
OUT
OUT
IN
IN
IN
IN
IN
OUT
OUT
OUT
OUT
IN
IN
IN
IN
OUT
OUT
C



P/N SWAP
P/N SWAP
P/N SWAP
CPU1_P0_TX/RX<0-15> LANE REVERSAL
CPU1_P1_TX/RX<0-15> LANE REVERSAL
Thu Aug 24 14:09:45 2023
MB FABCGTI
<NAME_1>
<NAME_2>
V02
122 OF 365
P5E_CPU1_P1_RX_BUF_DN<5>
331
331
55
55
320
320
330
330
319
319
128
331
331
320
330
249
249
331
55
55
331
320
320
319
319
123124
129
249
331
320
320
331
28
28
249
330
330
320
320
331
330
330
319
113
113
320
331
331
331
53
53
53
53
128
319
319
330
330
320
320
331
53
53
53
53
319
319
330
330
320
331
331
113
113
126
128
319
319
319
320
330
319
319
235
235
234
127
234
319
319
330
330
123
330
330
320
320
331
P5E_CPU1_P1_TX_BUF_C_DP<0>
P5E_CPU1_P1_TX_BUF_C_DN<0>
CLK_100M_CPU1_CLK01_DN
CLK_100M_CPU1_CLK01_DP
P5E_CPU1_P0_TX_BUF_C_DP<0>
P5E_CPU1_P0_TX_BUF_C_DN<0>
P5E_CPU1_P1_RX_BUF_DP<0>
P5E_CPU1_P1_RX_BUF_DN<0>
P5E_CPU1_P0_RX_BUF_DP<0>
P5E_CPU1_P0_RX_BUF_DN<0>
RST_PERST_2_SWB_BUF_N
P5E_CPU1_P1_TX_BUF_C_DP<1>
P5E_CPU1_P1_TX_BUF_C_DN<1>
P5E_CPU1_P0_TX_BUF_C_DN<1>
P5E_CPU1_P1_RX_BUF_DN<1>
SMB_2_BMC_GPU_BUF_SDA
SMB_2_BMC_GPU_BUF_SCL
P5E_CPU1_P1_TX_BUF_C_DP<2>
CLK_100M_CPU1_CLK11_DN
CLK_100M_CPU1_CLK11_DP
P5E_CPU1_P1_TX_BUF_C_DN<2>
P5E_CPU1_P0_TX_BUF_C_DP<2>
P5E_CPU1_P0_TX_BUF_C_DN<2>
P5E_CPU1_P0_RX_BUF_DP<2>
P5E_CPU1_P0_RX_BUF_DN<2>
HGX_DETECT_N_ISO
GPU_NVS_PWR_BRAKE_N_BUF
SMB_1_BMC_GPU_BUF_SDA
P5E_CPU1_P1_TX_BUF_C_DP<3>
P5E_CPU1_P0_TX_BUF_C_DN<3>
P5E_CPU1_P0_TX_BUF_C_DP<3>
P5E_CPU1_P1_TX_BUF_C_DN<3>
CLK_100M_CPU0_CLK11_DN
CLK_100M_CPU0_CLK11_DP
SMB_1_BMC_GPU_BUF_SCL
P5E_CPU1_P1_RX_BUF_DN<2>
P5E_CPU1_P1_RX_BUF_DP<2>
P5E_CPU1_P0_TX_BUF_C_DN<4>
P5E_CPU1_P0_TX_BUF_C_DP<4>
P5E_CPU1_P1_TX_BUF_C_DN<4>
P5E_CPU1_P1_RX_BUF_DP<4>
P5E_CPU1_P1_RX_BUF_DN<4>
P5E_CPU1_P0_RX_BUF_DN<4>
P2E_MB_BMC_TX_BUF_C_DN<0>
P2E_MB_BMC_TX_BUF_C_DP<0>
P5E_CPU1_P0_TX_BUF_C_DN<5>
P5E_CPU1_P1_TX_BUF_C_DP<6>
P5E_CPU1_P1_TX_BUF_C_DP<7>
P5E_CPU1_P1_TX_BUF_C_DN<7>
P3E_CPU1_P5_RX_DN<0>
P3E_CPU1_P5_RX_DP<0>
P3E_CPU1_P5_TX_C_DN<0>
P3E_CPU1_P5_TX_C_DP<0>
RST_PERST_0_SWB_BUF_N
P5E_CPU1_P0_RX_BUF_DN<6>
P5E_CPU1_P0_RX_BUF_DP<6>
P5E_CPU1_P1_RX_BUF_DN<6>
P5E_CPU1_P1_RX_BUF_DP<6>
P5E_CPU1_P0_TX_BUF_C_DN<6>
P5E_CPU1_P0_TX_BUF_C_DP<6>
P5E_CPU1_P1_TX_BUF_C_DN<6>
P3E_CPU1_P5_RX_DN<1>
P3E_CPU1_P5_RX_DP<1>
P3E_CPU1_P5_TX_C_DP<1>
P3E_CPU1_P5_TX_C_DN<1>
P5E_CPU1_P0_RX_BUF_DN<5>
P5E_CPU1_P0_RX_BUF_DP<5>
P5E_CPU1_P1_RX_BUF_DP<5>
P5E_CPU1_P0_TX_BUF_C_DP<5>
P5E_CPU1_P1_TX_BUF_C_DN<5>
P5E_CPU1_P1_TX_BUF_C_DP<5>
P2E_MB_BMC_RX_DP<0>
P2E_MB_BMC_RX_DN<0>
GPU_FPGA_THERM_OVERT_N
RST_PERST_1_SWB_BUF_N
P5E_CPU1_P0_RX_BUF_DP<4>
P5E_CPU1_P0_RX_BUF_DP<7>
P5E_CPU1_P0_RX_BUF_DN<7>
P5E_CPU1_P0_TX_BUF_C_DP<1>
P5E_CPU1_P1_RX_BUF_DP<1>
P5E_CPU1_P0_RX_BUF_DP<1>
P5E_CPU1_P0_RX_BUF_DN<1>
USB2_HUB_BUF_SWB_DN
USB2_HUB_BUF_SWB_DP
NC_J112_O5
NC_J112_S5
CLK_100M_GPU_FPGA_DN
NC_J112_N2
NC_J112_O2
GPU_FPGA_READY
CLK_100M_GPU_FPGA_DP
IO
THLF
THLF
IO
PCIE - CPU1_EXAMAX_P0/P1_X16
P5E_CPU1_P0_RX_BUF_DN<3>
P5E_CPU1_P0_RX_BUF_DP<3>
P5E_CPU1_P1_RX_BUF_DN<3>
P5E_CPU1_P1_RX_BUF_DP<3>
PRSNT_SWB_N
P5E_CPU1_P1_RX_BUF_DN<7>
P5E_CPU1_P1_RX_BUF_DP<7>
P5E_CPU1_P0_TX_BUF_C_DN<7>
P5E_CPU1_P0_TX_BUF_C_DP<7>
NC_J112_R5
NC_J112_P5
P5E_CPU1_P1_TX_BUF_C_DP<4>
T4
T3
T2
T1
S4
S3
S2
S1
R4
R3
R2
R1
Q4
Q3
Q2
Q1
P4
P3
P2
P1
O4
O3
O2
O1
N4
N3
N2
N1
M4
M3
M2
M1
L4
L3
L2
L1
K4
K3
K2
K1
J4
J3
J2
J1
I4
I3
I2
I1
H4
H3
H2
H1
G4
G3
G2
G1
F4
F3
F2
F1
E4
E3
E2
E1
D4
D3
D2
D1
C4
C3
C2
C1
B4
B3
B2
B1
A4
A3
A2
A1
T8
T7
T6
T5
S8
S7
S6
S5
R8
R7
R6
R5
Q8
Q7
Q6
Q5
P8
P7
P6
P5
O8
O7
O6
O5
N8
N7
N6
N5
M8
M7
M6
M5
L8
L7
L6
L5
K8
K7
K6
K5
J8
J7
J6
J5
I8
I7
I6
I5
H8
H7
H6
H5
G8
G7
G6
G5
F8
F7
F6
F5
E8
E7
E6
E5
D8
D7
D6
D5
C8
C7
C6
C5
B8
B7
B6
B5
A8
A7
A6
A5
J112
J112
1/2
TSRQPONM
5
LKJC D E F G H IA B
6
7
8
T8
S8
R8
Q8
P8
O8
T7
S7
R7
Q7
P7
O7
T6
S6
R6
Q6
P6
O6
T5
S5
R5
Q5
P5
O5
N8
M8
N7
M7
N6
M6
N5
M5
L5
L6
L7
L8
K5
K6
K7
K8
J5
J6
J7
J8
I5
I6
I7
I8
H5
H6
H7
H8
G5
G6
G7
G8
F5
F6
F7
F8
E5
E6
E7
E8
D5
D6
D7
D8
C5
C6
C7
C8
B5
B6
B7
B8
A5
A6
A7
A8
2/2
TSRQPONM
1
LKJC D E F G H IA B
2
3
4
T4
S4
R4
Q4
P4
O4
T3
S3
R3
Q3
P3
O3
T2
S2
R2
Q2
P2
O2
T1
S1
R1
Q1
P1
O1
N4
M4
N3
M3
N2
M2
N1
M1
L1
L2
L3
L4
K1
K2
K3
K4
J1
J2
J3
J4
I1
I2
I3
I4
H1
H2
H3
H4
G1
G2
G3
G4
F1
F2
F3
F4
E1
E2
E3
E4
D1
D2
D3
D4
C1
C2
C3
C4
B1
B2
B3
B4
A1
A2
A3
A4
1
SHEETDATE
23
7 3 2 16 5 4
E
A
B
C
E
D
C
B
A
7 6 5 4
D
DEPARTMENT
SIZE
PROJECT DOCUMENT NUMBER REV
REVIEWER
DESIGNER
OUT
OUT
IN
IN
IN
IN
IN
IN
BI
IN
OUT
IN
IN
OUT
OUT
OUT
OUT
IN
IN
IN
IN
OUT
IN
IN
IN
BI
OUT
OUT
OUT
OUT
IN
IN
IN
IN
OUT
IN
IN
OUT
IN
OUT
OUT
OUT
IN
IN
IN
IN
IN
IN
IN
IN
OUT
OUT
OUT
OUT
OUT
IN
IN
IN
IN
OUT
OUT
IN
IN
IN
IN
OUT
OUT
OUT
OUT
OUT
IN
IN
OUT
IN
IN
IN
OUT
IN
IN
OUT
OUT
OUT
OUT
IN
IN
IN
IN
IN
OUT
OUT
IN
IN
IN
OUT
OUT
OUT
OUT
IN
C



Thu Aug 24 14:09:09 2023<NAME_2>
<NAME_1>
MB FABCGTI V02
123 OF 365
P3V3_AUX
P3V3_AUX
P3V3_AUX
P3V3_AUX
P3V3_AUX
P3V3_AUX
P3V3_AUX
P3V3_AUX
P3V3_AUX
P3V3_AUX
P3V3_AUX
P3V3_AUX
116
122
117
246
246
118
81 246
124122
121246
121246
121246
121246
246
CHIP
50V
5%
EMPTY
PRSNT_CABLE_SWB_B1_N
PRSNT_SWB_N
PRSNT_CABLE_SWB_B2_N
PRSNT_CABLE_SWB_B2
PRSNT_SWB
PRSNT_CABLE_SWB_B1
PRSNT_CABLE_SWB_B1_ISO_N
PRSNT_CABLE_SWB_B2_ISO_N
PRSNT_CABLE_GPU_A3_N
PRSNT_CABLE_GPU_A3
PRSNT_SWB_ISO_N
HGX_DETECT_N_ISO
GPU_PEX_STRAP0
GPU_PEX_STRAP1
GPU_BASE_ID1
GPU_BASE_ID0
PRSNT_CABLE_GPU_A3_ISO_N
1%
1/16W
100K
0402LF
EMPTY
PJT138K
IC
SMLF
1%
CHIP
1/16W
10K
0402LF
0402LF
1%
100K
EMPTY
1/16W
10K
CHIP
1/16W
0402LF
1%
1%
0402LF
1/16W
10K
CHIP
5%
1/16W
CHIP
4.7K
0402LF
0402LF
EMPTY
1/16W
1%
100K
IC
PJT138K
SMLF
IC
PJT138K
SMLF
0402LF
1/16W
CHIP
4.7K
5%
4.7K
5%
1/16W
CHIP
0402LF
SMLF
PJT138K
IC
PJT138K
SMLF
IC
IC
PJT138K
SMLF
5%
1/16W
CHIP
0402LF
4.7K
1000PF
0402
5%
0402
EMPTY
50V
1000PF
5%
EMPTY
0402
50V
1000PF
100K
1%
EMPTY
1/16W
0402LF
1%
1/16W
CHIP
0402LF
10K
IC
SMLF
PJT138K
5%
CHIP
4.7K
1/16W
0402LF
4.7K
5%
1/16W
0402LF
1/16W
CHIP
4.7K
5%
0402LF
0402LF 0 CHIP 1/16W5%
1/16W5%0 EMPTY0402LF
0402LF CHIP 1/16W0 5%
0402LF 0 CHIP 1/16W5%
1%
E MP TY
1/16W 0402LF
100
50V
0402
EMPTY
5%
1000PF
CHIP
4.7K
5%
1/16W
0402LF
IC
PJT138K
SMLF
EXAMAX_PRESENT
G2
G1
G2
G2
G1
G1
G2
G1
S2 D2
D1S1
S2 D2
S2 D2
D1S1
D1S1
S2 D2
D1S1
R2656
R3442
R3443
R3440
R3441
R9016R8002
R9004
R9008
5
2
5
2
5
2
5
2
4 3
1 6
4 3
1 6
4 3
1 6
4 3
1 6
Q9002
Q9002
Q9000
Q8000
Q9001
Q9001
Q8000
Q9000
2
1
2
1
21
21
21
21
21
2
1
2
1
2
1
2
1
R9014
2
1
2
1
2
1
2
1
2
1
2
1
2
1
R9006
2
1
R4058
2
1
2
1
2
1
2
1
2
1
2
1
R9002
1
SHEETDATE
23
7 3 2 16 5 4
E
A
B
C
E
D
C
B
A
7 6 5 4
D
DEPARTMENT
SIZE
PROJECT DOCUMENT NUMBER REV
REVIEWER
DESIGNER
OUT
IN
IN
OUT
OUT
IN
OUT
OUT
OUT
OUT
OUT
OUT
IN
R9017
C9002
R8003
R9015
C9000
C9001
C8000
R9005
R9003
R8001
R9007
R9009
C



20220105 CHANGE PIN3 CONNECT TO GND
20211130 CHANGE FOR GPU/BD RSVD PIN
PUSH-PULL OUTPUT
Thu Aug 24 14:09:09 2023
MB FABC
<NAME_2>
<NAME_1>
GTI V02
124 OF 365
P3V3_AUX
P3V3_AUX
P3V3_AUX
P3V3_AUX
P3V3_AUX
P3V3_AUX
P3V3_AUX
P3V3_AUX
P3V3_AUX
P3V3_AUX
P3V3_AUX
P3V3_AUX
P3V3_AUX
P3V3_AUX
P3V3_AUX
81
123 122
115
81
81
115
115
81
81
117
EMPTY
PJT138K
SMLF
0402
25V
HGX_DETECT_N
PJT138K
1%
1K
0402LF
CHIP
1/16W
HGX_DETECT_N_ISO
10%
0.1UF
IC
IC
0402
X7R
0.1UF
25V
IC
0.1UF 74LVC2G17GW
1%
EMPTY
0402LF
5%
SMLF
IC
SMLF
EXAMAX_ISO (1/7)
PJT138K
4.7K
NC_U316_2Y
IC
GPU_3V3IO_RSVD4
GPU_3V3IO_RSVD1_ISO
GPU_3V3IO_RSVD4_ISO
GPU_3V3IO_RSVD1
GPU_3V3IO_RSVD1_N
GPU_3V3IO_RSVD3
GPU_3V3IO_RSVD3_N
GPU_3V3IO_RSVD4_N
0402LF
CHIP
1/16W
100K
SWB_HSC_EN
HGX_DETECT
GPU_3V3IO_RSVD3_ISO
SMLF
PJT138K
1/16W0402LF
E MP TY5%0
0402LF 1/16W
E MP TY5%0
0402LF
5%0
1/16W
E MP TY
0402LF
4.7K
5%
1/16W
EMPTY
0.1UF
25V
X 7R
0402
10%
E MP TY
1/16W
1%
100K
0402LF
E MP TY
1/16W
1%
100K
0402LF
IC
SMLF
0402LF
CHIP
0402LF
CHIP
1/16W
4.7K
5%
PJT138K
SMLF
IC
CHIP
4.7K
1/16W
0402LF
5%
PJT138K
SMLF
SMLF
IC
PJT138K
0402LF
CHIP
1/16W
4.7K
5%
SMLF
PJT138K
IC
0402LF
1/16W
54.9K
EMPTY
1%
100K
0402LF
E MP TY
1%
1/16W
0402LF
EMPTY
1/16W
54.9K
1%
E MP TY
1%
100K
1/16W
0402LF
0402LF
EMPTY
1/16W
1%
54.9K
1/16W
100K
1%
0402LF
E MP TY
1/16W
CHIP
SWB_HSC_EN_BUF_R SWB_HSC_EN_BUF49.9
0402LF
0402LF
1/16W
CHIP
100K
1%
CHIP
1/16W
0402LF
100K
1%
1/16W
0402LF
CHIP
100K
1%
4.7K
5%
1/16W
1%
1/16W
EMPTY
0402LF
100K
10%
0.1UF
25V
10%
X7R
0402
25V
10%
X7R
0402
G1
G2
G2
G2
G1
G2
G1
G1
D1S1
S2 D2 S2 D2
S2 D2
D1S1
S2 D2
D1S1
D1S1
C6
R4546
R4549
R4545
R4167
R4169
R4168
R4164
R4166
R4165
4
6
3
1
2
5
5
5
2
5
2
2
52
1 6
4 3 4 34 3
1 6
4 3
1 61 6
U316
Q148
Q148
Q135
Q137
Q135
Q136
Q137
Q136
B0
A1
A0
B1
GND VCC
2
1
2
1
21R4570
21R4571
21R4569
2
1
2
1
21R45502
1 C8
2
1
2
1
2
1
2
1
2
1
2
1
2
1
2
1
2
1
2
1
2
1
2
1
2
1
2
1
2
1
2
1
2
1
2
1
2
1
2
1
1
SHEETDATE
23
7 3 2 16 5 4
E
A
B
C
E
D
C
B
A
7 6 5 4
D
DEPARTMENT
SIZE
PROJECT DOCUMENT NUMBER REV
REVIEWER
DESIGNER
OUTIN
IN
OUT
IN
OUT
OUT
OUT
IN
IN
R4555
R4547
R4548
R4543
R4544
C4
C7
C5
R4158
R4159
R4162
R4163
R4160
R4161
C



20220103 ADD SWB_HSC_PWRGD
20211130 CHANGE FOR GPU/BD RSVD PIN
Thu Aug 24 14:09:54 2023
<NAME_1>
V02
125 OF 365
MB FABC
<NAME_2>
GTI
P3V3_AUX
P3V3_AUX
P3V3_AUX
P3V3_AUX
P3V3_AUX
P3V3_AUX
P3V3_AUX
P3V3_AUX
P3V3_AUX
P3V3_AUX
P3V3_AUX
P3V3_AUX
P3V3_AUX
P3V3_AUX
P3V3_AUX
P3V3_AUX
P3V3_AUX
P3V3_AUX
P3V3_AUX
P3V3_AUX
P3V3_AUX
P3V3_AUX
P3V3_AUX
P3V3_AUX
117
116
81 246
81
119
119
119
80 246
81
81
118
118
118
81
81 246
80
PRSNT_CABLE_GPU_A1
SWB_HSC_PWRGD
SWB_HSC_PWRGD_N
PRSNT_CABLE_GPU_B3
GPU_3V3IO_RSVD0_FFU_N
GPU_3V3IO_RSVD5_FFU_N
PRSNT_CABLE_GPU_A2
GPU_3V3IO_RSVD3_FFU_N
GPU_3V3IO_RSVD1_FFU_N
PRSNT_CABLE_GPU_A1_N
PRSNT_CABLE_GPU_A1_ISO_N
SWB_HSC_PWRGD_ISO
PRSNT_CABLE_GPU_B3_N
GPU_3V3IO_RSVD1_FFU
GPU_3V3IO_RSVD0_FFU
PRSNT_CABLE_GPU_B3_ISO_N
GPU_3V3IO_RSVD1_FFU_ISO
GPU_3V3IO_RSVD0_FFU_ISO
GPU_3V3IO_RSVD5_FFU
PRSNT_CABLE_GPU_A2_N
GPU_3V3IO_RSVD3_FFU
GPU_3V3IO_RSVD5_FFU_ISO
PRSNT_CABLE_GPU_A2_ISO_N
GPU_3V3IO_RSVD3_FFU_ISO
1/16W
E MP TY
100K
1%
0402LF
0402LF
10K
1%
1/16W
CHIP
IC
SMLF
PJT138K
4.7K
5%
1/16W
0402LF
CHIP
SMLF
PJT138K
IC
CHIP
1/16W
0402LF
1%
100K
0402
10%
25V
0.1UF
X7R
CHIP
1/16W
100K
0402LF
1%
1%
E MP TY
1/16W
100K
0402LF SMLF
IC
PJT138K
CHIP
5%
4.7K
0402LF
1/16W
IC
PJT138K
SMLF
0402
X7R
10%
25V
0.1UF
E MP TY
100K
1%
1/16W
0402LF
CHIP
1/16W
10K
0402LF
1%
1/16W
0402LF
100K
1%
E MP TY
PJT138K
SMLF
IC
1/16W
E MP TY
0402LF
5%0
0402LF
4.7K
CHIP
5%
1/16W
IC
SMLF
PJT138K
0402LF 1/16W
E MP TY0 5%
54.9K
1%
1/16W
0402LF
EMPTY
0402LF
100K
1%
1/16W
E MP TY
0402LF
1%
54.9K
1/16W
EMPTY
4.7K
CHIP
1/16W
0402LF
5%
0402LF
E MP TY
1/16W
0 5%
SMLF
PJT138K
IC
0402LF
CHIP
1/16W
5%
4.7K
PJT138K
IC
SMLF
0402LF
1/16W
CHIP
100K
1%
0.1UF
25V
0402
X7R
10%
1%
100K
1/16W
0402LF
CHIP
IC
PJT138K
SMLF
1%
1/16W
CHIP
0402LF
100K
0.1UF
0402
25V
10%
X7R
0402
25V
X7R
10%
0.1UF
1/16W
5% E MP TY0
0402LF
100K
1/16W
E MP TY
1%
0402LF
EMPTY
0402LF
1/16W
1%
54.9K
100K
E MP TY
0402LF
1%
1/16W
10K
1%
CHIP
1/16W
0402LF
0402LF
E MP TY
100K
1%
1/16W
1/16W
EMPTY
0402LF
54.9K
1%
IC
PJT138K
SMLF
4.7K
5%
0402LF
1/16W
CHIP
1/16W
0 E MP TY5%
0402LF
CHIP
0402LF
1/16W
100K
1%
IC
PJT138K
SMLF
0402LF
1/16W
CHIP
100K
1%
PJT138K
SMLF
IC
0402LF
CHIP
1/16W
4.7K
5%
IC
SMLF
PJT138K
1/16W0402LF
5%0 E MP TY
IC
SMLF
PJT138K
0402LF
CHIP
1/16W
100K
1%
SMLF
PJT138K
IC
CHIP
0402LF
1/16W
4.7K
5%
5%0 E MP TY
1/16W0402LF
CHIP
0402LF
1/16W
1%
100K
0.1UF
X7R
0402
10%
25V
X7R
0.1UF
25V
10%
0402
X7R
0402
10%
0.1UF
25V
IC
SMLF
PJT138K
EXAMAX_ISO (2/7)
G1
G1
G1
G1
G2
G2
G1
G2
G1
G1
G2
G2
G2
G2
G1
G2
D1S1
D1S1
D1S1
D1S1
S2 D2
S2 D2
D1S1
S2 D2
D1S1
D1S1
S2 D2 S2 D2
S2 D2
S2 D2
D1S1
S2 D2
R4140
R4142
R4141
R4561
R4137
R4128
R4139
R4138
R4130
R4129
R4560
R4156
R4125
R4127
R4126
R4155
5
5
5
5
2
2
2
2
5
5
2
5
2
2
5
2
4 3 4 34 34 3
1 61 61 61 6
4 34 3
1 6
4 3
1 61 6
4 3
1 6
Q146
Q130
Q133
Q129
Q130
Q133
Q129
Q146
Q128
Q131
Q128
Q132
Q131
Q132
Q134
Q134
2
1
2
1
2
1
2
1
2
1
2
1
2
1
2
1
21R4577
2
1
2
1
21R4578
2
1
2
1
2
1
2
1
2
1
21R4576
2
1
2
1
2
1
2
1
2
1
2
1
2
1
2
1
2
1
2
1
2
1
2
1
2
1
2
1
21R4575
21R4572
2
1
2
1
21R4573
21R4574
2
1
2
1
2
1
2
1
2
1
2
1
2
1
2
1
2
1
1
SHEETDATE
23
7 3 2 16 5 4
E
A
B
C
E
D
C
B
A
7 6 5 4
D
DEPARTMENT
SIZE
PROJECT DOCUMENT NUMBER REV
REVIEWER
DESIGNER
IN
OUT
IN
OUT
OUT
IN
IN
OUT
IN
IN
IN
OUT
OUT
OUT
OUT
IN
R4124
C16
C19
C17
R4131
R4132
R4135
R4136
R4133
R4134
C12
C14
C13
C18R4562
R4559
C15
R4119
R4120
R4123
R4121
R4122
R4153
R4154
C



Thu Aug 24 14:09:08 2023
<NAME_1>
<NAME_2>
GTI MB FABC
126 OF 365
V02
P3V3_AUX
P3V3_AUX
P3V3_AUX
P3V3_AUX
P3V3_AUX
P3V3_AUX
P3V3_AUX
P3V3_AUX
P3V3_AUX
P3V3_AUX
P3V3_AUX
P3V3_AUX
P3V3_AUX
P3V3_AUX
P3V3_AUX
P3V3_AUX
P3V3_AUX
P3V3_AUX
P3V3_AUX
P3V3_AUX
P3V3_AUX
81
81
81
122
118
120
120
81
81
119
81 246242
121
115
81
1/16W
CHIP
0402LF
1%
1K
SMLF
PJT138K
0402
X7R
10%
25V
0.1UF
SMLF
0402
X7R
10%
25V
0.1UF
IC
IC
SMLF
PJT138K
GPU_FPGA_OVERT_ISO_N
GPU_FPGA_OVERT
GPU_HMC_PRSNT_ISO_N
GPU_BASE_HMC_READY_ISO
GPU_FPGA_THERM_OVERT_N
EXAMAX_ISO (3/7)
0402LF
1/16W
CHIP
1%
54.9K
54.9K
CHIP
1%
1/16W
0402LF
1%
100K
E MP TY
1/16W
0402LF
1/16W
0402LF
1%
10K
CHIP
1%
54.9K
CHIP
E MP TY
0402LF
100K
1%
1/16W
IC
CHIP
4.7K
1/16W
5%
0402LF
PJT138K
SMLF
IC
4.7K
5%
1/16W
0402LF
IC
SMLF
IC
1/16W
CHIP
0402LF
5%
4.7K
IC
PJT138K
SMLF
0402LF
5%
4.7K
CHIP
1/16W
SMLF
IC
0402LF
1/16W
E MP TY
100K
1%
0402LF
100K
1%
1/16W
E MP TY
PJT138K
GPU_FPGA_OVERT_N
CHIP
PJT138K
0402LF
GPU_BASE_HMC_READY_N
GPU_BASE_HMC_READY
1/16W
GPU_HMC_PRSNT
GPU_HMC_PRSNT_N
0402LF
1/16W
CHIP
100K
1%
1/16W
0402LF
CHIP
100K
1%
GPU_FPGA_THERM_OVERT
1%
100K
1/16W
CHIP
0402LF
1/16W
0402LF
CHIP
100K
1%
25V
0.1UF
10%
X7R
0402
SMLF
GPU_FPGA_THERM_OVERT_ISO_N
0.1UF
10%
X7R
0402
25V
PJT138K
PJT138K
PJT138K
SMLF
IC 0.1UF
0402
X7R
10%
25V
0402LF
1/16W
100K
CHIP
1%
0402LF
CHIP
5%
4.7K
1/16W
PJT138K
SMLF
IC
1/16W
CHIP
1%
54.9K
0402LF
0402LF
100K
1%
1/16W
E MP TY
GPU_FPGA_EROT_FATALERR_ISO_N
GPU_FPGA_EROT_FATALERR_N
GPU_FPGA_EROT_FATALERR
PJT138K
SMLF
IC
IC
SMLF
PJT138K
10%
25V
X7R
0402
0.1UF
1%
100K
0402LF
CHIP
1/16W
0402LF
CHIP
1/16W
4.7K
5%
1%
CHIP
1/16W
10K
0402LF
100K
1%
E MP TY
1/16W
0402LF
GPU_PRSNT_N_ISO
GPU_PRSNT
GPU_PRSNT_N
SMLF
PJT138K
IC
0402LF
5%
EMPTY
0
1%
1/16W
4.7K
0402LF
E MP TY
5%
CHIP
0402LF
IC
SMLF
0402LF
E MP TY
1%
1/16W
10K
LEAVE GPU_WP_HW_CTRL_ISO_N FLOATING PER NV DESIGN GUIDE REQUIREMENT
GPU_WP_HW_CTRL_ISO_N
PJT138K
GPU_WP_HW_CTRL_ISO
1/16W
4.7K
GPU_WP_HW_CTRL_N
G2
G1
G2
G2
G1
G1
G2
G1
G1
G2
G1
G2
G1
G2
S2 D2
D1S1
S2 D2
S2 D2
D1S1D1S1
S2 D2
D1S1
D1S1
S2 D2
D1S1
S2 D2
D1S1
S2 D2
R9044
R9043
R3503
C1988
R3474
C1978
C1975
R3439
R3438
R3432
R3433
R3434
C1976
R3435
2
5
2
5
2
5
5
2
5
5
2
2
5
2
1 6
4 3
1 6
4 3
1 6
4 3
4 3
1 6
4 34 3
1 61 6
4 3
1 6
Q106
Q106
Q108
Q108
Q107
Q107
Q101
Q101
Q102
Q103
Q102
Q103
Q104
Q104
DESIGN NOTE:
2
1 R3472
2
1
2
1
2
1
2
1
2
1
2
1
2
1
2
1
2
1
2
1
2
1
2
1
2
1
2
1
2
1
2
1
2
1
2
1
2
1
2
1
2
1
2
1
2
1
2
1
2
1
2
1
2
1
2
1
2
1
2
1
2
1
2
1
2
1
21
1
SHEETDATE
23
7 3 2 16 5 4
E
A
B
C
E
D
C
B
A
7 6 5 4
D
DEPARTMENT
SIZE
PROJECT DOCUMENT NUMBER REV
REVIEWER
DESIGNER
OUT
OUT
OUT
IN
OUT
OUT
IN
OUT
IN
IN
OUT
IN
OUT
IN
IN
R3470
R3471
R3525
R3502
R3504
R3498
R3487
R3473
R3475
R3464
R3431
R3465
R3463
R3429
C1974
C1973
R3436
R3437
R3428
R3430
C



20211230 DEPOP R2837,POP R2838
20210527 MODIFY FOR GT
Thu Aug 24 14:09:09 2023
MB FABC V02
127 OF 365
GTI
<NAME_2>
<NAME_1>
P3V3_AUX
P3V3_AUX
P3V3_AUX
P3V3_AUX
P3V3_AUX
P3V3_AUX
P3V3_AUX
P3V3_AUX
P3V3_AUX
P3V3_AUX
P3V3_AUX
P3V3_AUX
P3V3_AUX
P3V3_AUX
P3V3_AUX
P3V3_AUX
P3V3_AUX
P3V3_AUX
P3V3_AUX
P3V3_AUX
P3V3_AUX
P3V3_AUX
P3V3_AUX
P3V3_AUX
81
81
81
81
81
81
122
116
81
81
234
119
115
120
121
120
115
0402
X7R
10%
25V
0.1UF
PJT138K
SMLF
0402
X7R
10%
0.1UF
IC
0402
X7R
10%
25V
0.1UF
0402
X7R
10%
0.1UF
25V
IC
25V
0402
X7R
10%
0.1UF
10%
0402
X7R
0.1UFIC
0.1UF
25V
10%
X7R
10%
X7R
25V
0402
0402
25V
25V
0402LF
GPU_FPGA_READY_ISO
SMLF
PJT138K
1%
100K
1/16W
CHIP
1%
100K
CHIP
1/16W
0402LF
1%
100K
CHIP
1/16W
0402LF
1%
100K
1/16W
CHIP
0402LF
IC
100K
FM_SWB_BIC_READY_ISO_N0402LF
CHIP
1/16W
1%
0402LF
CHIP
1/16W
1%
100K
FM_SMB_1_ALERT_GPU_ISO_N
FM_SWB_BIC_READY
4.7K
1%
FM_SMB_2_ALERT_GPU_ISO_N
SMLF
PJT138K
PJT138K
PJT138K
PJT138K
RST_BMC_FROM_SWB_ISO_N
PJT138K
BIC_MONITER_ISO
SMLF
BIC_MONITER_N
1/16W
CHIP
0402LF
GPU_FPGA_READY
PJT138K
1/16W
1/16W
PJT138K
IC
CHIP
IC
PJT138K
5%
CHIP
4.7K
0402LF
5%
1/16W
0402LF
CHIP
1/16W
5%
0402LF
1/16W
CHIP
5%
4.7K
1/16W
CHIP
0402LF
5%
4.7K
PJT138K
IC
SMLF
100K
1%
E MP TY
1/16W
0402LF
1/16W
E MP TY
0402LF
1%
100K
0402LF
E MP TY
1/16W
1%
100K
CHIP
1/16W
1%
100K
0402LF
0402LF
1/16W
1%
CHIP
100K
CHIP
0402LF
100K
1%
1/16W
0402LF
CHIP
1/16W
1%
100K
0402LF
E MP TY
1/16W
100K
1%
5%
1/16W
CHIP
0402LF
0402LF
E MP TY
1/16W
1%
100K
1/16W
100K
E MP TY
1%
0402LF
4.7K
0402LF
1/16W
CHIP
5%
IC
SMLF
5%
0402LF
4.7K
CHIP
0402LF
1/16W
1%
E MP TY
100K
1%
1/16W
CHIP
54.9K
54.9K
1%
0402LF
1/16W
0402LF
E MP TY
100K
1%
1%
54.9K
1/16W
CHIP
0402LF
0402LF
CHIP
1/16W
54.9K
1%
FM_SWB_PWRGD
PJT138K
SMLF
PJT138K
FM_GPU_PWRGD_ISO
FM_SWB_PWRGD_ISO
SMLF
PJT138K
GPU_FPGA_READY_N
RST_BMC_FROM_SWB
FM_GPU_PWRGD_N
IC
SMLF
IC
SMLF
IC
SMLF
SMLF
IC
IC
SMLF
FM_SMB_1_ALERT_GPU
SMLF
PJT138K
BIC_MONITER
RST_BMC_FROM_SWB_N
SMLF
FM_SMB_2_ALERT_GPU_N
FM_GPU_PWRGD
FM_SMB_1_ALERT_GPU_N
EXAMAX_ISO (4/7)
FM_SWB_BIC_READY_N
FM_SWB_PWRGD_N
4.7K
IC
0402LF
100K
0402LF
1/16W
CHIP
1%
IC
4.7K
SMLF
CHIP
FM_SMB_2_ALERT_GPU
1/16W
100K
0402LF
PJT138K
0.1UFIC
G2
G2
G1
G1
G1
G2
G1
G1
G2
G2
G1
G2
G2
G1
G1
G2
S2 D2
S2 D2
D1S1
D1S1
D1S1
S2 D2
D1S1
D1S1
S2 D2
S2 D2
D1S1
S2 D2
S2 D2
D1S1
D1S1
S2 D2
R3320
C1881
C1802
R3029
R3034
C1804
C1756
C1754
R2919
R2842
R2841
R2836
R2834
R2835
5
2
2
5
5
2
5
5
2
2
5
5
5
2
2
2
4 3
1 6
1 6
4 3
4 3
1 6
4 3
4 3
1 6
1 6
4 3
4 3
4 3
1 6
1 6
1 6
Q96
Q96
Q75
Q75
Q74
Q74
Q70
Q72
Q71
Q69
Q71
Q69
Q67
Q72
Q70
Q67
2
1 2
1
2
1
R3030
2
1
R2920
2
1
2
1
2
1
2
1
2
1
2
1
2
1
2
1
2
1
2
1
2
1
2
1
2
1
2
1
2
1
2
1
2
1
2
1
2
1
2
1
2
1
2
1
2
1
2
1
2
1
2
1
2
1
2
1
2
1
2
1
2
1
2
1
2
1
2
1
2
1
2
1
1
SHEETDATE
23
7 3 2 16 5 4
E
A
B
C
E
D
C
B
A
7 6 5 4
D
DEPARTMENT
SIZE
PROJECT DOCUMENT NUMBER REV
REVIEWER
DESIGNER
OUT
OUT
OUT
OUT
IN
IN
IN
IN
IN
OUT
IN
OUT
OUT
IN
IN
OUT
OUT
R2933
R3035
R3510
R3514
R3512
R3513
R3511
R3318
R3321
R3028
R3032
C1772
C1773
C1774
R2935
R2934
R2837
R2830
R2832
R2828
R2838
R2833
R2829
R2831
C



PUSH-PULL OUTPUT
2021014 MODIFY FOR GT
PUSH-PULL OUTPUT
PUSH-PULL OUTPUT
TBC
FROM CPU1
FROM CPU1
FROM CPU0
Thu Aug 24 14:09:09 2023
<NAME_1>
<NAME_2>
GTI MB FABC
128 OF 365
V02
P3V3_AUX
P3V3_AUX
P3V3_AUXP3V3_AUX
P3V3_AUX
P3V3_AUX
P3V3_AUX
P3V3_AUX
P3V3_AUX
122
85
85
122
85
81
115
122
120
81
81 120
0402LF
49.9 RST_PERST_2_SWB_BUF_NSMLF
RST_PERST_CPU1_SWB_1_R_N
RST_PERST_CPU1_SWB_R_N
IC
RST_PERST_1_SWB_BUF_N
X 7R
25V
0.1UF
RST_PERST_1_SWB_BUF_R_N0402
RST_PERST_2_SWB_BUF_R_N
74LVC2G17GW
RST_PERST_0_SWB_BUF_R_N
CHIP
CHIP0402LF
0402LF
RST_PERST_CPU0_SWB_R_N
0402LF
FM_SWB_PWR_EN_R
1/16W 74LVC2G17GW
100K
SMLF
CHIP
1/16W
1%
10K
IC
E MP TY
49.9
CHIP0402LF
1/16W
4.7K
10K
0402LF
49.9
0402LF CHIP
CHIP
1/16W
0402LF CHIP
FM_SWB_PWR_EN_R_BUF
4.7K
5%
RST_PERST_0_SWB_BUF_N
E MP TY
1/16W
0402LF
49.9
0402LF CHIP
1/16W
1%
49.9
0402LF CHIP
10K
0402LF
EMPTY
49.9
1%
X 7R
GPU_BASE_STBY_EN_BUF
1%
CHIP
GPU_BASE_STBY_EN
SMLF
74LVC2G17GW
0.1UF
25V
0402
X 7R
10%
0402LF
100K
1/16W
0402LF
1%
100K
4.7K
EMPTY
1/16W
5%
0402LF
10K
1%
1/16W
10%
0402
25V
0.1UF
0402LF
100K
1%
1/16W
0402LF
1/16W
1K
1%
CHIP
5%
1/16W
0402LF
EMPTY
4.7K
100K
CHIP
1%
0402LF
1/16W
IC
10%
CHIP
E MP TY
1/16W
1%
4.7K
CHIP
5%
0402LF
5%
CHIP
1/16W
0402LF
EXAMAX_ISO (5/7)
FM_SWB_PWR_EN_R1_BUF
GPU_FPGA_BOOT_EN
GPU_BASE_STBY_EN_BUF_R
GPU_FPGA_BOOT_EN_BUF_R GPU_FPGA_BOOT_EN_BUF
R3515
R2914
R2918
R3468
R3469
R3391
R3392
4
6
3
1
4
6
3
1
4
6
3
1
52
52
52
U256
21R3390
U252
U253
B0
A1
A0
B1
B0
A1
A0
B1
B0
A1
A0
B1 GND VCC
GND VCC
GND VCC
2
1
21
2
1
2
1
2
1
2
1
21
2
1
21
2
1 C1977
2
1
2
1
2
1
2
1
2
1 C1957
21
2
1
2
1
2
1
2
12
1
21
2
1 C1958
1
SHEETDATE
23
7 3 2 16 5 4
E
A
B
C
E
D
C
B
A
7 6 5 4
D
DEPARTMENT
SIZE
PROJECT DOCUMENT NUMBER REV
REVIEWER
DESIGNER
OUT
IN
IN
OUT
IN
OUT
IN
OUT
IN
IN OUT
OUT
R2932
R2910
R3466
R3467
R3449
R3448
R3454
R3453
R3455
R3451
R3456
R3457
R3452
C



OPEN-DRAIN OUTPUT
OPEN-DRAIN OUTPUT
20220105 CHANGE PIN3 CONNECT TO GND
20210603 MODIFY FOR GT
Thu Aug 24 14:09:10 2023<NAME_2>
<NAME_1>
MB FABCGTI V02
129 OF 365
P3V3_AUXP3V3_AUX
P3V3_AUX
P3V3_AUX
P3V3_AUX
P3V3_AUXP3V3_AUX
P3V3_AUX
122
120
120
81
81
81
1/16W
CHIP
0402LF
1%
1K
1%
1K
CHIP
1/16W
0402LF
1%
1K
0402LF
CHIP
1/16W
GPU_NVS_PWR_BRAKE_N_R
GPU_FPGA_EROT_RECOV_BUF_R_N
GPU_NVS_PWR_BRAKE_N_BUF
GPU_FPGA_EROT_RST_BUF_N
GPU_FPGA_EROT_RECOV_BUF_N
NC_U257_2Y
GPU_NVS_PWR_BRAKE_N
GPU_FPGA_EROT_RST_N
EXAMAX_ISO (6/7)
GPU_FPGA_EROT_RST_BUF_R_N
GPU_FPGA_EROT_RECOV_N
E MP TY
0402LF
1/16W
1%
100K
10%
0.1UF
25V
X 7R
0402
E MP TY
1%
1/16W
0402LF
100K
54.9K
CHIP
1/16W
1%
0402LF
CHIP0402LF
33.2
IC
74LVC2G07DW-7
SMLF
0402LF
E MP TY
100K
1%
1/16W
0402LF
CHIP
1%
54.9K
1/16W
CHIP0402LF
33.2
1%
100K
1/16W
0402LF
E MP TY
CHIP0402LF
33.2
0402LF
CHIP
1%
54.9K
1/16W
100K
1%
1/16W
E MP TY
0402LF
E MP TY
0402LF
1/16W
100K
1%
IC
SMLF
74LVC2G07DW-7
X 7R
0.1UF
0402
25V
10%
52
43
61
52
43
61
21R3497
U257
21R3496
21R3397
U255
VCCGND
2Y
1Y
2A
1A
VCCGND
2Y
1Y
2A
1A
2
1
2
1
2
1 C1979
2
1
2
1
2
1
R3494
2
1
2
1
R3492
2
1
2
1
2
1
R3461
2
1
2
1
2
1 C1963
1
SHEETDATE
23
7 3 2 16 5 4
E
A
B
C
E
D
C
B
A
7 6 5 4
D
DEPARTMENT
SIZE
PROJECT DOCUMENT NUMBER REV
REVIEWER
DESIGNER
IN OUT
OUT
IN
OUTIN
R3459
R3491
R3495
R3490
R3493
R3489
R3488
R3462
R3460
C



20211126 DPPOP R259,R260
PUSH-PULL OUTPUT
20211215 ADD R4515 PU TO P3V3_AUX
20211126 CHANGE R3036 TO 33.2 OHM
20210527 MODIFY FOR GT
PUSH-PULL OUTPUT
Thu Aug 24 14:09:10 2023
MB FABC
<NAME_2>
<NAME_1>
GTI V02
130 OF 365
P3V3_AUX
P3V3_AUX
P3V3_AUX
P3V3_AUX
P3V3_AUX
P3V3_AUX
P3V3_AUX
P3V3_AUX
P3V3_AUX
P3V3_AUX
P3V3_AUX
P3V3_AUX
P3V3_AUX
241
121
121
115246
81 119
150
116
81
81
FM_PDB_BUF_EN_R1
0402LF
CHIP
1%
1/16W
GPU_FPGA_RST_R_BUF_N
FM_GPU_PWR_EN_R_BUF49.9
CHIP0402LF
0402LF
0402LF CHIP
5%
1/16W
49.9
0402LF CHIP
4.7K
49.9
RST_SWB_BIC_BUF_NRST_SWB_BIC_BUF_R_N
SMLF
EXAMAX_ISO (7/7)
4.7K
5%
1/16W
CHIP
0402LF
RST_SWB_BIC_R_N
BMC_MONITER_R
FM_GPU_PWR_EN_R1
BMC_MONITER_BUF_R BMC_MONITER_BUF
UART_BMC_BIC_BUF_RX
CHIP
SMLF
UART_BMC_BIC_RX
100K
1/16W
GPU_FPGA_RST_R_N
FM_GPU_PWR_EN_R
UART_BMC_BIC_R_RX
FM_UART_EN
33.2
CHIP
1%
0402LF
IC
0402LF
1%
100K
0402LF
1/16W
CHIP
54.9K
1%
0402LF
CHIP
1/16W
4.7K
0402LF
5%
1/16W
EMPTY
1/16W
1%
CHIP
10K
0402LF
1%
10K
5%
4.7K
1/16W
EMPTY
0402LF
33.2
CHIP0402LF
0402LF
0
CHIP
0
X 7R
0.1UF
25V
10%
1/16W
E MP TY
100K
1%
0402LF
1/16W
4.7K
0402LF
CHIP
5%
4.7K
1/16W
0402LF
EMPTY
5%
0402LF
EMPTY
1/16W
4.7K
5%
0.1UF
X 7R
10%
25V
0402
74LVC2G17GW
IC
SMLF
CHIP
4.7K
1/16W
EMPTY
0402LF
5%
CHIP
1/16W
5%
4.7K
0402LF
0402
X 7R
10%
25V
0.1UF
4.7K
EMPTY
1/16W
5%
0402LF
100K
0402LF
E MP TY
1/16W
1%
74LVC2G17GW
IC
0402
100K
0402LF
UART_BMC_BIC_R_BUF_RX
74LVC1G126SE-7
GPU_FPGA_RST_R1_BUF_N
1/16W
CHIP
0402LF
E MP TY
R3036
R3317
R3315
R3063
R2937
R2924
R2911
R2912
R2916
R2915
R2820
4
1
2
4
6
3
1
4
6
3
1
53
52 52
U204
R3033
21R2917
U196
U195
B0
A1
A0
B1
OE
Y
A
B0
A1
A0
B1
GND VCC
GND VCC
GND VCC
2
1
2
1
2
1
R4515
2
1
21
2
1
2
1
2
1
2
1
2
1
21
21
21
2
1 C1803
2
1
2
1
21R2925
21
2
1
2
1
2
1 C1770
2
1
2
1
2
1
2
1 C1769
2
1
2
1
1
SHEETDATE
23
7 3 2 16 5 4
E
A
B
C
E
D
C
B
A
7 6 5 4
D
DEPARTMENT
SIZE
PROJECT DOCUMENT NUMBER REV
REVIEWER
DESIGNER
OUT
OUT
IN
IN
OUTIN
IN
IN
OUT
IN OUT
R4173
R2927
R2909
R3508
R3506
R3507
R3509
R2936
R2926
R2815
C



20210525 MODIFY FOR GT
FROM CPU0 PCIE G3 [15:0]
TO CPU0 PCIE G3 [15:0]P/N SWAP
P/N SWAP
P/N SWAP
P/N SWAP
P/N SWAP
P/N SWAP
P/N SWAP
P/N SWAP
P/N SWAP
P/N SWAP
P/N SWAP
P/N SWAP
P/N SWAP
P/N SWAP
P/N SWAP
P/N SWAP
Thu Aug 24 14:09:10 2023
<NAME_1>
MB FABC
131 OF 365
V02GTI
<NAME_2>
P12V_OCP_SFF_R
P12V_OCP_SFF_R
P3V3_OCP_SFF
P3V3_OCP_SFF
P3V3_OCP_SFF
P3V3_OCP_SFF
1%
1%200
200
1/16W
CLK _50M_NCS I_O CP _S FF_IS O
N C SI_OC P_SFF_TXD 1
CLK_100M_CPU0_CLK05_DN
0402LF
CHIP
SMB_OC P_SFF_3V3AU X_BU F_R _SC L SMB_OC P_SFF_3V3AU X_BU F_SC L
0402LF
133
CHIP 1/16W
CLK_100M_CPU0_CLK05_DP
SMB_OC P_SFF_3V3AU X_BU F_R _SD A SMB_OC P_SFF_3V3AU X_BU F_SD A
CLK_100M_CPU0_CLK03_DN
28
CLK_100M_CPU0_CLK03_DP
13182132
132
80131
13180
131
136 131 132
23
23
65
65
28
28
82 131
131 82 132
131136132
133
248
248
131
131
134143
80131
13180
80131
80131
132
132
132
134143
132
80131
80131
132
134 143
28
133
28
134 143
131
132
132
132
132
28
28
29
29
133
82131
28
132
132
133
133
133
IO_SLOT
CHIP
1/16W0402LF
CHIP
OCP_SFF_MAIN_PWR_EN_R
FM_OCP_SFF_PWR_GOOD
NCSI_OCP_SFF_RXD0
SGPIO_OCP_SFF_DATAOUT
SGPIO_OCP_SFF_CLK
OCP_SFF_ID0
1/16W
OCP_SFF_AUX_PWR_EN
P5E_CPU0_G3_RX_DP<15:0>
P5E_CPU0_G3_RX_DN<15:0>
P5E_CPU0_G3_TX_C_DN<15:0>
P5E_CPU0_G3_TX_C_DP<15:0>
CLK_100M_CPU0_CLK02_DP
CLK_100M_CPU0_CLK02_DN
0402LF
10K
1%
CHIP
OCP_SFF_MAIN_PWR_EN
FM_OCP_SFF_PWR_GOOD
1%
OC P_SFF_AU X_PW R _EN 0 5% 0402LF
R ST_PER ST0_OC P_SFF_N
OC P_SFF_BIF2_R _N0402LF0
OC P_SFF_AU X_PW R _EN _R
OC P_SFF_BIF1_R _N
IO_SLOT
SCONN168_ME1016810202011
CHIP1%
OCP_SFF_ID0
OCP_SFF_ID1
OCP_SFF_PRSNT3_R_N
TP_OCP_SFF_B68
TP_OCP_SFF_B69
SGPIO_OCP_SFF_DATAIN
SGPIO_OCP_SFF_CLK
SGPIO_OCP_SFF_DATAOUT
SGPIO_OCP_SFF_LD_N
OC P_SFF_ISO_BIF2_EN
OC P_SFF_ISO_BIF0_EN
OC P_SFF_ISO_BIF1_EN
OCP_SFF_PRSNT0_R_N
NCSI_OCP_SFF_CRS_DV
SGPIO_OCP_SFF_LD_N
SGPIO_OCP_SFF_DATAIN
NCSI_OCP_SFF_RXD1
O CP _S FF_P RS NT2_R_N
R ST_PER ST1_OC P_SFF_N
OCP_SFF_PRSNT1_R_N
OCP _S FF_ID1
N C SI_OC P_SFF_TXD 0
R ST_SMB_OC P_SFF_N
N C SI_OC P_SFF_TX_EN
IO_SLOT IO_SLOT
10K 1% CHIP
1K 1%
10K 1%
0402LF 1/16W
1K
IO_SLOT
IO_SLOT
IO_SLOT
IO_SLOT
IO
SMLF
PCIE - SFF OCP3.0_X16_CPU0 (1/3)
OC P_SFF_BIF0_R _N
5%0
1/16WCHIP
0402LF
X7R
0.1UF
10%
25V
0402
X7R
0402
25V
0.1UF
10%
X7R
0402
10%
25V
0.1UF
0 5% 0402LF
C0805
22UF
20%
X6S
16V
X6S
C0805
20%
16V
22UF
0402LF0 5%
0402LF
CHIP
5%0
0402LF0 5%
5%
1%
4.7K
1/16W
EMPTY
0402LF
4.7K
CHIP
0402LF
1%
1/16W
1/16W
10K CHIP
1%
EMPTY
0402LF
4.7K
1/16W
0402
0.1UF
X7R
10%
25V
X7R
10%
25V
0.1UF
0402
0.1UF
25V
10%
0402
X7R
X7R
0402
10%
25V
0.1UF
10%
25V
0.1UF
X7R
0402
0402LF
1% CHIP100K
1/16W
4.7K
1/16W
1%
CHIP
0402LF
CLK_100M_CPU0_CLK04_DP
CLK_100M_CPU0_CLK04_DN
USB2_CPU0_P11_DN
USB2_CPU0_P11_DP
PLACE THE BULK CAPS CLOSE TO SLOT
OCP_SFF_PWRBRK_N
USB2_P11_DN
USB2_P11_DP
OC P_SFF_MAIN _PW R _EN
OC P_SFF_ISO2_R BT_AR B_OU T
OC P_SFF_ISO1_R BT_AR B_IN
IR Q_LVC 3_OC P_SFF_W AKE_N
R ST_PER ST3_OC P_SFF_N
R ST_PER ST2_OC P_SFF_N
O CP _S FF_P RS NTA _R_N
0402LF
0
5%
CHIP
1/16W
21
21
R42
R46
R38
R8420
R8421
R8423
R8422
OA3
A69
A68
A9
A8
A7
OA6
OB7
B69
B68
OA12OB12
A15B15
OA11OB11
A14B14
OA8
OA9
OA7
OB8
OB9
OB14 OA14
OA5
OA4
A70B70
A12
A42B42
A10
B66
B63
B60
B57
B54
B51
B48
B45
B40
B37
B34
B31
B27
B24
B21
B18
B65
B62
B59
B56
B53
B50
B47
B44
B39
B36
B33
B30
B26
B23
B20
B17
OA2
OA1
A11
B10
A66
A63
A60
A57
A54
A51
A48
A45
A40
A37
A34
A31
A27
A24
A21
A18
A65
A62
A59
A56
A53
A50
A47
A44
A39
A36
A33
A30
A26
A23
A20
A17
OB1
OB2
OB3
OB13
OB10
OA13
OA10
B67
B64
B61
B58
B55
B52
B49
B46
B43
B41
B38
B35
B32
B29
B28
B25
B22
B19
B16
B13
A67
A64
A61
A58
A55
A52
A49
A46
A43
A41
A38
A35
A32
A29
A28
A25
A22
A19
A16
A13
A6
A5
A4
A3
A2
A1
G5
G4
G3
G2
G1
OB5
OB4
OB6
B9
B8
B7
B12
B6
B5
B4
B3
B2
B1
B11
15
14
14
15
12
13
11
13
11
8
10
9
10
9
8
6
7
5
7
6
5
4
3
4
3
2
1
2
1
14
12
13
12
11
10
9
8
10
9
8
7
6
5
7
5
6
4
3
4
3
2
1
0
2
1
0
15
12
0
0
15
11
14
13
J38
CAD NOTE:
KEY
KEY
KEY
G5
G4
G3
G2
G1
PRSNTB3#
RFU1_NC_B69
RFU1_NC_B68
GND_B67
PETp15
PETn15
GND_B64
PETp14
PETn14
GND_B61
PETp13
PETn13
GND_B58
PETp12
PWRBRK0#
USB_DATp
USB_DATn
GND_A67
PERp15
PERn15
GND_A64
PERp14
PERn14
GND_A61
PERp13
PERn13
GND_A58
PERp12
PERn12
GND_A55
PERp11
PERn11
GND_A52
PERp10
PERn10
GND_A49
PERp9
PERn9
GND_A46
PERp8
PERn8
GND_A43
PRSNTB1#
GND_A41
PERp7
PERn7
GND_A38
PERp6
PERn6
GND_A35
PERp5
PERn5
GND_A32
PERp4
PERn4
GND_A29
GND_A28
PERp3
PERn3
GND_A25
PERp2
PERn2
GND_A22
PERp1
PERn1
GND_A19
PERp0
PERn0
GND_A16
REFCLKp1
REFCLKn1
GND_A13
PRSNTB2#
PERST1#
PRSNTA#
SMRST#
SMDAT
SMCLK
GND_A6
GND_A5
GND_A4
GND_A3
GND_A2
GND_A1
RBT_CLK_IN
GND_OA13
REFCLKp3
REFCLKn3
GND_OA10
RBT_TXD0
RBT_TXD1
RBT_TX_EN
SLOT_ID1
RBT_ARB_OUT
RBT_ARB_IN
WAKE#
PERST3#
PERST2#
PETn12
GND_B55
PETp11
PETn11
GND_B52
PETp10
PETn10
GND_B49
PETp9
PETn9
GND_B46
PETp8
PETn8
GND_B43
PRSNTB0#
GND_B41
PETp7
PETn7
GND_B38
PETp6
PETn6
GND_B35
PETp5
PETn5
GND_B32
PETp4
PETn4
GND_B29
GND_B28
PETp3
PETn3
GND_B25
PETp2
PETn2
GND_B22
PETp1
PETn1
GND_B19
PETp0
PETn0
GND_B16
REFCLKp0
REFCLKn0
GND_B13
AUX_PWR_EN
+3.3V_EDGE
PERST0#
BIF2#
BIF1#
BIF0#
+12V_EDGE_B6
+12V_EDGE_B5
+12V_EDGE_B4
+12V_EDGE_B3
+12V_EDGE_B2
+12V_EDGE_B1
RBT_CRS_DV
GND_OB13
REFCLKp2
REFCLKn2
GND_OB10
RBT_RXD0
RBT_RXD1
SLOT_ID0
CLK
DATA_OUT
DATA_IN
LD#
MAIN_PWR_EN
NIC_PWR_GOOD
R47
R48
2
1
21
2
1 C1236
2
1 C27
2
1 C1239
21
2
1 C34
2
1 C1213
21
21R39
21R40
21R41
21
21
21
21
2
1
2
1
21R1929
21R1930
2
1
2
1 C1240
2
1 C1238
2
1 C1237
2
1 C1235
2
1 C21
21R1671
21R3132
2
1
1
SHEETDATE
23
7 3 2 16 5 4
E
A
B
C
E
D
C
B
A
7 6 5 4
D
DEPARTMENT
SIZE
PROJECT DOCUMENT NUMBER REV
REVIEWER
DESIGNER
IN
IN
IN
IN
OUT
IN
OUT
OUT
OUT
IN
IN
IN
IN
IN
IN
OUT
OUT
OUT
OUT
IN
IN
IN
IN
IN
OUT IN
OUT
OUT OUT
BI
IN
IN
IN
IN
OUT
OUT
IN
OUT
IN
IN
IN
IN
IN
IN
IN
IN
IN
OUT
IN
OUT
OUT
IN
OUT
OUT
IN
IN
OUT
R1895
R33
R34
R31
R32
C



Thu Aug 24 14:09:11 2023
GTI
<NAME_2>
<NAME_1>
MB FABC V02
132 OF 365
P3V3_AUX
P3V3_AUX
P3V3_AUX
P3V3_AUX
131136132
80139241246251253
131
13182
131136132
133
81
143
132 150 138
132 138 150
132 138
150
132 138 150
143
131
131
131
131
131
131
131
150132138
150132138
132138150
131
132 150 138
150
132138150
132138150
150132138
131
132 150 138
131
131
OCP_SFF_AUX_PWR_EN
RST_SMB_SWITCH_N
IC
1/16W
1%
0402LF
100K
CHIP
R ST_SMB_OC P_SFF_NCHIPR ST_H P_OC P_SFF_R _N
74LVC1G126SE-7
PCIE - SFF OCP3.0 (2/3)
OCP_SFF_AUX_PWR_EN_R2
0402LF 1/16W
CHIP
IC
FM_OCP_SFF_PWR_GOOD
OCP_SFF_AUX_PWR_EN_R1OCP_SFF_AUX_PWR_EN 1%33.2
0402LF
1/16WCHIP
0402
X 7R
10%
25V
0.1UF
FB_BMC _ISOLATE_R 1
1/16W
FB_BMC _ISOLATE
0402LF
0 E MP TY5%FM_N C SI_OC P_SFF_R _OE
0
1/16W
CHIP
0402LF
5%
0402LF
74LVC1G126SE-7
NCSI_BMC_TX_EN_R
OCP_SFF_RBT_ARB_OUT
RMII_BMC_OCP_TXD_0
SMLF
CHIP
RMII_OCP_BMC_RXD_0
RMII_OCP_BMC_CRSDV
RMII_OCP_BMC_RXD_1
CHIPNCSI_BMC_RXD0_R
NCSI_BMC_RXD1_R
OCP_SFF_RBT_ARB_INE MP TY
0402LF1/16W
22
22
22
NCSI_BMC_TXD1_R
74CBTLV3126PW
1%
10%
NCSI_OCP_SFF_TXD1
OCP_SFF_ISO_BIF0_EN
OCP_SFF_ISO_BIF1_EN
OCP_SFF_ISO_BIF2_EN
NCSI_OCP_SFF_TXD0
NCSI_OCP_SFF_TX_EN
OCP_SFF_ISO2_RBT_ARB_OUT
RMII_BMC_OCP_TXD_0
RMII_BMC_OCP_TX_EN
RMII_OCP_BMC_RXD_1
OCP_SFF_ISO1_RBT_ARB_IN OCP_SFF_RBT_ARB_IN_R
RMII_BMC_OCP_TX_EN
NCSI_BMC_CRS_DV_R
RMII_BMC_OCP_RX_ER
RMII_OCP_BMC_CRSDV
RMII_OCP_BMC_RXD_0
RMII_BMC_OCP_TXD_1
NCSI_OCP_SFF_RXD1
RMII_BMC_OCP_TXD_1
SMLF
NCSI_OCP_SFF_RXD0
NCSI_BMC_TXD0_R
NCSI_OCP_SFF_CRS_DV
33.2
1/16W
0
5%0
X 7R
0.1UF
CHIP1K
1/16W
1%
0402LF
100K 1% CHIP
100K 1% CHIP
1% CHIP100K
100K CHIP1%
0402LF
1% CHIP
1/16W
100K
1%100K CHIP
0402LF
CHIP
100
1%
1/16W
1%
CHIP
1/16W
0402LF
1%
100
1/16W
CHIP
0402LF
CHIP0
0 CHIP
CHIP0
CHIP22
CHIP
1%
CHIP
100K
1/16W
10%
0402
X 7R
0.1UF
25V
0.1UF
25V
X 7R
0402
10%
IC
SMLF
IC
74CBTLV3126PW
SMLF
25V
100
0402
0402LF
R87
R3231
R83
R82
R80
R79
R77
R84
R1897R1896 R1898
R1719
4
1
2
4
1
2
R76
R75
R74
R73
R72
R59
R1290
53
53
U224
U66
U7
U67
VCC
4OE
4A4B
3OE
3A
GND
1A
2B
1B
2OE
1OE
3B
2A
OE
Y
A
OE
Y
A
VCC
4OE
4A4B
3OE
3A
GND
1A
2B
1B
2OE
1OE
3B
2A
GND VCC
GND VCC
21R2474
21R2473
21
21R3233
2
1
R3232
2
1
21
21
21
21
21
21
21
2
1
2
1
2
1
21
2
1
2
1
R1289
2
1
2
1
14
7
13
11 12
10
8 9
4
6 5
1
3 2
14
7
13
11 12
10
8 9
4
6 5
1
3 2
21
1
SHEETDATE
23
7 3 2 16 5 4
E
A
B
C
E
D
C
B
A
7 6 5 4
D
DEPARTMENT
SIZE
PROJECT DOCUMENT NUMBER REV
REVIEWER
DESIGNER
OUT
IN
IN
IN
OUT
OUT
OUT
IN
IN
OUT
OUT
OUT
OUT
IN
IN
IN
IN
74CBTLV3126
OUT
IN
OUT
IN
OUT
OUT
OUT
OUT
OUT
OUT
OUT
IN
IN
OUT
OUT
OUT
74CBTLV3126
R3237
C1840
C639
C640
C641
C



20210706 MODIFY FOR GT
20220120 ADD R4601
POP
20210607 MODIFY FOR GT
Thu Aug 24 14:09:11 2023
MB FABC
133 OF 365<NAME_2>
<NAME_1>
GTI V02
P3V3_AUX
P3V3_AUX
P3V3_AUX
P3V3_AUX
P3V3_OCP_SFF
P3V3_AUX
P3V3_AUX
P3V3_AUX
P3V3_AUX
P3V3_AUX
P3V3_AUX
0402LF
136
131
131
131
131
139
131
131
8083139
150
133
131
132
133
155
0
0
0
0
RST_PERST_OCP_SFF_BUF_N
IC
74LVC1G17GW
RST_PERST_OCP_SFF_BUF2_N
RS T_P E RS T3_O CP _S FF_N
RS T_P E RS T0_O CP _S FF_N
RS T_P E RS T1_O CP _S FF_N
RS T_P E RS T2_O CP _S FF_N
1/16W
CHIP
CLK _50M_RMII
10K
1%
10K
CLK _50M_NCS I_O CP _V 3_2
X 7R
0.1UF
CLK _50M_B MC_MA C_R
CLK _50M_NCS I_O CP _1
TP _CLK _50M_Y 3
CLK _50M_NCS I_O CP _2
0402LF
1%
CHIP
CLK _50M_NCS I_O CP _S FF_IS O
X 7R
0.1UF
0402
25V
10%
SMLF
4.7K
0.1UF
25V
CHIP
0402LF
1/16W
1%
CHIP
IC
CLK_50M_EN
PU_OCP_SFF_WAKE_OE
IRQ_LVC3_OCP_SFF_WAKE_N
NC_U104_NC1
FM_SYS_THROTTLE_N
C LK_50M_R MII_R CLK _50M_RMII_B MC_O CP
CLK _50M_NCS I_O CP _S FF
OCP_SFF_WAKE_BUFF_N OCP_SFF_WAKE_BUFF_R_N
OCP_SFF_PWRBRK_N
IRQ_LVC3_WAKE_BUF_N
0402LF
CHIP
10K
1%
1/16W
IO_SLOT
0402
X 7R
25V
0.1UF
10%
OSC
50MHZ
SMLF
IO_SLOT
5%0
CHIP
0402LF
1/16W
IC
SMLF74LVC1G126SE-7
0402LF
1%
1/16W
CHIP
IO_SLOT
SMLF
PI6CV304LE
IC
0402
10%
0.1UF
X 7R
25V
1%27.4 CHIP
CHIP27.4
1/16W
27.4 1%
IC
SMLF
74LVC1G07GV
CHIP0
CHIP1%33.2
0402LF 1/16W
25V
0402
X 7R
10%
0.1UF
4.7K
1%
0402LF
CHIP
1/16W
SMLF
10%
X 7R
0402
33.2 0402LF
1/16W
1%
0402
X 7R
25V
0.1UF
10%
0402LF
1%
1/16W
33.2 CHIP
10%
25V
0402
4.7K
1/16W
1%
0402LF
EMPTY
PCIE - SFF OCP3.0 (3/3)
FB_BMC _ISOLATE
CLK _50M_NCS I_O CP _S FF_IS O _R
CLK _50M_NCS I_O CP _S FF
IC
PLACE R2487 CLOSE TO U157
IRQ_OCP_SFF_WAKE_BUF_N
SMLF
74LVC1G66GV
NC_U157_NC1
OCP_SFF_PWRBRK_BUFF_N
74LVC1G07GV
21 R956
21 R905
21 R877
21 R899
R2489
R1594
R4601
R1140
R1141
R3181
R1139
R1595
2
1 5
3
4
4
5
13
2
4
51
3
2
4
51
3
24
1
2
4 3
1 2
53
U320
U75
U104
U157
U90
U8082
OSC1
CAD NOTE:
VCC
E
GND
Z
Y
OE
Y
A
NC
Y
GND
A
VCC
VDD OUT
GNDOE
NC1
YGND
A
VCC
NC1
YGND
A
VCC
GND
VDD
Y3
Y2
Y1
Y0
OE
CLK_IN
GND VCC
2
1
21
2
12
1
2
1
21
21
21
21
21
2
1
8
7
5
3
6
2
4
1
2
1
R45
2
1
R1824
21
2
1C1274
2
1
R1138
2
1
2
1
21
2
1
R53
2
1
1
SHEETDATE
23
7 3 2 16 5 4
E
A
B
C
E
D
C
B
A
7 6 5 4
D
DEPARTMENT
SIZE
PROJECT DOCUMENT NUMBER REV
REVIEWER
DESIGNER
OUT
OUT
OUT
OUT
IN
OUT
IN
OUT
IN
OUT
OUT
OUT
OUT
IN
IN
C10
C1663
R2488
C36
C1275
R2487
C2344
C72
C



START UP TIME:3.94MS
VIMON(MAX)= 1.594V @ IOUT=1.6A
VIMON(MAX)= 1.679V @ IOUT=9.03A
20211130 CHANGE TO 1K OHM
UVP: 2.63V
OVP: 3.89V
START UP TIME:8.21MS
FROM CPLD
FROM PRSNT BUFFER
FROM CPLD
FROM OCP_12V_PG
20211130 CHANGE TO 1K OHM
IMAX=1.1A
DESIGN SPECIFICATION
OCP=IMAX*1.3=1.43A
20211108 MODIFY FOR GTP3V3_OCP_V3
P12V_OCP_V3
IMAX=6.6A
OCP=IMAX*1.3=8.58A
OVP: 14.91V
UVP: 10.17V
FROM PRSNT BUFFER
Thu Aug 24 14:09:24 2023
MB FABCGTI V02
<NAME_1>
<NAME_2> 134 OF 365
NIC_P12V_MAM_TIC_BOM1
P3V3_AUX
P12V_AUX
P12V_AUX
P12V_AUX
P3V3_AUX
P12V_OCP_SFF
P3V3_AUX
P3V3_OCP_SFF_R
P3V3_AUX
P3V3_AUX
P3V3_AUX
P3V3_AUX
P3V3_AUX
8083135
248
258
135 134 136
248
258
136134135248
134135
136248
80
83
135
136
136134
135248
136
131143
131143
131143
131143
136
81
0 5%
1/16W
CHIP
0402LF
NIC_P3V3_BOM1
0402LF
SMLF
NIC_P12V_MAM_TIC_BOM1
MAX15090BEWI+T
C0402
0402LF 1%
1/16W
N IC _P12V_MAM_TIC _BOM1
NIC_P12V_MAM_TIC_BOM1
3900P F
C0402
1/16W
P12V_OC P_FAU LT_1
CHIP
0402LF
0402LF
NIC_P12V_MAM_TIC_BOM1
1%
1/16W
P12V_OC P_PW R GD _1
NIC_P12V_MAM_TIC_BOM1
EMPTY
P12V_OC P_GATE_1
0.01UF
IC
B340A-13-F
1UF
NIC_P12V_MAM_TIC_BOM1
0402LF
SMLF
1/16W
0402LF
P3V3_OCP_EN_1_R
C0402
P3V3_OC P_SEN SE_1
NIC_P12V_MAM_TIC_BOM1
P12V_OC P_VC C _1
PJT138K
P3V3_OCP_SFF_EN_R
E MP TY
NIC_P3V3_BOM1
0402LF
NIC_P3V3_BOM1
N IC _P3V3_BOM1
CHIP
5%
0402LF
5%
0402LF
P12V_OC P_SFF_ISEN SE_MAM_MAM
H P_LVC 3_OC P_V3_1_P12V_PW R GD
0402LF
CHIP
NIC_P12V_MAM_TIC_BOM1
0402LF
CHIP
E MP TY
N IC _P12V_MAM_TIC _BOM1
1/16W
P12V_OC P_SFF_ISEN SE_MAM_TIC
100K
NIC_P12V_MAM_TIC_BOM1
0402LF
CHIP
NIC_P12V_MAM_TIC_BOM1
1%
0402LF
5%0
C0402
P3V3_OC P_FAU LT_1
5%
1/16W
5%
N IC _P12V_MAM_TIC _BOM1
0402LF
NIC_P3V3_BOM1
E MP TY
0402LF
P12V_OCP_SFF_BUF_EN_R
EMPTY
IC
10M
1/16W
CHIP
845
P12V_OC P_SEN SE_1
X 6S
25V
P12V_OC P_U V_1_R
SMLF
PJT138K
0402LFHP_LVC3_OCP_V3_1_P12V_PWRGD 0 5%
NIC_P3V3_BOM1
5%
P3V3_OCP_1_EN_G
P 12V _O CP _S FF_E N_R
PJT138K
PJT138K
IC
NIC_P12V_MAM_TIC_BOM1 P12V_OC P_R EG_1
IC
NIC_P3V3_BOM1
P12V_OCP_SFF_BUF_EN_R
0402LF
NIC_P3V3_BOM1
CHIP
5%
1/16W
0
CHIP
1%
N IC _P12V_MAM_TIC _BOM1 IC
1%
6.8K
1/16W
5%
CHIP
0
CHIP
IC
0.1UF
NIC_P12V_MAM_TIC_BOM1
C0402
25V
1UF
CHIP
C0402
S MF14A
1/16W
X 6S
0402LF
1%
50V
NIC_P12V_MAM_TIC_BOM1
5%
NIC_P12V_MAM_TIC_BOM1
0
0CHIP
0
NIC_P12V_MAM_TIC_BOM1
50V
16V
X6S
OC P_V3_1_P3V3_PW R GD
C0805
NIC_P3V3_BOM1
4.53K
P3V3_OC P_OV_1
0402LF
EMPTY
SMLF
NIC_P 3V 3_B OM1
10
NIC_P 3V 3_B OM1
0402LF
1/16W
100K
NIC_P 3V 3_B OM1
1/16W
1%
CHIP6800PF
NIC_P 3V 3_B OM1
1/16W
10M
1%
0.01UF
0402LF
NIC_P3V3_BOM1
1/16W
50V
E MP TY
NIC_P 3V 3_B OM1
CHIP
C0402
EMPTY
100K
1%
1/16W
E MP TY
NIC_P 3V 3_B OM1
0.1UF
X7R
B340A-13-F
0402LF
OC P_SFF_PR SN T1_R _N
OC P_SFF_PR SN T0_R _N
OC P_SFF_PR SN T3_R _N
OC P_SFF_PR SN T2_R _N
HP_LVC3_OCP_SFF_PRSNT2_N
H P_LVC 3_OC P_V3_1_PR SN T2_N _R H P_LVC 3_OC P_SFF_PR SN T2_PLD _N
SFF_OCP3.0 HSC(1/3)
IC
0402LF
CHIP
1/16W
1%
1K
X6S
0402LF
CHIP
0402LF
10K
CHIP
1%
1/16W
CHIP
1UF
25V
X 6S
10K
10
1%
1/16W
0402LF0
CHIP 1/16W
5%
1UF
1%
15K
25V
0.1UF
X 7R
10%
0402
X 7R
10%
25V
0.1UF
0402
74LVC2G07DW-7
IC
1K
1%
0402LF
CHIP
SMLF
IC
74LVC2G07DW-7
1%
1/16W
0402LF
CHIP
1K
1%
1K
1/16W
4.7K
0
0
1%
1/16W
CHIP
10K
0402LF
CHIP
0402LF
1/16W
5%0
15K
0402LF
5.36K
1%
1/16W
IC
16V
10UF
X6S
25V
50V
0402LF
0402 C0805
25V
C0402
1%
1/16W
CHIP
1%
CHIP
0402LF
1UF
NIC_P3V3_BOM1
C0402
7.15K
1%
IC
CHIP
1/16W
1%
NIC_P3V3_BOM1
1/16W
25.5K
0402LF
MAX15090BEWI+T
SMLF
NIC_P3V3_BOM1
1/16W
NIC_P3V3_BOM1
C0402
25V
X 6S
1UF
NIC_P3V3_BOM1
P3V3_OC P_VC C _1
P3V3_OC P_C B_11/16W
0402LF
CHIP
22UF
16V
10UF
C0805
25V
X7R
0402
CHIP
R3869/R3870 CO-LAYOUT
EMPTY
CHIP
1/16W
1%
1/16W
30.1K
0402LF
CHIP
1%
1/16W
CHIP
CHIP
P12V_OC P_U V_1
NIC_P12V_MAM_TIC_BOM1
NIC_P12V_MAM_TIC_BOM1
NIC_P12V_MAM_TIC_BOM1
P12V_OC P_C B_1
P12V_OC P_OV_1
25V
P3V3_OC P_GATE_PU 202_1
P3V3_OC P_PW R GD _1
100K
1/16W
1/16W
1%
160K
1%
1/16W
10K
5%
0402LF
1/16W
SMLF
5% P12V_OCP_EN_1_R
0402LF
P12V_OCP_1_EN_G
N IC _P12V_MAM_TIC _BOM1
4.7K
0
NIC_P3V3_BOM1
P3V3_OC P_U V_1_R 1
NIC_P3V3_BOM1
P3V3_OC P_R EG_1
P3V3_OC P_U V_1
SMLF
PR4525
PC4056
PC2088
G1
G2
G2
G1
D1S1
S2 D2
CA
S2 D2
D1S1
PD101
R1136
R3794
R3783
R5487
R561
R4061
R576
PR3791 PR3780
PC2086
PC2091
R3796
PC2089
PR5481
PC2144
PC2080PC2092
R3797R3799
R3869
R3870
R3144
PR3781
PR3798
PC2093
PR3789
PR3790
PC5328
R4070
PR3792
PC2085
PC2087
PR5484
R1148
PC2079
PR3786
PR3787
R3784
PR3788
R4068
A2
D2
D1 D7
D3
D6
D4
C6
C4
B6
B4
A4
A1
D5
C5
C3
B5
B3
A5
A3
C2
C1
B2
A6
C7
B7
A7B1
5
PC2081
PC2082
A2
D2
D1 D7
D3
D6
D4
C6
C4
B6
B4
A4
A1
D5
C5
C3
B5
B3
A5
A3
C2
C1
B2
A6
C7
B7
A7B1
52
43
61
52
43
61
2
5
2
4 3
1 6
4 3
1 6
PU202
Q124
PD103
PD102
PU203
U211
U8
Q124
Q123
Q123
CAD NOTE:
PG
FAULT#
GND_C2
GND_C1
GND_B2
CDLY
GATE
OUT_D6
OUT_D4
OUT_C6
OUT_C4
OUT_B6
OUT_B4
OUT_A4
ISENSEOV
UV
REG
EN#
CB
IN_D5
IN_C5
IN_C3
IN_B5
IN_B3
IN_A5
IN_A3
VCC
VCCGND
2Y
1Y
2A
1A
VCCGND
2Y
1Y
2A
1A
PG
FAULT#
GND_C2
GND_C1
GND_B2
CDLY
GATE
OUT_D6
OUT_D4
OUT_C6
OUT_C4
OUT_B6
OUT_B4
OUT_A4
ISENSEOV
UV
REG
EN#
CB
IN_D5
IN_C5
IN_C3
IN_B5
IN_B3
IN_A5
IN_A3
VCC
CA
CA
21
21
21
2
1
2
1
R6045
2
1
R4069
21
21
21
2
1
21
2
1
2
1
2
1
2
1
2
1
2
1
21
21
2
1
PR4524
2
1
2
1
2
1
2
1
21
2
1
2
1
2
1
2
1
2
1
2
1
2
1
CA
CA
CA
1
SHEETDATE
23
7 3 2 16 5 4
E
A
B
C
E
D
C
B
A
7 6 5 4
D
DEPARTMENT
SIZE
PROJECT DOCUMENT NUMBER REV
REVIEWER
DESIGNER
OUT
OUT
OUT
IN
IN
OUT
IN
IN
IN
IN
IN
IN
IN
OUT
OUT
R1486
R577 R1150
R3785
C592
C593
R1907
R1908
R1905
R1906
C



DE-POP
POP
=1.6A
CURRENT LIMIT
DESIGN SPECIFICATION
P3V3_OCP_V3
P12V_OCP_V3
IMAX=6.6A
IMAX=1.1A
OCP=IMAX*1.3=1.43A
ENABLE:
TFAULT: 1.27MS
TDELAY: 6.29MS
VIMON(MAX)= 1.582V @ IOUT=9.09A
MP5025A/
MP5022A
OCP=IMAX*1.3=8.58A
START UP TIME:4.7MS
POP
POP
DE-POP
MP5022C
POP
DE-POP
START UP TIME:8.62MS
2ND SOURCE OF PU202
20221005 MODIFY FOR GTI
FROM CPLD
FROM PRSNT BUFFER
FROM OCP_12V_PG
PR3840
PR3838
PR3843
MP5025C/
DE-POP
PC2158
FROM CPLD
PR3841 POP
DE-POP
PU204 OPTIONAL BOM
FROM PRSNT BUFFER
VTH>1.391V(HIGH)
2ND SOURCE OF PU203
Thu Aug 24 14:09:25 2023
V02
135 OF 365
GTI MB FABC
<NAME_2>
<NAME_1>
P12V_AUX
P3V3_OCP_SFF_R
P12V_OCP_SFF
P12V_AUX
P3V3_AU X
P3V3_AUX
P3V3_AUX
H P_LVC 3_OC P_V3_1_P12V_PW R GD
P12V_OC P_IMON _1
NIC_P12V_MPS_MAM_BOM2
SMLF
IC
RS31312R
P12V_OC P_AVIN _PD _1
P12V_OC P_OV_FB_1
P12V_OC P_FLTB_1
P12V_OC P_EN _1_R 2
P12V_OC P_TIMER _1
P12V_OC P_ISET_1
P12V_OC P_SS_1
0402LF
NIC_P12V_MPS_MAM_BOM2
NIC_P12V_MPS_MAM_BOM2
CHIP
NIC_P12V_MPS_MAM_BOM2
0
0 5%
N IC _P12V_MPS_MAM_BOM2
0.047UF
X 7R
25V
CHIPNIC_P12V_MPS_MAM_BOM2
X 7R
10K
1/16W
NIC_P12V_MPS_MAM_BOM2
1/16W
NIC_P12V_MPS_MAM_BOM2
100NF
C0603
P12V_OC P_AVIN _PD _1
NIC_P12V_MPS_MAM_BOM2
0402
X 7R
10%
2.2UF
16V
20%
X7R
0402LF
0402LF
1%
CHIP
0402LF
1%
0402LF
E MP TY
NIC_P12V_MPS_MAM_BOM2
1/10W
CHIP
0603LF
0402LF
1%
NIC_P12V_MPS_MAM_BOM2
X7R
NIC_P12V_MPS_MAM_BOM2
C0402
CHIP
50V
CHIP
1%
17.4K
1/16W
0.1UF
NIC_P12V_MPS_MAM_BOM2
100
1%
16V
0402
N IC _P3V3_BOM2
CHIP
X 7R
X 6S
NIC_P3V3_BOM2
100PF
50V
C0805
16V
16V
0.22UF
C0402
0402LF
1%
0
25V
SFF_OCP3.0 HSC CO-LAYOUT(2/3)
5%
X7R
0402
IC
10UF
X 6SNIC_P3V3_BOM2
P3V3_OC P_MOD E_1
71.5K
1UF
25V
C0402
P3V3_OC P_ILIMIT_1
P3V3_OC P_GATE_1
P3V3_OC P_D VD T_1
0.068U F
NIC_P3V3_BOM2
1/16W
1%
CHIP
10K
71.5K
1/16W
1% CHIP
0402LF
EMPTY
49.9
1%
NIC_P12V_MPS_MAM_BOM2
10K
1/16W
120K
0
5%
0402
14.3K
1%
0402LF
1/16W
NIC_P12V_MPS_MAM_BOM2
P3V3_OC P_EN _1_R 2
E MP TY
NIC_P3V3_BOM2
MP5016GQH-L-Z
SMLF
N IC _P3V3_BOM2
0402LF
5%
P12V_OCP_SFF_BUF_EN_R
P12V_OCP_SFF_BUF_EN_R
NIC_P3V3_BOM2
E MP TY
0402LF
HP_LVC3_OCP_V3_1_P12V_PWRGD
1.33K
P3V3_OCP_SFF_EN_R
NIC_P3V3_BOM2
0
1%
0402LF
CHIP
N IC _P3V3_BOM2
5%E MP TYP 12V _O CP _S FF_E N_R
NIC_P3V3_BOM2
5%0 CHIP
135
135
258
258
248 135 134 136
248 135 134 136
248 136 135 134
248 134 83 80
248
136
136 134 83 80
50V
39P F
N IC _P3V3_BOM2
NP O
0402
R3871/R3872 CO-LAYOUT
1/16W
CHIP
N IC _P12V_MPS_MAM_BOM2
NIC_P12V_MPS_MAM_BOM2
1/16W
0EMPTY
0402LF
5%
P12V_OC P_SFF_ISEN SE_MPS_MAM
NIC_P12V_MPS_TIC_BOM3
P12V_OC P_SFF_ISEN SE_MPS_TIC
0402LF
5%
NIC_P12V_MPS_MAM_BOM2
N IC _P12V_MPS_MAM_BOM2
135
134
C0402
25V
X 6S
1UF
R1137
R1487
R3845
R591
R3834
PC2159
PC2160
PR3843
PC2158
PR3841
PR3842
PR3838
R4532
PR3839
PC2156PR3837
PC2154
PC2155
PR3835
PC2153
20
19
18
17
16
15
14
13
26
25
24
23
21_22
4
6
10
11
2
5
87
9
3
1
12
PU204
PU205
PC2163
PC2161
PR3844PC2157
PR3840
CAD NOTE:
GND
SS
ISET
TIMER
ENTM
LOADEN
EN
VIN_26
VIN_25
VIN_24
VIN_23
IMON
FLTB
PG
OV
VOUT_13
AVIN
VOUT_14
VOUT_15
VOUT_16
VOUT_17
VOUT_18
VOUT_19
VIN_21_22
VOUT_20
SOURCE
GATE
DV_DT
VCC
GND
ILIMIT
MODE
EN
21
21
21
21
21
1_2 6_7
5
4
3
8
9
10
PC2162PR3846
2
1
2
1
21
21
2
1
2
1
2
1
2
1
2
1
1
SHEETDATE
23
7 3 2 16 5 4
E
A
B
C
E
D
C
B
A
7 6 5 4
D
DEPARTMENT
SIZE
PROJECT DOCUMENT NUMBER REV
REVIEWER
DESIGNER
IN
OUT
OUT
OUT
OUT
IN
IN
IN
IN
IN
R3871
R3872
C



P3V3_OCP_SFF PWRGD
PUSH PULL
PUSH PULL
OPEN DRAIN
PUSH PULL OUTPUT
PUSH PULL
TO OCP_HSC EN
OPEN DRAIN
OCP CARD PRSNT
FROM CPLD
Thu Aug 24 14:09:57 2023
<NAME_1>
MB FABC V02GTI
<NAME_2> 136 OF 365
I31
P3V3_AUX
P3V3_AUX
P3V3_AUX
P3V3_AUX
P3V3_AUX
P3V3_AUX
P3V3_AUX
P3V3_AUX
P3V3_AUX
P3V3_AUX
P3V3_OCP_SFF_R
P3V3_AUX
P3V3_AUX
P3V3_OCP_SFF_R
0402
HP_LVC3_OCP_V3_1_PWRGD_R1
FM_PLD_OCP_SFF_AUX_PWR_EN SET TO HIGH BY DEFAULT
0402LF
FM_PLD_OCP_SFF_AUX_PWR_EN
1%
5%
0.1UF
CHIP
OC P_V3_1_P3V3_R 3_PW R GD
RST_PERST_OCP_SFF_N
0402LF CHIP
10K
HP_LVC3_OCP_V3_1_P12V_R2_PWRGD
HP_LVC3_OCP_V3_1_PWRGD_R2
OC P_V3_1_P3V3_PW R GD
P12V_OC P_V3_1_PLD _PW R GD
CHIP
BSS138K
BSS138K
HP_LVC3_OCP_SFF_PRSNT2
P12V_OCP_SFF_EN_R
134136
134136
136
134
135
136
248
136
134136
134 136
82
82
81
133
134
8083134135
80
131 132
134 135 248
134135136
248
25V
74LVC1G08W5-7
OCP_V3_1_P3V3_PWRGD
HP_LVC3_OCP_V3_1_P12V_R2_PWRGD
1/16W
HP_LVC3_OCP_V3_1_P12V_PWRGD 0402LF0 5%
IC
0402LF
CHIP
P12V_OCP_SFF_EN_R3
1%
0 5% 0402LF
1/16W
0E MP TY
0.1UF
P12V_OC P_V3_1_PLD _R _PW R GD
SN74LVC1G07DBVR
OCP_V3_1_P3V3_PWRGD
RST_PERST_OCP_SFF_R_N
1/16W
OCP_V3_1_P3V3_PWRGD
0402LF
CHIP
E MP TY
CHIP
5% 0402LF
0402LF
0.1UF
0402
5%
X7R
SMLF
10%
1/16W
CHIP
EMPTY
1/16W
H P_LVC 3_OC P_V3_1_P12V_R _PW R GD
SMLF
APX809-29SAG-7
0402LF
CHIP
0 0402LF
1/16W
5%
74LVC1G08W5-7 25V
0.1UF
10%
0402
X7RIC
33.2
33.2
RST_PERST_OCP_SFF_BUF_N
10%
33.2
CHIP0402LF
OCP_SFF_AUX_PWR_EN_R3
25V
IC
0402LF
0402LF
HP_LVC3_OCP_SFF_PRSNT2_N
1/16W
1K
1% SMLF 10%
X7R
0.1UF
0402
CHIP
1/16W
0402LF
1K
0 5%
0 5%E MP TY
SFF_OCP3.0 HSC(3/3)
33.2
0402
25V
10%
0
P12V_OCP_SFF_BUF_EN
25V
OCP_V3_1_P3V3_PLD_PWRGD OCP_V3_1_P3V3_PLD_R_PWRGD
1%
CHIP
OCP_SFF_AUX_PWR_EN
5%
1/16W
EMPTY
0402LF
10K
5%0
0.1UF
X7R
IC
0402LF
1/16W
5%0
0402LF
1/16W
CHIP
1%
1K
SMLF
CHIP
1/16W
33.2
IC
P12V_OCP_SFF_BUF_EN_R
74LVC1G08W5-7
IC
10K
CHIP
1/16W
CHIP
0402LF
1%
IC
0.1UF
25V
0402
10%
X7R
CHIP
74LVC1G32GW
0
E MP TY
25V
SMLF
OCP_V3_1_P3V3_R2_PWRGD
SMLF
X 7R
SMLF
X7R
CHIP
HP_LVC3_OCP_V3_1_P12V_PWRGD
0402
10%
CHIP 1/16W
SN74LVC1G07DBVR
RST_PERST_OCP_SFF_BUF_R_N
0
0402LF
0 0402LF
1K
CHIP 1/16W
HP_LVC3_OCP_V3_1_PWRGD
0402LF
IC
1/16W
OC P_V3_1_P3V3_R 1_PW R GD
100K
R9029
R9030
R1519
C9050
C9008
R1144
R1133
R1130
4
5
3
2
1
3
2
1
5
4
2
1
3
4
5
13
2
4
5
13
2
4
5
3
2
1
G
4
5
3
2
1
S D
U9050
U8001
U9002
U30
U28
U23
U24
R9033
U9001
R9031
R9023
R9022
R9034
DESIGN NOTE:
VCC
Y
GND
B
A
GND
RESET_L
VCC
GND
O
I1
VCC
I0
NC
Y
GND
A
VCC
NC
Y
GND
A
VCC
VCC
Y
GND
B
A
VCC
Y
GND
B
A
21
2 1
21
2
1
2
1
R8092
21R8094
2
1
2
1C8008
2
1
2
1
21
2
1
21
2
1
2
1
2121
2
1
21
21
2
1
2
1
C1059
2
1
21
2
1 C9007
21
2 1
2 1
21
21
21
2
1
R9032
1
SHEETDATE
23
7 3 2 16 5 4
E
A
B
C
E
D
C
B
A
7 6 5 4
D
DEPARTMENT
SIZE
PROJECT DOCUMENT NUMBER REV
REVIEWER
DESIGNER
IN
OUTIN
OUT
IN
IN OUT
OUTIN
IN
OUT
IN
OUT
OUT
IN
IN
IN
R1518
R1509
R8093
R1145
R1142
C1060
R1143
R1132R1129
C1058
R1134
R1131
R1128
C



TO CPU1 PCIE G1 [15:0]
P/N SWAP
P/N SWAP
P/N SWAP
P/N SWAP
P/N SWAP
P/N SWAP
P/N SWAP
P/N SWAP
P/N SWAP
P/N SWAP
P/N SWAP
P/N SWAP
FROM CPU1 PCIE G1 [15:0]
P/N SWAP
P/N SWAP
20210824 MODIFY FOR GT
P/N SWAP
P/N SWAP
Thu Aug 24 14:09:11 2023
MB FABCGTI V02
137 OF 365<NAME_2>
<NAME_1>
P12V_OCP_V3_2_R
P12V_OCP_V3_2_R
P3V3_OCP_V3_2
P3V3_OCP_V3_2
P3V3_OCP_V3_2
P3V3_OCP_V3_2
C LK_100M_C PU 1_C LK05_D P
CLK _50M_NCS I_O CP _V 3_2_IS O
1%200
CHIP 1/16W
0402LFSMB_OC P_V3_2_3V3AU X_BU F_R _SC L SMB_OC P_V3_2_3V3AU X_BU F_SC L
CHIP
1%200
1/16W
0402LF
C LK_100M_C PU 1_C LK03_D N
OC P_V3_2_PR SN T2_R _N
C LK_100M_C PU 1_C LK03_D P
P5E_CPU1_G1_RX_DP<15:0>
P5E_CPU1_G1_RX_DN<15:0>
R ST_PER ST1_OC P_V3_2_N
R ST_SMB_OC P_V3_2_N
SMB_OC P_V3_2_3V3AU X_BU F_R _SD A
139
O CP _V 3_2_P RS NTA _R_N
SMB_OC P_V3_2_3V3AU X_BU F_SD A
N C SI_OC P_V3_2_TXD 1
55
49
143
49
55C LK_100M_C PU 1_C LK05_D N
13780138
29
140 143
140
138
138
139
67
55
55
138
80137
80137
80137
13780
137
137
142 137 138 139
137 80 138
80 137
67
140143
137
13780
80137
80137
80137
139
55
55
138
137142138139
138
140143
29
248
248
55
139
139
139
137
138
139
138
138
80137
FM_OC P_V3_2_PW R _GOOD
5%
0
CHIP
1/16W
0402LF
USB2_CPU0_P10_DN
N C SI_OC P_V3_2_TX_EN
CHIP
OCP_V3_2_PRSNT1_R_N
N C SI_OC P_V3_2_R XD 1
N C SI_OC P_V3_2_R XD 0
IR Q_LVC 3_OC P_V3_2_W AKE_N
P5E_CPU1_G1_TX_C_DP<15:0>
C LK_100M_C PU 1_C LK02_D P
C LK_100M_C PU 1_C LK02_D N
0402LF5%
OC P_V3_2_ISO1_R BT_AR B_IN
0402
X7R
10%
0.1UF
25V
0.1UF
25V
10%
X7R
0402
4.7K
CHIP
1%
0402LF
1/16W
1% CHIP10K
0
4.7K
1%
0402LF
EMPTY
1/16W
CHIP
1/16W
1%
4.7K
0402LF
0402LF
1K 1%
C0805
16V
20%
X6S
22UF 22UF
16V
20%
X6S
C0805
0.1UF
10%
X7R
25V
0402
10%
25V
0402
X7R
0.1UF
10%
25V
X7R
0.1UF
0402
25V
X7R
10%
0402
0.1UF 0.1UF
X7R
0402
10%
25V 25V
0402
0.1UF
10%
X7R
0402
0.1UF
X7R
10%
25V
1/16W
EMPTY
0402LF
1%
4.7K
1/16W
1%10K
0402LF
CHIP
0
0
0402LF0 5%
5%0
1/16W
CHIP
CHIP
SGPIO_OCP_V3_2_LD_N
SGPIO_OCP_V3_2_DATAIN
SGPIO_OCP_V3_2_DATAOUT
SGPIO_OCP_V3_2_CLK
OCP_V3_2_ID0
OCP_V3_2_ID1
OCP_V3_2_AUX_PWR_EN
FM_OCP_V3_2_PWR_GOOD
OCP_V3_2_MAIN_PWR_EN
IO_SLOT IO_SLOT
10K 1%
CHIP10K 1%
1/16W
1K 1%
0402LF
IO_SLOT IO_SLOT
1/16W0402LF
CHIP1%100K
PLACE THE BULK CAPS CLOSE TO SLOT
PCIE - V3_2 OCP3.0_X16_CPU1 (1/3)
CHIP 1/16W
0402LF5%0
5% 0402LF
P5E_CPU1_G1_TX_C_DN<15:0>
OCP_V3_2_PRSNT3_R_N
TP_OCP_V3_2_B69
OC P_V3_2_AU X_PW R _EN _R
OC P_V3_2_ID 0
SGPIO_OC P_V3_2_C LK
SGPIO_OC P_V3_2_D ATAOU T
SGPIO_OC P_V3_2_D ATAIN
SGPIO_OC P_V3_2_LD _N
OC P_V3_2_MAIN _PW R _EN _R
IO
OCP_V3_2_PWRBRK_N
USB2_P10_DP
USB2_P10_DN
C LK_100M_C PU 1_C LK04_D N
C LK_100M_C PU 1_C LK04_D P
N C SI_OC P_V3_2_C R S_D V
0402LF5%
OC P_V3_2_AU X_PW R _EN
OC P_V3_2_ISO_BIF1_EN
OC P_V3_2_PR SN T0_R _N
TP_OCP_V3_2_B68
1/16W
CHIP
5% 0402LF
USB2_CPU0_P10_DP0402LF
0
IO_SLOT
SMLF
SCONN168_ME1016810202011
R ST_PER ST3_OC P_V3_2_N
R ST_PER ST2_OC P_V3_2_N
OC P_V3_2_ID 1
OC P_V3_2_ISO2_R BT_AR B_OU T
OC P_V3_2_BIF2_R _N
OC P_V3_2_BIF1_R _N
OC P_V3_2_BIF0_R _N
R ST_PER ST0_OC P_V3_2_N
OC P_V3_2_ISO_BIF2_EN
OC P_V3_2_ISO_BIF0_EN
OC P_V3_2_MAIN _PW R _EN
138
138
138
55
N C SI_OC P_V3_2_TXD 0
139
21R3228
21
R3180
R3177
R3178
R3168
R3176
R3175
R3174
OA3
A69
A68
A9
A8
A7
OA6
OB7
B69
B68
OA12OB12
A15B15
OA11OB11
A14B14
OA8
OA9
OA7
OB8
OB9
OB14 OA14
OA5
OA4
A70B70
A12
A42B42
A10
B66
B63
B60
B57
B54
B51
B48
B45
B40
B37
B34
B31
B27
B24
B21
B18
B65
B62
B59
B56
B53
B50
B47
B44
B39
B36
B33
B30
B26
B23
B20
B17
OA2
OA1
A11
B10
A66
A63
A60
A57
A54
A51
A48
A45
A40
A37
A34
A31
A27
A24
A21
A18
A65
A62
A59
A56
A53
A50
A47
A44
A39
A36
A33
A30
A26
A23
A20
A17
OB1
OB2
OB3
OB13
OB10
OA13
OA10
B67
B64
B61
B58
B55
B52
B49
B46
B43
B41
B38
B35
B32
B29
B28
B25
B22
B19
B16
B13
A67
A64
A61
A58
A55
A52
A49
A46
A43
A41
A38
A35
A32
A29
A28
A25
A22
A19
A16
A13
A6
A5
A4
A3
A2
A1
G5
G4
G3
G2
G1
OB5
OB4
OB6
B9
B8
B7
B12
B6
B5
B4
B3
B2
B1
B11
15
12
0
00
1
15
15
14
14
12
11
12
10
11
10
9
8
8
9
7
6
7
6
5
4
5
4
3
2
3
15
14
13
11
12
10
9
13
14
11
8
9
6
4
5
6
5
4
3
2
1
2
3
13
13
2
0
1
1
10
8
7
7
J35
CAD NOTE:
KEY
KEY
KEY
G5
G4
G3
G2
G1
PRSNTB3#
RFU1_NC_B69
RFU1_NC_B68
GND_B67
PETp15
PETn15
GND_B64
PETp14
PETn14
GND_B61
PETp13
PETn13
GND_B58
PETp12
PWRBRK0#
USB_DATp
USB_DATn
GND_A67
PERp15
PERn15
GND_A64
PERp14
PERn14
GND_A61
PERp13
PERn13
GND_A58
PERp12
PERn12
GND_A55
PERp11
PERn11
GND_A52
PERp10
PERn10
GND_A49
PERp9
PERn9
GND_A46
PERp8
PERn8
GND_A43
PRSNTB1#
GND_A41
PERp7
PERn7
GND_A38
PERp6
PERn6
GND_A35
PERp5
PERn5
GND_A32
PERp4
PERn4
GND_A29
GND_A28
PERp3
PERn3
GND_A25
PERp2
PERn2
GND_A22
PERp1
PERn1
GND_A19
PERp0
PERn0
GND_A16
REFCLKp1
REFCLKn1
GND_A13
PRSNTB2#
PERST1#
PRSNTA#
SMRST#
SMDAT
SMCLK
GND_A6
GND_A5
GND_A4
GND_A3
GND_A2
GND_A1
RBT_CLK_IN
GND_OA13
REFCLKp3
REFCLKn3
GND_OA10
RBT_TXD0
RBT_TXD1
RBT_TX_EN
SLOT_ID1
RBT_ARB_OUT
RBT_ARB_IN
WAKE#
PERST3#
PERST2#
PETn12
GND_B55
PETp11
PETn11
GND_B52
PETp10
PETn10
GND_B49
PETp9
PETn9
GND_B46
PETp8
PETn8
GND_B43
PRSNTB0#
GND_B41
PETp7
PETn7
GND_B38
PETp6
PETn6
GND_B35
PETp5
PETn5
GND_B32
PETp4
PETn4
GND_B29
GND_B28
PETp3
PETn3
GND_B25
PETp2
PETn2
GND_B22
PETp1
PETn1
GND_B19
PETp0
PETn0
GND_B16
REFCLKp0
REFCLKn0
GND_B13
AUX_PWR_EN
+3.3V_EDGE
PERST0#
BIF2#
BIF1#
BIF0#
+12V_EDGE_B6
+12V_EDGE_B5
+12V_EDGE_B4
+12V_EDGE_B3
+12V_EDGE_B2
+12V_EDGE_B1
RBT_CRS_DV
GND_OB13
REFCLKp2
REFCLKn2
GND_OB10
RBT_RXD0
RBT_RXD1
SLOT_ID0
CLK
DATA_OUT
DATA_IN
LD#
MAIN_PWR_EN
NIC_PWR_GOOD
R3229
2
1
21
21
21
21R3171
21R3170
21R3172
21R3164
2
1
2
1 C1838
2
1 C1836
2
1 C1835
2
1
2
1 C1833
2
1 C1832
2
1 C1831
2
1 C1830
2
1 C1829
21
21
21R3173
21
2
1
2
1
21R3169
21R8413
21R3165
2
1
2
1 C1837
2
1 C1834
1
SHEETDATE
23
7 3 2 16 5 4
E
A
B
C
E
D
C
B
A
7 6 5 4
D
DEPARTMENT
SIZE
PROJECT DOCUMENT NUMBER REV
REVIEWER
DESIGNER
IN
IN
IN
OUT
IN
OUT
OUT
IN
IN
OUT
OUT
IN
OUT
OUT
IN
IN
OUT
OUT
OUT
OUT
OUT
OUT
OUT
IN
IN
IN
IN
IN
IN
IN
OUT
OUT
IN
IN
IN
IN
OUT
OUT
IN
IN
IN
IN
IN
IN
IN
IN
BI
IN
IN
IN
OUT
IN
IN
OUT
OUT
OUT
IN
R3166
C1839
R3167R3163
R3162
C



20210824 MODIFY FOR GT
Thu Aug 24 14:09:10 2023
<NAME_1>
MB FABC
<NAME_2>
V02GTI
138 OF 365
P3V3_AUX
P3V3_AUX
P3V3_AUX
139
81
137
137
13780
137142139
137
132 150
143
132 150
143
132
150
132 150
132 150
137
137
137
137
137
137
137
137 132
150
FB_BMC _ISOLATE1
E MP TY
1/16W0402LF
0 5%FM_N C SI_OC P_V3_2_R _OE
1/16W
5% CHIP
0402LF
0FB_BMC _ISOLATE_R 2
0402LF
CHIP
1/16W
100K
SMLF
OCP_V3_2_ISO1_RBT_ARB_IN
0402
74CBTLV3126PW
NCSI_BMC_RXD1_R1
NCSI_OCP_V3_2_TXD1
OCP_V3_2_AUX_PWR_EN_R1
FM_OCP_V3_2_PWR_GOOD
X 7R
OCP_V3_2_AUX_PWR_EN
74LVC1G126SE-7
1%
25V
0.1UF
10%
0402
IC
SMLF
74CBTLV3126PW
0402
0.1UF
25V
X 7R
10%
100
1%
1/16W
0402LF
CHIP CHIP
100
1%
1/16W
0402LF
1%
100
CHIP
1/16W
0402LF
EMPTY0
0 EMPTY
0 EMPTY
22 E MP TY
22 E MP TY
1/16W
22
0402LF
E MP TY
22 E MP TY
X 7R
0.1UF
25V
10%
IC
SMLF
0
CHIP
IC
33.2 1%
CHIP
0402LF
1/16W
OCP_V3_2_ISO2_RBT_ARB_OUT
RMII_OCP_BMC_RXD_1
NCSI_BMC_TX_EN_R1
OCP_V3_2_RBT_ARB_OUT
RMII_BMC_OCP_TXD_1
OCP_V3_2_RBT_ARB_IN
CO-LAYOUT
RMII_OCP_BMC_RXD_0
NCSI_BMC_TXD0_R1
NCSI_BMC_TXD1_R1
RMII_BMC_OCP_TX_EN
RMII_BMC_OCP_TXD_0
OCP_V3_2_ISO_BIF0_EN
OCP_V3_2_ISO_BIF1_EN
OCP_V3_2_ISO_BIF2_EN
NCSI_OCP_V3_2_TX_EN
NCSI_OCP_V3_2_TXD0
PCIE - V3_2 OCP3.0 (2/3)
OCP_V3_2_RBT_ARB_IN_R
NCSI_OCP_V3_2_RXD1
NCSI_OCP_V3_2_RXD0
NCSI_OCP_V3_2_CRS_DV
NCSI_BMC_RXD0_R1
NCSI_BMC_CRS_DV_R1 RMII_OCP_BMC_CRSDV
R3203
R3217R3216R3208
4
1
2
R3210
R3209
R3211
R3212
R3213
R3214
R3215
53
U286
U223
U222
OE
Y
A
VCC
4OE
4A4B
3OE
3A
GND
1A
2B
1B
2OE
1OE
3B
2A
VCC
4OE
4A4B
3OE
3A
GND
1A
2B
1B
2OE
1OE
3B
2A
GND VCC
21R3205
21R3206
21
14
7
13
11 12
10
8 9
4
6 5
1
3 2
2
1
2
1
2
1
2
1
2
1
14
7
13
11 12
10
8 9
4
6 5
1
3 2
2
1
2
1
R3207
21
1
SHEETDATE
23
7 3 2 16 5 4
E
A
B
C
E
D
C
B
A
7 6 5 4
D
DEPARTMENT
SIZE
PROJECT DOCUMENT NUMBER REV
REVIEWER
DESIGNER
IN
OUT
IN
74CBTLV3126
OUT
OUT
OUT
OUT
IN
IN
IN
IN
OUT
OUT
OUT
74CBTLV3126
IN
IN
IN
IN
IN
OUT
OUT
OUT
OUT
R3244
C1827
C1826
C1825
C



20220120 ADD R4602
POP
20210824 MODIFY FOR GT
RST FOR OCP V3_2
Thu Aug 24 14:09:12 2023<NAME_2>
<NAME_1>
MB FABCGTI V02
139 OF 365
P3V3_OCP_V3_2
P3V3_AUX
P3V3_AUX
P3V3_AUX
P3V3_AUX
P3V3_AUX
P3V3_AUX
P3V3_AUX
P3V3_AUXP3V3_AUX
142
133
138
137
137142138
80132241246251253
8083133
137
137
155
137
137
137
137
1370
0
0
0RST_PERST_OCP_V3_2_BUF_N RST_PERST_OCP_V3_2_BUF2_N
74LVC1G17GW
CLK _50M_NCS I_O CP _V 3_2
74LVC1G66GV
IC
CLK _50M_NCS I_O CP _V 3_2_IS O _R
SMLF
FB_BMC _ISOLATE1
1/16W
0402LF
CHIP
1%
4.7K
OCP_V3_2_PWRBRK_BUFF_N
IRQ_LVC3_OCP_V3_2_WAKE_N
PU_OCP_V3_2_WAKE_OE
OCP_V3_2_AUX_PWR_EN
RST_SMB_SWITCH_N
OCP_V3_2_AUX_PWR_EN_R3
FM_SYS_THROTTLE_N
NC_U218_NC1
OCP_V3_2_WAKE_BUFF_N
R ST_H P_OC P_V3_2_R _N R ST_SMB_OC P_V3_2_N
NC_U219_NC1
CLK _50M_NCS I_O CP _V 3_2_IS O
IRQ_LVC3_V3_2_WAKE_BUF_N IR Q_OC P_V3_2_W AKE_BU F_N
10K
1%
1/16W
0402LF
CHIP
0402LF
1%
10K
1/16W
CHIP
1%33.2
CHIP 1/16W
0402LF
74LVC1G126SE-7
SMLF
IC
10%
0402
X 7R
25V
0.1UF
SMLF74LVC1G126SE-7
IC
0.1UF
10%
X 7R
0402
25V
4.7K
0402LF
1%
1/16W
CHIP
IC
SMLF
74LVC1G07GV
100K
0402LF
CHIP
1/16W
1%
1/16W
5% CHIP
0402LF
0
0402LF 1/16W
1%33.2
25V
0.1UF
X 7R
10%
0402
IC
1%
1/16W
33.2
CHIP
0402LF
0 CHIP
0402
X 7R
0.1UF
10%
25V
1/16W
CHIP
0402LF
1/16W
4.7K
1%
EMPTY
0.1UF
25V
10%
X 7R
0402
PCIE - V3_2 OCP3.0 (3/3)
33.2 1%
0402LF
OCP_V3_2_PWRBRK_N
OCP_V3_2_WAKE_BUFF_R_NCHIP
74LVC1G07GV
SMLF
PLACE R3192 CLOSE TO U219
IC
SMLF
X 7R
0402
10%
25V
0.1UF
RS T_P E RS T0_O CP _V 3_2_N
RS T_P E RS T1_O CP _V 3_2_N
RS T_P E RS T2_O CP _V 3_2_N
RS T_P E RS T3_O CP _V 3_2_N
21 R6059
21 R6058
21 R6057
21 R6056
R3193
R3185
R3191
R3234
2
1 5
3
4
4
5
13
2
4
51
3
2
4
51
3
2
4
1
2
4
1
2
53
53
U321
U207
U219
U218
U217
U225
CAD NOTE:
OE
Y
A
VCC
E
GND
Z
Y
NC
Y
GND
A
VCC
NC1
YGND
A
VCC
NC1
YGND
A
VCC
OE
Y
A
GND VCC
GND VCC
2
1
21
21R4602
2
1
R3190
21
21R3236
2
1
2
1
2
1
R3183
2
1
R3182
2
1
2
1
2
1
21
2
1
2
1
R3235
2
1
21
1
SHEETDATE
23
7 3 2 16 5 4
E
A
B
C
E
D
C
B
A
7 6 5 4
D
DEPARTMENT
SIZE
PROJECT DOCUMENT NUMBER REV
REVIEWER
DESIGNER
OUT
OUT
IN
OUT
OUT
IN
OUT
IN
OUT
IN
OUT
OUT
IN
IN
IN
C1821
R3184C1822
C38
R3192
C1824
C1823
C1841
C



FROM PRSNT BUFFER
FROM PRSNT BUFFER
UVP: 10.17V
OVP: 14.91V
START UP TIME:8.21MS
START UP TIME:3.94MS
FROM CPLD
VIMON(MAX)= 1.679V @ IOUT=9.03A
20211130 CHANGE TO 1K OHM
IMAX=6.6A
OCP=IMAX*1.3=1.43A
P12V_OCP_V3_2
P3V3_OCP_V3_2_R
DESIGN SPECIFICATION
IMAX=1.1A
20211108 MODIFY FOR GT
OCP=IMAX*1.3=8.58A
OVP: 3.89V
UVP: 2.63V
VIMON(MAX)= 1.594V @ IOUT=1.6A
20211130 CHANGE TO 1K OHM
Thu Aug 24 14:09:12 2023<NAME_2>
<NAME_1>
MB FABCGTI V02
140 OF 365
P3V3_AUX
P12V_AUX
P3V3_AUX
P3V3_OCP_V3_2_R
P3V3_AUX
P3V3_AUX
P3V3_AUX
P12V_AUX
P3V3_AUX
P3V3_AUX
P12V_OCP_V3_2
P12V_AUX
P3V3_AUX
N IC _P12V_MAM_TIC _BOM1
140141
142248
8183141
248
142140
141248
142140
141248
81
83
141
142
141 140 142
248
142
80
137143
137143
137143
137143
142
258
258
5%0 CHIP
NIC_P3V3_BOM1
H P_LVC 3_OC P_V3_2_P12V_PW R GD
NIC_P3V3_BOM1
P3V3_OCP_V3_2_EN_R
P12V_OCP_V3_2_BUF_EN_R
P12V_OC P_V3_2_BU F_EN _R
NIC_P3V3_BOM1
CHIP
N IC _P12V_MAM_TIC _BOM1
0402LF
P12V_OCP_V3_2_EN_R
E MP TY
10K
PJT138K
SMLF
NIC_P12V_MAM_TIC_BOM1
P12V_OC P_U V_2_R
C0402
CHIP
1/16W
C0402
NIC_P12V_MAM_TIC_BOM1
0402LF
6.8K
1/16W
CHIP
0402LF
NIC_P12V_MAM_TIC_BOM1
NIC_P12V_MAM_TIC_BOM1
EMPTY 3900PF
NIC_P12V_MAM_TIC_BOM1
50V
1/16W
CHIP
1%
IC
C0402
NIC_P12V_MAM_TIC_BOM1
10
1%
1/16W
NIC_P12V_MAM_TIC_BOM1
CHIP
0402LF
P12V_OC P_U V_2
P12V_OC P_R EG_2
P12V_OC P_OV_2
P12V_OC P_C B_2
NIC_P12V_MAM_TIC_BOM1
NIC_P12V_MAM_TIC_BOM1
1/16W
CHIP CHIP
1%
1/16W
30.1K
0402LF
50V
H P_LVC 3_OC P_V3_2_P12V_PW R GD
NIC_P12V_MAM_TIC_BOM1
0402LF
0402LF
CHIP 0 5%
0402LF
845
1/16W
0402LF
NIC_P12V_MAM_TIC_BOM1
R3867/R3868 CO-LAYOUT
CHIP
0402LF
CHIP
0
NIC_P12V_MAM_TIC_BOM1
1%
C0805
NIC_P3V3_BOM1
NIC_P3V3_BOM1
PJT138K
SMLF
P3V3_OC P_U V_2_R 1
CHIP
0
NIC_P3V3_BOM1
1/16W
5% 0402LF
NIC_P3V3_BOM1
C0402
1%
NIC_P3V3_BOM1
CHIP NIC_P3V3_BOM1
NIC_P3V3_BOM1
6800PFNIC_P3V3_BOM1
P3V3_OC P_GATE_2
P3V3_OC P_OV_2
0402LF
1%
15K
C0402
NIC_P3V3_BOM1
C0402
25V
X 6S
N IC _P3V3_BOM1
10
1%
CHIP
1UF
NIC_P3V3_BOM1
0402LF
1/16W
P3V3_OC P_SEN SE_2
P3V3_OC P_FAU LT_2
0402LF
EMPTY
100K
1/16W
CHIP
0402LF
OC P_V3_2_P3V3_PW R GD
1%
10M
1/16W
0402
50V
0.01UF
B340A-13-F
X6S
16V
10UF
25V
C0805
0
CHIP
5% 0402LF
1/16W
1K
0402LF
1%
1/16W
CHIP
0 5%
EMPTY
EMPTY
0
100K
1/16W
E MP TY
1%
0402LF
1/16W
0402LF
CHIP
1K
1%
1K
1%
1/16W
0402LF
CHIP
1/16W
1%
IC
IC
SMLF
74LVC2G07DW-7
0.1UF
25V
10%
0402
X 7R
SMLF
IC
74LVC2G07DW-7
0.1UF
25V
0402
X 7R
10%
15K
0402LF
1%
0402LF
CHIP
1K
1%
1/16W
1%
IC
SMF14A
1UF
25V
X 6S
CHIP
1/16W
C0402
25V
1UF
1/16W
0402LF
25.5K
1%
0402LF
1/16WCHIP
0 5%
1K
1%
1/16W
CHIP
0402LF
CHIP
1/16W
1%
0402LF
1K
5%0
100K
1/16W
1%
CHIP
1/16W
CHIP
5.36K
1%
IC
4.53K
1%
CHIP
25V
X6S
16V
C0805
V3_2_OCP3.0 HSC(1/3)
H P_LVC 3_OC P_V3_2_PR SN T2_PLD _N
OC P_V3_2_PR SN T1_R _N
OC P_V3_2_PR SN T0_R _N
H P_LVC 3_OC P_V3_2_PR SN T2_N _R
OC P_V3_2_PR SN T3_R _N
OC P_V3_2_PR SN T2_R _N
H P_LVC 3_OC P_V3_2_PR SN T2_N
X7R
0.1UF 10UF
16V
X6S
C0402
P3V3_OC P_PW R GD _2
0402LF
0 5%
N IC _P3V3_BOM1
E MP TY
1/16W
N IC _P3V3_BOM1
50V
MAX15090BEWI+T
CHIP
X 6S
0402LF
NIC_P3V3_BOM1
SMLF
1/16W
NIC_P3V3_BOM1
NIC_P3V3_BOM1
25V1UF
1%
CHIP
7.15K
P3V3_OC P_C B_2
P3V3_OC P_VC C _2
P3V3_OC P_R EG_2
P3V3_OC P_U V_2
NIC_P3V3_BOM1
1/16W
0402LF
NIC_P3V3_BOM1
SMLF
NIC_P3V3_BOM1
IC
4.7K
5%
1/16W
0402LF
0402LF
P3V3_OCP_2_EN_G
NIC_P3V3_BOM1
1/16W
100K
22UF
0402LF
0.1UF
P12V_OC P_GATE_2
IC
B340A-13-F
X7R
1/16W
P12V_OC P_V3_2_ISEN SE_MAM_MAM
5%
P12V_OC P_V3_2_ISEN SE_MAM_TIC
EMPTY
0402LF
C0402
0402LF
1/16W
NIC_P12V_MAM_TIC_BOM1
CHIP
0402
P12V_OC P_FAU LT_2
P12V_OC P_SEN SE_2
P12V_OC P_PW R GD _2
25V
C0402
1UF
X 6S
NIC_P12V_MAM_TIC_BOM1
SMLF
MAX15090BEWI+T
N IC _P12V_MAM_TIC _BOM1
1/16W
1%
1UF
P12V_OC P_VC C _2
25V
1%
0402LF
1%
160K
CHIP
1/16W
10M
0.01UF
1/16W
NIC_P12V_MAM_TIC_BOM1
CHIP
IC
5%0
NIC_P12V_MAM_TIC_BOM1
NIC_P12V_MAM_TIC_BOM1
P12V_OCP_2_EN_G
5% CHIP
N IC _P12V_MAM_TIC _BOM1
4.7K
5%
1/16W
0402LF
SMLF
PJT138K
IC
N IC _P12V_MAM_TIC _BOM1
P12V_OCP_EN_2_R
NIC_P12V_MAM_TIC_BOM1
PJT138K
0
E MP TY
5% P3V3_OCP_EN_2_R
10K
0 5%
E MP TY
PC2149
C40
PR3829
G2
G1
G2
G1
CA
S2 D2
D1S1
S2 D2
D1S1
PD107
R1182
R3826
R3832
R1181
R4060
R4059
R1191
PC2137
PC2151
PR3782
R3816
R3831
PC2150
PC2140
R3807
PR3828
R4065
R3833
PC2141PC2152
PR3824
C39
PR3822
PC2147
PR3830
R3825
21 R3868
PR3823
PC2146
PC2098
PR3821
R3142
PR3795
PR3812
PC2139
R4067
PR3805
PR3806
PC2142
52
43
61
PC2143
A2
D2
D1 D7
D3
D6
D4
C6
C4
B6
B4
A4
A1
D5
C5
C3
B5
B3
A5
A3
C2
C1
B2
A6
C7
B7
A7B1
A2
D2
D1 D7
D3
D6
D4
C6
C4
B6
B4
A4
A1
D5
C5
C3
B5
B3
A5
A3
C2
C1
B2
A6
C7
B7
A7B1
5
2
52
43
61
5
2
4 3
1 6
4 3
1 6
PD109
U59
PD108
PU200
PU201
Q119
Q119
U58
Q118
Q118
CAD NOTE:
PG
FAULT#
GND_C2
GND_C1
GND_B2
CDLY
GATE
OUT_D6
OUT_D4
OUT_C6
OUT_C4
OUT_B6
OUT_B4
OUT_A4
ISENSEOV
UV
REG
EN#
CB
IN_D5
IN_C5
IN_C3
IN_B5
IN_B3
IN_A5
IN_A3
VCC
PG
FAULT#
GND_C2
GND_C1
GND_B2
CDLY
GATE
OUT_D6
OUT_D4
OUT_C6
OUT_C4
OUT_B6
OUT_B4
OUT_A4
ISENSEOV
UV
REG
EN#
CB
IN_D5
IN_C5
IN_C3
IN_B5
IN_B3
IN_A5
IN_A3
VCC
VCCGND
2Y
1Y
2A
1A
VCCGND
2Y
1Y
2A
1A
CA
CA
21
21
2
1
21
21
21
2
1
R4066
2
1
R6060
21
2
1
21
2
1
2
1
2
1
2
1
21
2
1
PR4522
2
1
2
1
21
2
1
2
1
2
1
2
1
2
1
2
1
2
1
2
1
2
1
2
1
2
1
2
1
2
1
21
2
1
2
1
2
1
2
1
21
2
1
2
1
2
1
2
1
2
1
21
2
1
2
1
2
1
CA
2
1
2
1
CA
2
1
2
1
CA
1
SHEETDATE
23
7 3 2 16 5 4
E
A
B
C
E
D
C
B
A
7 6 5 4
D
DEPARTMENT
SIZE
PROJECT DOCUMENT NUMBER REV
REVIEWER
DESIGNER
OUT
OUT
OUT
OUT
IN
IN
IN
IN
IN
IN
IN
OUT
OUT
IN
IN
R1520
R1192
C1809
C1810
R3134
PR4523
R3867
R3147
R3827
R3135R3133
R3136
C



START UP TIME:4.7MS
START UP TIME:8.62MS
PR3857
PR3852
20211108 MODIFY FOR GT
2ND SOURCE OF PU200
MP5025A/
DE-POPPOP
POP
MP5022A
FROM CPLD
FROM PRSNT BUFFER
VTH>1.391V(HIGH)
PU206 OPTIONAL BOM
=1.6A
CURRENT LIMIT
PC1320
DE-POP
POP
VIMON(MAX)= 1.582V @ IOUT=9.09A
POP
ENABLE:
DESIGN SPECIFICATION
IMAX=6.6A
OCP=IMAX*1.3=8.58A
P12V_OCP_V3_2
P3V3_OCP_V3_2_R
IMAX=1.1A
OCP=IMAX*1.3=1.43A
TDELAY: 6.29MS
TFAULT: 1.27MS
MP5022C
POP
DE-POP
DE-POP
MP5025C/
DE-POPPR3850
PR3853
2ND SOURCE OF PU201
Thu Aug 24 14:09:12 2023
GTI
141 OF 365
V02MB FABC
<NAME_1>
<NAME_2>
P3V3_AUX
P3V3_OCP_V3_2_R
P12V_AUX
P3V3_AUX
P3V3_AUX
P12V_OCP_V3_2
P12V_AUX
NIC_P12V_MPS_MAM_BOM2
H P_LVC 3_OC P_V3_2_P12V_PW R GD
IC
SMLF
RS31312R
NIC_P12V_MPS_MAM_BOM2
P12V_OC P_AVIN _PD _2
P12V_OC P_OV_FB_2
P12V_OC P_FLTB_2
P12V_OC P_IMON _2
P12V_OC P_V3_2_EN _2_R 3
P12V_OC P_TIMER _2
P12V_OC P_ISET_2
P12V_OC P_SS_2
1%
1/16W
N IC _P12V_MPS_MAM_BOM2
NIC_P12V_MPS_MAM_BOM2
10K
NIC_P12V_MPS_MAM_BOM2
142
0402
50VNP O
39P F
N IC _P3V3_BOM2
142140141248
140141142248
8183140142
142140141248
258
258
141
141
140 141 248
8183140248
0
NIC_P3V3_BOM2
5% CHIPP12V_OCP_V3_2_BUF_EN_R
HP_LVC3_OCP_V3_2_P12V_PWRGD
P12V_OCP_V3_2_EN_R
E MP TY
X7R
16V
0.22UF
0 5%
P12V_OCP_V3_2_BUF_EN_R
0402
20%
1%
120K
1%
1%
1/16W
49.9
100
E MP TY
1%
1.33K
C0402
1%
0402LF
P3V3_OC P_GATE_PU 207_2
0402
10%
X6S
100P F
V3_2_OCP3.0 HSC-CO-LAYOUT(2/3)
25V
C0402
NPO
5%
50V
0402
IC
10%
1/16W
0402
0402LF
25V
1UF
X6S
X 7R
N IC _P3V3_BOM2
C0805
X6S
NIC_P3V3_BOM2
X 7R
SMLF
NIC_P3V3_BOM2
NIC_P3V3_BOM2
CHIP
0402LF
71.5K
CHIP
N IC _P3V3_BOM2
MP5016GQH-L-Z
25V
NIC_P3V3_BOM2
16V
0.068U F
P3V3_OC P_D VD T_2
P 3V 3_O CP _ILIMIT_2
P3V3_OC P_MOD E_2
CHIP
10K
71.5K
1/10W
0603LF
16V
1/16W
1%
CHIP
NIC_P12V_MPS_MAM_BOM2
CHIP
CHIP
2.2UF
0402LF
1%
0402LF
NIC_P12V_MPS_MAM_BOM2
50V
0402LF
CHIP
1%10K
1/16W
EMPTY
1%
CHIP
1/16W
0402LF
0402LF
5%0 CHIP
C0402
N IC _P12V_MPS_MAM_BOM2
1%
14.3K
0.047UF
X7R
0402LF
NIC_P12V_MPS_MAM_BOM2
CHIP
NIC_P12V_MPS_MAM_BOM2
NIC_P12V_MPS_MAM_BOM2
P3V3_OCP_V3_2_EN_R
E MP TY
0 5%
N IC _P3V3_BOM2
1UF
P3V3_OC P_EN _2
NIC_P3V3_BOM2
0 5%
E MP TY
NIC_P3V3_BOM2
0
1/16W
N IC _P12V_MPS_MAM_BOM2
5%
R3873/R3874 CO-LAYOUT
X7R
1/16W
NIC_P12V_MPS_MAM_BOM2
NIC_P12V_MPS_MAM_BOM2
17.4K
0402LF
CHIP
0.1UF
0402
P12V_OC P_V3_2_ISEN SE_MPS_MAM
1/16W
EMPTY 0 5%
0402LF
P12V_OC P_V3_2_ISEN SE_MPS_TIC
NIC_P12V_MPS_TIC_BOM3
C0603NIC_P12V_MPS_MAM_BOM2
0402LF
NIC_P12V_MPS_MAM_BOM2
P12V_OC P_AVIN _PD _2
X7R
25V
NIC_P12V_MPS_MAM_BOM2
10%
16V
10UF
100PF
NIC_P12V_MPS_MAM_BOM2
N IC _P12V_MPS_MAM_BOM2
R3848
R3873
R3874
R1196
R3631
R3630
PC2169
PR3856
PC2174
PR3857PR3853
PC1320
PR3854
PR3851
PR3849
PR3847
20
19
18
17
16
15
14
13
26
25
24
23
21_22
4
6
10
11
2
5
87
9
3
1
12
PU206
PC1322
PU207
PC1321
PR3855PC2168
PR3852
CAD NOTE:
GND
SS
ISET
TIMER
ENTM
LOADEN
EN
VIN_26
VIN_25
VIN_24
VIN_23
IMON
FLTB
PG
OV
VOUT_13
AVIN
VOUT_14
VOUT_15
VOUT_16
VOUT_17
VOUT_18
VOUT_19
VIN_21_22
VOUT_20
SOURCE
GATE
DV_DT
VCC
GND
ILIMIT
MODE
EN
21
21
21
R1193
21
21
2
1 PC2167
PC2173
1_2 6_7
5
4
3
8
9
10
2
1
2
1
2
1
2
1
2
1
21
21
2
1
PC2165
PC2166
2
1
PC2164
1
SHEETDATE
23
7 3 2 16 5 4
E
A
B
C
E
D
C
B
A
7 6 5 4
D
DEPARTMENT
SIZE
PROJECT DOCUMENT NUMBER REV
REVIEWER
DESIGNER
IN
IN
IN
IN
OUT
IN
OUT
IN
OUT
OUT
R1521
PR3850
C



OPEN DRAIN
TO OCP_12V_HSC EN
PUSH PULL
FROM CPLD
OCP CARD PRSNT
PUSH PULL
OPEN DRAIN
PUSH PULL
P3V3_OCP_V3_2 PWRGDPUSH PULL OUTPUT
Thu Aug 24 14:09:57 2023<NAME_2>
<NAME_1>
MB FABCGTI V02
142 OF 365
I24
P3V3_AUX
P3V3_AUX
P3V3_AUX
P3V3_AUX
P3V3_AUX
P3V3_AUX
P3V3_AUX
P3V3_AUX
P3V3_AUX
P3V3_OCP_V3_2_R
P3V3_AUX
P3V3_OCP_V3_2_R
P3V3_AUX
P3V3_AUX
81
80
140
142
142
140 141 248
140
8183140141
80140142
139
80
137 138 139
140141142
248
140 142
140
141
142
248
142
140142
0.1UF
1/16WCHIP
RST_PERST_OCP_V3_2_N
E MP TY 5%0
0.1UF
25V
0402
0402LF
P12V_OC P_V3_2_PLD _PW R GD
SMLF
0402
10%
25V
OCP_V3_2_P3V3_PWRGD
HP_LVC3_OCP_V3_2_P12V_PWRGD_R2
P12V_OCP_V3_2_BUF_EN_RP12V_OCP_V3_2_BUF_EN
HP_LVC3_OCP_V3_2_PRSNT2_N
P12V_OCP_V3_2_EN_R3
HP_LVC3_OCP_V3_2_PRSNT2
P12V_OCP_V3_2_EN_R
OCP_V3_2_P3V3_PLD_R_PWRGDOCP_V3_2_P3V3_PWRGD
RST_PERST_OCP_V3_2_BUF_N
FM_OCP_V3_2_AUX_PWR_EN SET TO HIGH BY DEFAULT
HP_LVC3_OCP_V3_2_PWRGD_R1
FM_OCP_V3_2_AUX_PWR_R_EN
OCP_V3_2_AUX_PWR_ENOCP_V3_2_AUX_PWR_EN_R2
OCP_V3_2_P3V3_R2_PWRGD
HP_LVC3_OCP_V3_2_P12V_PWRGD H P_LVC 3_OC P_V3_2_P12V_R _PW R GD
SMLF
IC
SMLF
IC
1/16W
CHIP
1%
1K
0402LF
0402LF5%
1/16W
0402LF
1/16W
5%
CHIP
0
10%
X7R
5%
1/16W
EMPTY
10K
0402LF
0402LF
33.2
CHIP
SMLF
SN74LVC1G07DBVR
IC
CHIP0402LF
33.2
74LVC1G32GW
SMLF
IC
10%
X7R
0402
25V
0.1UF
5%0
CHIP 1/16W
CHIP
1/16W
1%
1K
0402LF
74LVC1G08W5-7
IC
SMLF
0402LF
1/16W
CHIP
1K
1%
BSS138K
BSS138K
IC
1K
CHIP
0402LF
1/16W
CHIP
0 5%
1/16W
0402LF
33.2
CHIP0402LF
33.2
10%
25V
0402
0.1UF
X 7R
0402LF CHIP
33.2
CHIP
1%
0.1UF
0402
X7R
25V
10%
0 0402LF5%
EMPTY
CHIP
5%0
1%
IC
0.1UF
25V
X7R
10%
0402
100K
1/16W
CHIP
0402LF
V3_2_OCP3.0 HSC(3/3)
OCP_V3_2_P3V3_PLD_PWRGD 0
CHIP
1%
HP_LVC3_OCP_V3_2_PWRGD
OCP_V3_2_P3V3_R1_PWRGD
0402LF
SMLF
0402LF
0
E MP TY
0
E MP TY
IC RST_PERST_OCP_V3_2_R_N
0402LF
74LVC1G08W5-7
0402
X7R
10%
0.1UF
25V
RST_PERST_OCP_V3_2_BUF_R_N
SN74LVC1G07DBVR
OCP_V3_2_P3V3_PWRGD
1/16W
APX809-29SAG-7
HP_LVC3_OCP_V3_2_P12V_PWRGD
5%
10K
1/16W
OC P_V3_2_P3V3_R 3_PW R GD
X7R
HP_LVC3_OCP_V3_2_P12V_PWRGD_R2
CHIP
HP_LVC3_OCP_V3_2_PWRGD_R2
74LVC1G08W5-7
0402LF
CHIP 1/16W
0 5%
5%0
CHIP
5%0 0402LF
1/16W
P12V_OC P_V3_2_PLD _R _PW R GD
0402LF
1/16W
10K
E MP TYOC P_V3_2_P3V3_PW R GD
R1146
R1147
R1525
R1171
R1164
R1167
C1065
4
5
3
2
1
3
2
1
4
5
13
2
4
5
3
2
1
4
5
13
2
5
4
2
1
3
4
5
3
2
1
G
S D
U9051
U8002
U33
U35
R1177
U34
R1175
U37
U31
U32
R1174
R1173
R1178
DESIGN NOTE:
VCC
Y
GND
B
A
GND
RESET_L
VCC
NC
Y
GND
A
VCC
VCC
Y
GND
B
A
NC
Y
GND
A
VCC
GND
O
I1
VCC
I0
VCC
Y
GND
B
A
21
21
21
2
1 C9051
2
1
R8095
21R8097
2
1
2
1C8009
2
1
21
21
2
1
2
1
21
2
1 C1064
21
2 1
2 1
2
1
C1062
21
2
1
21
2
1
2
1
21
21
21
2
1
21
2
1
R1176
2
1
21
1
SHEETDATE
23
7 3 2 16 5 4
E
A
B
C
E
D
C
B
A
7 6 5 4
D
DEPARTMENT
SIZE
PROJECT DOCUMENT NUMBER REV
REVIEWER
DESIGNER
IN
IN
OUTIN
IN
OUT
IN
OUT
OUT
OUT
OUT
IN
IN
IN
OUT
IN
IN
R1524
R1523
R8096
R1170
R1168
C1063
R1172
R1169
R1165
R1149
R1166
C1061
R1163
C



20210922 MODIFY FOR GT
Thu Aug 24 14:09:12 2023<NAME_2>
<NAME_1>
MB FABCGTI V02
143 OF 365
P3V3_AUX
P3V3_AUX
P3V3_AUX
P3V3_AUX
P3V3_AUX
P3V3_AUX
P3V3_AUX
137140
131134
131134
143
137140
138
132
143
143
138
132
143
131134
131134
137140
137140
74LVC2G08DP
1/16W
OC P_V3_2_PR SN T23_R 1_N
10%
EMPTY
25V
0.1UF
0402LF
5%
0402LF
EMPTY
0402
EMPTY
10%
25V
0.1UF
OC P_SFF_PR SN T23_R 1_N
0402LF
74LVC2G08DP
0
0402LF
EMPTY
OC P_SFF_PR SN T01_R _N
SMLF
10%
OC P_V3_2_PR SN T01_R 1_N
X 7R
OC P_V3_2_PR SN T01_R _N
5%
EMPTY
OC P_V3_2_PR SN T23_R _N
1/16W
74LVC2G08DP
OC P_SFF_PR SN T_ALL_R _N
OC P_V3_2_PR SN T_ALL_R _N
OC P_V3_2_PR SN T1_R _N
74LVC2G08DP
25V
10%
OC P_SFF_PR SN T1_R _N
OC P_SFF_PR SN T0_R _N
5%
OC P_SFF_R BT_AR B_IN _MU X2
1/16W
0
OC P_V3_2_PR SN T0_R _N
NC7SB3157P6X
EMPTY
NC7SB3157P6X
EMPTY
EMPTY
NC7SB3157P6X
EMPTY
X 7R
10%
25V
0.1UF
25V
0402
X 7R
10%
0.1UF
X 7R
10%
25V
0.1UF
0402
25V
0402
X 7R
10%
0.1UF
25V
10%
CHIP
0 5%
1/16W
0402LF
CHIP
0
1/16W
5%
0402LF
CHIP
1/16W
5%
CHIP
0402LF
0
0402LF 1/16W
5%0
CHIP
0402LF
5%
CHIP
0
1/16W
OCP_V3_2_NOT_PRSNT_RBT_ARB_INO CP _V 3_2_P RS NT_A LL_R1_N
O CP _S FF_P RS NT_A LL_R3_N
OC P_SFF_R BT_AR B_IN _MU X1_R
OCP_V3_2_RBT_ARB_OUT
OCP_SFF_NOT_PRSNT_RBT_ARB_IN
OC P_SFF_R BT_AR B_IN
OC P_SFF_R BT_AR B_IN _MU X2 OC P_SFF_R BT_AR B_IN _MU X2_R
O CP _V 3_2_P RS NT_A LL_R3_N
OC P_SFF_R BT_AR B_IN _MU X1
O CP _S FF_P RS NT_A LL_R1_N
OCP_V3_2_RBT_ARB_IN
OC P_SFF_R BT_AR B_OU T
OCP3.0 NCSI
OC P_SFF_R BT_AR B_IN _MU X1
0402LF
25V
SMLF
SMLF
EMPTY
OC P_SFF_PR SN T2_R _N
OC P_SFF_PR SN T3_R _N
OC P_V3_2_PR SN T3_R _N
OC P_V3_2_PR SN T2_R _N
0402
NC7SB3157P6X
0.1UF
0402
0.1UF
EMPTY
EMPTY
5%
0
1/16W
0
0
EMPTY
0402
0.1UF
X 7R
X 7R
EMPTY74LVC2G08DP
OC P_SFF_PR SN T23_R _N
1/16W
5%
EMPTY
0402
25V
0.1UF
OC P_SFF_PR SN T01_R 1_N
0.1UF
25V
0402
0402
0402
EMPTY
74LVC2G08DP
SMLF
10%
EMPTY
10%
EMPTY
SMLF
R3307
R3306
R3308
21
21
R3305
R3304
R3303
C1878
C1877
C1879
C1880
5
6
2
1
34
5
6
2
1
34
5
6
2
1
34
5
6
2
1
34
3
6
5
7
2
1
3
6
5
7
2
1
3
6
5
7
2
1
S
B0
B1
VCC GND
A
S
B0
B1
VCC GND
A
S
B0
B1
VCC GND
A
S
B0
B1
VCC GND
A
84
8484
U245
U246
U244
U243
U242
U242
U240
U240
U241
U241
2Y
2B
2A
2Y
2B
2A
1Y
1B
1A
2Y
2B
2A
1Y
1B
1A
1Y
1B
1A
GND VCC
GND VCCGND VCC
2
1
2
1
2
1C8002
2
1C8001
21R8016
21R8015
R8014
R8013
21
21
21
21
21
21
2
1
2
1
2
1
2
1
2
1
2
1
2
1
1
SHEETDATE
23
7 3 2 16 5 4
E
A
B
C
E
D
C
B
A
7 6 5 4
D
DEPARTMENT
SIZE
PROJECT DOCUMENT NUMBER REV
REVIEWER
DESIGNER
IN
IN
IN
IN
IN
OUT
OUTIN
OUT
IN
IN
OUT IN
IN
IN
IN
C8004
C8003
C1876
C1874
C1875
C



TO SCM HDD ACTIVITY LED
20211201 PU TO P3V3_AUX
20211130 CHANGE TO P3V3_M2_0
20211201 PU TO P3V3_AUX
20211201 PU TO P3V3_AUX
20211201 PU TO P3V3_M2_0
20210904 MODIFY FOR GT
Thu Aug 24 14:09:13 2023
<NAME_1>
144 OF 365
01010101V02
<NAME_2>
MB FABCGTI
P3V3_M2_0
P3V3_AUX
P3V3_M2_0
P3V3_AUX
P3V3_AUX
P3V3_AUX
P3V3_AUX
P3V3_M2_0
P3V3_AUX
P3V3_AUX
P3V3_AUX
E MP TY
1K
1/16W
1/16W
M2_0_PEW AKE_R _N
M2_SSD0_CLKREQ_EN_N_BUF
RST_PERST_BUF_M2_0_R_N
1%
P3E_CPU1_P4_RX_DN<3:1>53
144
82144
53
67
67
155
144
55
14482
8183
144
53
67
148
55 144
144
144
144
67
148
144
53
80
85 150
EMPTY
SCONN75K_APCI0155-P004A
1/16W
NC_M2_0_NC11
NC_M2_0_NC8
PD_M2_0_DEVSLP
M2_SSD 0_C LKR EQ_EN _N
1%
P3E_CPU1_P4_RX_DP<3:1>
P3E_CPU1_P4_TX_C_DN<3:1>
P3E_CPU1_P4_TX_C_DP<3:1>
NC_M2_0_SUSCLK
M2_0_PEWAKE_N
CLK_100M_CPU1_CLK12_DP
M2_SSD0_CLKREQ_EN_N
RST_PERST_M2_0_N
CPU1 - M.2 - 0 CONN (EMPTY)
LED_M2_SSD_0_ACT_N
NC_M2_0_NC18
P3E_CPU1_P4_RX_DN<0>
P3E_CPU1_P4_TX_C_DN<0>
NC_M2_0_NC19
FM_M2_SSD_0_PEDET
NC_M2_0_NC2
NC_M2_0_NC10
NC_M2_0_NC17
NC_M2_0_NC16
NC_M2_0_NC15
NC_M2_0_NC14
SMB_M2_P1_1V8AUX_SDA
NC_M2_0_NC9
NC_M2_0_NC7
NC_M2_0_NC6
CLK_100M_CPU1_CLK12_DN
HDD_ACTIVITY_BUF
0402
1K
0402LF
1%
1/16W
CHIP
IC
C0402
10%
25V
0402
X7R
0.1UF
0402
0.1UF
X7R
25V
10%
25V
0.1UF
X7R
10%
0402
22UF
20%
6.3V
C0603
X6S
20%
C0603
X6S
6.3V
22UF
6.3V
22UF
X6S
C0603
PD_M2_0_DEVSLP
CHIP
1/16W
1%
1K
0402LF
1% CHIP
5%
0402LF 1/16W
0
10K
0402LF
CHIP
1/16W
CHIP
10K
1%
0402LF
X7R
0.1UF
1%
0402LF
5%
0402LF
EMPTY
4.7K
X6S
25V
SMLF
CHIP1%
CHIP
10%
1UF
0
5%
1/16W
CHIP5%0
1/16W
CHIP
1%
25V
10%
CHIP
4.7K
0
0402LF
0402LF
NC_Q 95_S 2
PU_BUFFER_HDD_ACTIVITY
RST_PERST_BUF_M2_0_R_N
IC
IC
SMLF
NC_Q 95_D2
PJT138K
NC_Q 95_G 2
33.2
0402LF
4.7K
1%
1/16W
CHIP
4.7K
1/16W
CHIP
RST_PERST_BUF_M2_0_N
10K
NC_M2_0_NC3
NC_M2_0_NC4
NC_M2_0_NC5
0402LF
PU_BUFFER_HDD_ACTIVITY
LED_HDD_ACTIVITY_N
P3E_CPU1_P4_TX_C_DP<0>
CHANGE CH4101KEE02 TO CH4101KEE01
SMB_M2_P1_1V8AUX_SCL
NC_M2_0_NC1
LED_M2_SSD_0_ACT_N
0402LF
SMLF
20%
P3E_CPU1_P4_RX_DP<0>
PCIE_M2_SSD0_PRSNT_N
LED_HDD_ACTIVITY_B_N
1/16W
HDD_ACTIVITY_BUF_N
SMLF
PJT138K
IC
SMLF
74LVC1G126SE-7
SN74LVC2G07DCKR
CHIP5%
R3301
G2
G1
S2 D2
D1S1
R1396
R155
R2113
R2121
KEY  M
5
4
1
2
2
52
43
61
2
3
2
3
3
2
2
1
3
1
1
1
4 3
53
1 6
Q95
R5377
U239
Q95
U259
J59
BOM NOTE:
REFCLKP
REFCLKN
PETP1
PETN1
PERP1
PERN1
PETP2
PETN2
PERP2
PERN2
PETP3
PETN3
PERP3
PERN3
GND10
GND9
GND8
GND7
GND6
GND5
GND4
GND3
GND2
GND1
NC4
NC5
NC6
NC7
NC8
NC9
NC11
NC12
NC13
NC14
NC15
NC16
NC17
NC10
NC3
NC2
NC1
G2
G1
GND14
GND13
GND12
PEDET
NC19
GND11
PETP0||SATA-A+
PETN0||SATA-A-
PERP0||SATA-B-
PERN0||SATA-B+
3.3V_9
3.3V_8
3.3V_7
SUSCLK
NC18PEWAKE#
CLKREQ#
PERST#
DEVSLP
3.3V_6
3.3V_5
3.3V_4
3.3V_3
DAS_DSS#||LED1#
3.3V_2
3.3V_1
OE
Y
A
VCCGND
2Y
1Y
2A
1A
GND VCC
2
1
2
1
2
1
2
1
2
1
2
1
2
1
21
2
1
2
1
2
1
2
1
2
1
21
21R153
2
1
R178
2
1
21
2
1
21
2
1
2
1
68
55
53
54
13
25
37
49
11
23
35
47
50
7
19
31 43
5
17
29 41
69
67
58
56
48
46
44
42
40
36
34
32
30
28
26
24
22
20
8
6
75
73
71
57
51
45
39
33
27
21
15
9
3
1
G2
G1
38
10
52
74
72
70
18
16
14
12
4
2
1
SHEETDATE
23
7 3 2 16 5 4
E
A
B
C
E
D
C
B
A
7 6 5 4
D
DEPARTMENT
SIZE
PROJECT DOCUMENT NUMBER REV
REVIEWER
DESIGNER
OUT
OUT
OUT
OUT
IN
IN
OUT
BI
IN
OUT
IN
IN
OUT
OUT
IN
IN
IN
IN
OUT
IN
IN
IN
OUT
OUT
OUT
IN
C1925C1924C1923
R1605
C9922C1921C1920
R3297
R3298
C1873
R3296
R3295
R3294
R138
C2007
C



RX[3:0] PN SWAP
20220407:TX[2:0] PN SWAP
20210904 MODIFY FOR GT
Thu Aug 24 14:09:22 2023<NAME_2>
<NAME_1>
MB FABCGTI V02
145 OF 365
P12V_E1S_0_R
P3V3_E1S_0
P12V_E1S_0_R
P3V3_E1S_0
P3V3_E1S_0
P3V3_AUX
P3V3_E1S_0
P3V3_AUX
P3V3_E1S_0
P 3V 3_E 1S _0
P3V3_AUX
145
145
80
83 80 82
148
148
26
26
148
145
67
67
28
85
80
28
8183
145
145
145
IO
R ST_SMB_E1S_0_N
FM_LED _AC TIVE_E1S_0_BU F
E1S_0_PER ST1_C LKR EQ_N
E1S_0_PR SN T_N
SMB_E1S_3V3AU X_ISO_SC L
SMB_E1S_3V3AU X_ISO_SD A
TP_C LK_100M_E1S_0_D N
TP_C LK_100M_E1S_0_D P
P 3E _CP U0_P 4_RX _DP <3:0>
P 3E _CP U0_P 4_RX _DN<3:0>
SCONN56_1-2327679-3
SMLF
1/16W
0402LF
CHIP
10K
1%
PLACE THE BULK CAPS CLOSE TO SLOT
IO_SLOT
SMB_PCIE_E1S_ISO_ENCHIP
1%
0402LF
5%
1/16W
E1S_0_PW R D IS
P3E_C PU 0_P4_TX_C _D P<3:0>
P3E_C PU 0_P4_TX_C _D N <3:0>
C LK_100M_C PU 0_C LK12_D N
R ST_PC IE_E1S_PER ST_N
FM_SMB_R ST_E1S_0_R _N
FM_LE D_A CTIV E _E 1S _0 CHIP0 FM_LE D_A CTIV E _E 1S _0_R_B UF CHIP0
0402LF
1/16W
4.7K
CHIP
5%
CHIP
4.7K
0402LF
1/16W
5%
C LK_100M_C PU 0_C LK12_D P
IO_SLOT
PU _E1S_0_D U ALPOR T_EN _N
R ST_PER ST_E1S_0_N
1/16W0402LF
FM_LE D_A CTIV E _E 1S _0_R
1/16W
SMLF
0402
0.1UF
X 7R
1%
0 5% CHIP
1%
1/16W
CHIP
0402LF
10K
CHIP0
0402
X 7R
0.1UF
25V
10%
5%0
1/16W
CHIP5%0
0402LF
0402LF
4.7K
CHIP
5%
20%
C0805
X6S
22UF
20%
X6S
C0805
16V
0402
25V
0.1UF
10%
X7R
10%
X7R
25V
0.1UF
0402
10%
X7R
0402
0.1UF
25V
10%
0402
X7R
25V
0.1UF
RST_SMB_E1S_N
E1S_0_PWRDIS
RST_SMB_BUF_E1S_0_N
SMB_PCIE_E1S_ISO_EN_R2
SMLF
IC
74LVC2G07DW-7
1K
CHIP
1/16W
0402LF
1%
IO_SLOT
10K
100
0402LF
E MP TY
1/16W
1%
IO_SLOT
IO_SLOT
CPU0 - E1S - 0 CONN
IC
DP/DN SWAP TX[0:1] RX[0]
CHIP
TP_E1S_0_MFG
TP_E1S_0_R FU
25V 74LV C1G 17G W
10%
FM_LE D_A CTIV E _E 1S _0_B UF
CHIP
1/16W
0402LF
10K
4.7K
5%
0402LF
1/16W
EMPTY
RST_SMB_E1S_0_N
16V
22UF
2
1
R1000
21
R1038
2
1
C508
4
5
13
2
U44
2
1
R999
21
R955
R3773
R1673 R10287
R2426
R2125
R3772
R2114
R3779
A9
A8
A7
B8
A15B15
A14B14
B12 A12
B27
B24
B21
B18
B26
B23
B20
B17
A11
B10
A27
A24
A21
A18
A26
A23
A20
A17
B6
B5
B4
B3
B2
B1
B11
B7
A10
B28
B25
B22
B19
B16
B13
A28
A25
A22
A19
A16
A13
A6
A5
A4
A3
A2
A1
G2 G1
B9
52
43
61
1
3
3
1
2
2
1
0
0
2
0
2
1
0
3
3
J90
R2317
R3771
U134
DESIGN NOTE:
CAD NOTE:
NC
Y
GND
A
VCC
G1G2
PER_p3
PER_n3
PER_p2
PER_n2
PER_p1
PER_n1
PER_p0
PER_n0
REFCLK_p1
REFCLK_n1
GND_A28
GND_A25
GND_A22
GND_A19
GND_A16
GND_A13
PRSNT0#
PERST1#_CLKREQ#
PERST0# LED#_ACTIVITY
SMBRST#
SMBDAT
SMBCLK
PET_p3
PET_n3
PET_p2
PET_n2
PET_p1
PET_n1
PET_p0
PET_n0
REFCLK_p0
REFCLK_n0
GND_B28
GND_B25
GND_B22
GND_B19
GND_B16
GND_B13
PWRDIS
P3V3_AUX
DUALPORTEN#
RFU
MFG
GND_A6
GND_A5
GND_A4
GND_A3
GND_A2
GND_A1
P12V_B6
P12V_B5
P12V_B4
P12V_B3
P12V_B2
P12V_B1
VCCGND
2Y
1Y
2A
1A
2
1
2
1
2
1 C1283
2
1 C1282
2
1
2
1
2
1 C1279
2
1 C1278
2
1 C1277
2
1 C1276
2
1
21
21
2
1
2
1
21
2
1
2
1
21
1
SHEETDATE
23
7 3 2 16 5 4
E
A
B
C
E
D
C
B
A
7 6 5 4
D
DEPARTMENT
SIZE
PROJECT DOCUMENT NUMBER REV
REVIEWER
DESIGNER
IN
OUT
OUT
IN
BI
IN
IN
OUT
OUT
OUT
OUT
OUT
IN
IN
IN
IN
IN
IN
OUT
IN
C1592
R10296
R3775
C



START UP TIME:3.94MS
VIMON(MAX)= 1.641V @ IOUT=2.79A
P3V3_E1S_0_R
OCP=MAX*1.3=2.71A
IMAX=2.083A
P12V_E1S_0
OCP=0.75A
IMAX=0.025A
DESIGN SPECIFICATION
VIMON(MAX)= 1.604V @ IOUT=0.75A
OVP: 3.89V
UVP: 2.63V
START UP TIME:8.21MS
OVP: 14.91V
UVP: 10.17V
Thu Aug 24 14:09:13 2023
GTI
<NAME_1>
<NAME_2>
V02
146 OF 365
MB FABC
P3V3_AUX
P12V_E1S_0
P3V3_E1S_0_R
P3V3_AUX
P12V_AUX
P12V_AUX
P3V3_AUX
P12V_AUX
258
147 81
81
83
147
8183147
258
147 81
E1S_P12V_MAM_TIC _BOM1
E1S_P12V_MAM_TIC _BOM1
CHIP
P12V_E1S_EN_0_R
0402LF
1/16W
E1S_P12V_MAM_TIC_BOM1
IC
0402LF
E1S_P12V_MAM_TIC_BOM1
160K
0
1/16W
1/16W
1%
0402LF
CHIP
10M
04021UF
P12V_E1S_VC C _0
MAX15090BEWI+T
SMLF
0402LF
1/16W
1%
P12V_E1S_U V_0
E1S_P12V_MAM_TIC_BOM1
EMPTY
0402LF
P12V_E1S_0_ISEN SE_MAM_MAM
0 5%
1%
2.67K
B340A-13-F
0.01UF
CHIP
0402LF1/16W
50V
X7R
10UF
16V
IC
100K
B340A-13-F
E1S_P3V3_BOM1
E1S_P3V3_BOM1
P3V3_E1S_EN_0_R
1/16W
0402LF
P3V3_E1S_0_EN_G
0
0402LF
CHIP
E1S_P3V3_BOM1
SMLF
4.7K
SMLF
PJT138K
E1S_P3V3_BOM1
IC
0.1UF
1%
E1S_P3V3_BOM1
P3V3_E1S_U V_0_R
E1S_P3V3_BOM1
PJT138K
E1S_P3V3_BOM1
1%
1/16W
CHIP
25V
P3V3_E1S_VC C _0
1UF
C0402
1/16W
CHIP
0402LF
0402LF
CHIP
25.5K
X 6S
E1S_P3V3_BOM1
1/16W
9.76K
0402LF
0402LF
50V
CHIP
EMPTY
25V
1%
P 3V 3_E 1S _P W RG D_0_R
0402LF
1%
CHIP
1%
0
5%
CHIP 1/16W
25V
1UF
C0402
0
CHIP
1/16W
1%
10K
5%
1%
0402LF
IC
SMF14A
X 6S
25V
C0402
0402LF
1%
CHIP
0402LF
5%
CHIP
0402LF
16V
10UF
X6S
IC
9.31K
1%
1/16W
CHIP
IC
0 5%
10K
X6S
16V
10UF
1%
CHIP
CCBUE1S_HSC
P12V_E1S_U V_0_R
E1S_0_P3V3_EN
E1S_0_P12V_EN
50V
C0805
10M
100K
1/16W
CHIP
1/16W
15K
7.15K
1%
CHIP
P3V3_E1S_R EG_0
0402LF
C0402
CHIP
1/16W
E1S_P3V3_BOM1E 1S _P 3V 3_B OM1
100K
1%
1/16W
CHIP
5%0
E1S_P3V3_BOM1
C0402
6800PFE1S_P3V3_BOM1
E 1S _P 3V 3_B OM1
P3V3_E1S_SEN SE_0
P3V3_E1S_FAU LT_0
P3V3_E1S_PW R GD _0
X7R
0402ICSMLF
10
1%
E1S_P3V3_BOM1
0402LF
2.49K
1/16W
CHIP
P3V3_E1S_C B_0
E1S_P3V3_BOM1
0402LF
E1S_P3V3_BOM1
1/16W
1UF
X 6S
25V
C0402
5%
P3V3_E1S_U V_0
P3V3_E1S_GATE_0
0402LF
E1S_P3V3_BOM1
1/16W
1%
0.01UF
E1S_P3V3_BOM1
CHIP
E1S_P3V3_BOM1
MAX15090BEWI+T
E1S_P3V3_BOM1
E1S_P3V3_BOM1
1/16W
P3V3_E1S_OV_0
1/16W
IC
0.1UF
25V
X6S
C0805 C0805
100K
0402LF
1/16W
E1S_P12V_MAM_TIC_BOM1
0402LF
CHIP
P12V_E1S_SEN SE_0
P12V_E1S_0_ISEN SE_MAM_TIC
E1S_P12V_MAM_TIC_BOM1
C0402
E MP TY
CHIP
E1S_P12V_MAM_TIC_BOM1
0402LF
H P_LVC 3_E1S_0_H SC _PW R GD
E1S_P12V_MAM_TIC_BOM1
1/16W
0402LF
1/16W
R3974/R3975 CO-LAYOUT
E1S_P12V_MAM_TIC _BOM1
CHIP
1/16W
E1S_P12V_MAM_TIC_BOM1
0 5%
1%
1/16W
3900P F
50V
CHIP
0402LF
E1S_P12V_MAM_TIC_BOM1
E1S_P12V_MAM_TIC_BOM1
C0402
P12V_E1S_FAU LT_0
P12V_E1S_PW R GD _0
P12V_E1S_GATE_0
1/16W
0402LF
E1S_P12V_MAM_TIC_BOM1
CHIP
15K
0402LF
E1S_P12V_MAM_TIC_BOM1
CHIP
1/16W
1%
P12V_E1S_OV_0
P12V_E1S_C B_0
P12V_E1S_R EG_0
25V
E1S_P12V_MAM_TIC_BOM1
1UF
CHIP
10
1%
E1S_P12V_MAM_TIC_BOM1
1/16W
0402LF
E1S_P12V_MAM_TIC_BOM1
1UF
X 6S
25V
C0402
E1S_P12V_MAM_TIC_BOM1
C0402
6.8K
CHIP
5%
1/16W
0402LF
E1S_P12V_MAM_TIC _BOM1
SMLF
PJT138K
PJT138K
IC
4.7K
5%
SMLF
E1S_P12V_MAM_TIC_BOM1
P12V_E1S_0_EN_G
E1S_P12V_MAM_TIC _BOM1
PC2215
PC2213
G2
G1
G2
G1
S2 D2
D1S1
CA
S2 D2
D1S1
PD114
R3978
PC2219
PC2209
PC2218
R3977
PC2216
PC2212
PR3961
R4064
R3959
R4072
PC2217
R3976
R3972
PR3970
PR3966
PR3968
PC2211
R3979
R3973
PR3971
PR3967
PC2210
PR3969
PR3960
PC2207
PR3962
R4074
PR3963
PC2208
PR3964
PR3965
R4063
A2
D2
D1 D7
D3
D6
D4
C6
C4
B6
B4
A4
A1
D5
C5
C3
B5
B3
A5
A3
C2
C1
B2
A6
C7
B7
A7B1
2
5
PC2280
A2
D2
D1 D7
D3
D6
D4
C6
C4
B6
B4
A4
A1
D5
C5
C3
B5
B3
A5
A3
C2
C1
B2
A6
C7
B7
A7B1
PC2220
5
2
1 6
4 3
CA
4 3
1 6
PU295
Q127
Q126
PD112
PU294
PD113
Q127
Q126
CAD NOTE:
PG
FAULT#
GND_C2
GND_C1
GND_B2
CDLY
GATE
OUT_D6
OUT_D4
OUT_C6
OUT_C4
OUT_B6
OUT_B4
OUT_A4
ISENSEOV
UV
REG
EN#
CB
IN_D5
IN_C5
IN_C3
IN_B5
IN_B3
IN_A5
IN_A3
VCC
PG
FAULT#
GND_C2
GND_C1
GND_B2
CDLY
GATE
OUT_D6
OUT_D4
OUT_C6
OUT_C4
OUT_B6
OUT_B4
OUT_A4
ISENSEOV
UV
REG
EN#
CB
IN_D5
IN_C5
IN_C3
IN_B5
IN_B3
IN_A5
IN_A3
VCC
CACA
21
2
1
2
1
2
1
2
1
2
1
2
1
21
2
1
2
1
2
1
2
1 PC2214
21
21
2
1
2
1
2
1
2
1
21
2
1
2
1
2
1
2
1
2
1
2
1
2
1
2
1
21
2
1
2
1
2
1
2
1
2
1
2
1
2
1
2
1
CA
2
1
2
1
CA
1
SHEETDATE
23
7 3 2 16 5 4
E
A
B
C
E
D
C
B
A
7 6 5 4
D
DEPARTMENT
SIZE
PROJECT DOCUMENT NUMBER REV
REVIEWER
DESIGNER
OUT
OUT
OUT
OUT
IN
IN
R3975
PR4528
R3974
PR4527
R3958
R4073
R6049
C



2ND SOURCE OF PU294
VTH>1.391V(HIGH)
START UP TIME:8.62MS
PR3950 DE-POP
MP5022C
MP5025A/MP5025C/
PR3952
PR3953
PU292 OPTIONAL BOM
MP5022A
DE-POP
2ND SOURCE OF PU295
PC2205 POP
VIMON(MAX)= 1.569V @ IOUT=2.8A
DE-POP
DE-POP
PUSH PULL OUTPUT
CURRENT LIMIT
=0.75A
START UP TIME:4.7MS
TDELAY: 6.29MS
TFAULT: 1.27MS
PR3957
POP
POP
DE-POP
POP
POPOCP=0.75A
DESIGN SPECIFICATION
OCP=MAX*1.3=2.71A
IMAX=2.083A
P3V3_E1S_0_R
IMAX=0.025A
P12V_E1S_0
ENABLE:
Thu Aug 24 14:09:13 2023<NAME_2>
MB FABC V02
147 OF 365
GTI
<NAME_1>
P12V_AUX
P3V3_AU X
P3V3_E1S_0_R
P3V3_AUX
P3V3_E1S_0_R
P3V3_E1S_0_R
P12V_E1S_0
P12V_AUX
P3V3_AUX
E1S_P12V_MPS_MAM_BOM2
H P_LVC 3_E1S_0_H SC _PW R GD
P12V_E1S_IMON _0
P12V_E1S_ISET_0
IC
SMLF
RS31312R
P12V_E1S_AVIN _PD _0
P12V_E1S_OV_FB_0
P12V_E1S_FLTB_0
P12V_E1S_EN _0_R 2
P12V_E1S_TIMER _0
P12V_E1S_SS_0
E1S_P12V_MPS_MAM_BOM2
0
1/16W
CHIP
1/16W
E1S_P12V_MPS_MAM_BOM2
E1S_P12V_MPS_MAM_BOM2
560P F
P12V_E1S_ISET_0_R
X 7R
50V
1%
CHIP
20K
1/16W
E1S_P12V_MPS_MAM_BOM2
CHIP
0.22UF
E1S_P12V_MPS_MAM_BOM2
E1S_P12V_MPS_MAM_BOM2
0402LF
E MP TY
1/16W
CHIP
0402LF
0402LF
1/16W
71.5K
0402LF
CHIP1% 1/16W
E1S_P12V_MPS_MAM_BOM2
1% E1S_P12V_MPS_MAM_BOM2
49.9
1%
120K
1/16W
0.1UF
E1S_P12V_MPS_MAM_BOM2
0402LF
10K
E1S_P3V3_BOM2
P3V3_E1S_EN _0_R 2
P3V3_E1S_MOD E_0
P3V3_E1S_ILIMIT_0
P3V3_E1S_D VD T_0
E1S_P3V3_BOM2
E1S_P3V3_BOM2
R3955/R3956 CO-LAYOUT
E1S_P3V3_BOM2
SMLF
0402LF5%E1S_0_P3V3_EN
E1S_P3V3_BOM2
E1S_P3V3_BOM2
1%
56K
CHIP
10K
E1S_P3V3_BOM2
1/16W
1/16W
CHIP
0402LF
P3V3_E1S_PWRGD_0_R1
E1S_P3V3_BOM2
0402LF
E1S_HSC_CO_LAYOUT
CHIP
E1S_P3V3_BOM2
0402
X7R
16V
0.068UF
100P F
E1S_P3V3_BOM2
0402
X 7R
50V
E1S_P3V3_BOM2
P3V3_E1S_GATE_0_PU 293
1%
CHIP
CHIP
2.8K
MP5016GQH-L-Z
X 6S
10UF
16V
0402
C0402
5%
IC
5%
16V
C0805
E MP TY
100
5%
0
X 7R
25V
1%
0402LF
SMLF
APX809-29SAG-7
IC
100K
1%
1/16W
5%
0
CHIP
5% 0402LF
25V
1UF
CCBU
P3V3_E1S_PWRGD_0_R
EMPTY
0402LF
X 6S
C0402
71.5K
1/16W
E1S_P3V3_BOM2
0402
X7R
25V
0.1UF
10%
E1S_P3V3_BOM2
1%
0402
10K
1%
X 7R
10%
0603LF
2.2UF
20%
16V
CHIP
10K
100NF
50V
X 7R
C0402
E1S_P12V_MPS_MAM_BOM2
0
C0603
0402LF
E1S_P12V_MPS_MAM_BOM2
P12V_E1S_AVIN _PD _0
1%
1/10W
CHIP
1/16W
1%
0402LF
25V
1UF
CHIP
1%
1/16W
E1S_0_P12V_EN
0.047UF
X 7R
25V
46.4K
X 7R
E1S_P12V_MPS_MAM_BOM2
C0402
0402LF
E1S_P12V_MPS_MAM_BOM2
0402LF
E1S_P12V_MPS_MAM_BOM2
146 83 81
81146
258
147
258
147
81
146 83 81
39PF
E1S_P3V3_BOM2
50V
NPO
0402
E1S_P12V_MPS_MAM_BOM2
0402LF
E1S_P12V_MPS_MAM_BOM2
146
E1S_P12V_MPS_MAM_BOM2
E1S_P12V_MPS_MAM_BOM2
E1S_P12V_MPS_MAM_BOM2
CHIP
P12V_E1S_0_ISEN SE_MPS_TIC5%
1/16W 0402LF
P12V_E1S_0_ISEN SE_MPS_MAM
0402LF
0
E1S_P12V_MPS_TIC _BOM3
EMPTY
1/16W
C0402
X 6S
PR3957PR3953
PR3952
PC2201
PR3945PC2197
PC2206
PC2205PR3954
PR3950
PR3951
PC2202
R3948
PR3949
PC2203
PC2198
PC2281
PR4541
PC2341
PR3944
PC2196
PC2200
PR3947
20
19
18
17
16
15
14
13
26
25
24
23
21_22
4
6
10
11
2
5
87
9
3
1
12
3
2
1
PU292
U8003
PC2204
PU293
CAD NOTE:
GND
SS
ISET
TIMER
ENTM
LOADEN
EN
VIN_26
VIN_25
VIN_24
VIN_23
IMON
FLTB
PG
OV
VOUT_13
AVIN
VOUT_14
VOUT_15
VOUT_16
VOUT_17
VOUT_18
VOUT_19
VIN_21_22
VOUT_20
GND
RESET_L
VCC
SOURCE
GATE
DV_DT
VCC
GND
ILIMIT
MODE
EN
21
2
1
2
1
2
1C8010
2
1
2
1
21
21
2
1
2
1
2
1
2
1
1_2 6_7
5
4
3
8
9
10
21
R3943
2
1
2
1
2
1
21R3946
1
SHEETDATE
23
7 3 2 16 5 4
E
A
B
C
E
D
C
B
A
7 6 5 4
D
DEPARTMENT
SIZE
PROJECT DOCUMENT NUMBER REV
REVIEWER
DESIGNER
OUT
OUT
OUT
OUT
OUT
IN
IN
IN
R8100
R8098
R8099
R3955
R3956
C



20210607 MODIFY FOR GT
TBC
20210616 MODIFY FOR GT
20211130 CHANGE R3529 TO 10K OHM
Thu Aug 24 14:09:13 2023<NAME_2>
<NAME_1>
MB FABCGTI V02
148 OF 365
P1V8_AUX P1V8_AUX
P3V3_E1S_0P3V3_AUX
P3V3_E1S_0
P3V3_AUX
144
270 81 255 271
251
251 144
251
251
145
145
145
S MB _M2_P 1_1V 8A UX _S CL
P W RG D_P 1V 8_A UX _RE MP TY
S MB _M2_P 1_1V 8A UX _S CL_R
1/16W0402LF
S MB _S E NS O R_M2_P 1_3V 3A UX _S CL
S MB _S E NS O R_M2_P 1_3V 3A UX _S DA
IC
X 7R
0402LF
S MB _M2_P 1_1V 8A UX _S DA _R
1/16W
S MB _M2_P 1_1V 8A UX _S DA
CHIP
1%
CHIP
1%
S MB _E 1S _3V 3A UX _IS O _S CL_R
S MB _P CIE _E 1S _IS O _E N_R
PCA9306DP1
CHIP
0402
S MB _P CIE _M2_0_E N
10%
25V
0.1UF 4.7K
5%
CHIP
1/16W
0402LF
CHIP
5%
4.7K
1/16W10%
0.1UF
25V
X 7R
0402
33.2
0402LF
1%
33.2 1%
200K
1%
0402LF
1/16W
200K
CHIP
1/16W0402LF
33.2 1%
33.2 CHIP
4.7K
5%
0402LF
1/16W
CHIP
4.7K
CHIP
0402LF
5%
1/16W
0402
25V
X 7R
10%
0.1UF
0402
25V
0.1UF
10%
X 7R
IC
SMLF
PCA9617ADP
E MP TY1%200K
1/16W0402LF
CPU - SATA / RAID KEY
1/16W
S MB _E 1S _3V 3A UX _IS O _S DA _RS MB _S E NS O R_E 1S _3V 3A UX _S DA
10K
0402LF
S MB _S E NS O R_E 1S _3V 3A UX _S CL
CHIP
1%
S MB _P CIE _E 1S _IS O _E N
S MB _E 1S _3V 3A UX _IS O _S DA
S MB _E 1S _3V 3A UX _IS O _S CL
SMLF
R3529 R3530 R3532
R3534
R3533
R1700
R2411
R2410
R1703R1702
8 1
6 3
7 2
45
7 2
5 4
6 3
1 8
U98
U279
GND
SCLB
SDAB SDAA
SCLA
VCCB VCCA
EN
GND EN
VREF2
SCL2
SDA2 SDA1
SCL1
VREF1
2
1
21R3531
2
1
2
1
2
1
2
1
21
21
2
1
21R2476
21
21
2
1
2
1
2
1
2
1
1
SHEETDATE
23
7 3 2 16 5 4
E
A
B
C
E
D
C
B
A
7 6 5 4
D
DEPARTMENT
SIZE
PROJECT DOCUMENT NUMBER REV
REVIEWER
DESIGNER
IN
IN
BI OUT
BI
IN
OUT
BI
IN
BI
C1997 C1998
C1305 C1323
C



Thu Aug 24 10:14:39 2023 149 OF 365
V02GTI MB FABC
<NAME_1>
<NAME_2>Blank
1
SHEETDATE
23
7 3 2 16 5 4
E
A
B
C
E
D
C
B
A
7 6 5 4
D
DEPARTMENT
SIZE
PROJECT DOCUMENT NUMBER REV
REVIEWER
DESIGNER
C



20210705 MODIFY FOR GT
SPI FROM MB TO SCM_BIOS FLASH
TBC
RERSERVE
SPI FROM SCM TO MB FPGA
Thu Aug 24 14:09:18 2023 150 OF 365
V02MB FABC
<NAME_2>
GTI
<NAME_1>
S CM_V DD_RTC
P12V_SCM P12V_SCM
P 3V 3_A UX
P3V3_AUX
0402LF
1/16W
80
172 151
80
80
249
249
SCM_ROT_CPU_RST_R_N
80
25V
X7R
80151
151 80
SGPIO_SCM_DI_<0>
151
80
151
151
80
80
151
151
241
80
243
80
80
151
151
151
0
0
FM_AC_PWR_BTN_R_N
80
151
153
77
77
77
77
77
29 81
180
180
180
29
29 81
29 81
29 81
15080
171
254
151
82
113
234
113
29 81
29 76 81
80
77
80
130
29
113
113
235
171
151
151
171
164 151
151 164
80
144 85
251
251
26
26
26
26
234
159
159
159
159
159
159
159
80
159
28
28
151249
151249
151
151
151160
151160
253
151248
151248
151249
151249
151248
151248
151
151
151241
151241
235
151160
151160
253
180
132 138
132 138
132 138
132 138
132
132 138
132 138
29 81
116
133
77
151
151
151
85
81
83
0
0
0
0
0
0
0
0
0
0
0
0
0
0
0
0
0
5% CHIP
CHIP
ESPI_CPU0_ALERT_N
SPI_CPU0_LVC3_SCM_CLK
SGPIO_SCM_CLK_R_<1>
SGPIO_SCM_DI_R_<1>
TP_SPI_2_PLD_CS_N
SGPIO_SCM_INTR_N
SGPIO_SCM_LD_<1>
SGPIO_SCM_DO_R_<1>
SGPIO_SCM_CLK_R_<0>
SGPIO_SCM_LD_R_<1>
TP_PVCCIO_PECI_BMC
SPI_CPU0_LVC3_SCM_D2
SPI_CPU0_LVC3_SCM_D1
SPI_CPU0_LVC3_SCM_D0
SPI_CPU0_LVC3_SCM_CS0_N
ESPI_CPU0_D3
U SB3_C PU 0_BMC _TX_BU F_C _D P
USB2_HUB_EXT_DN
USB2_HUB_EXT_DP
USB2_CPU0_P1_DN
RST_ESPI_CPU0_RSTOUT_N
FM_SOL_UART_CH_SEL_R
1%
1K
1/16W
CHIP
0402LF
5%
SMB_1_BMC _GPU _SC L
1/16W
FM_SCM_PRSNT1_N
P2E_MB_BMC_RX_BUF_DP<0>
CHIP
0
CHIP
P2E_MB_BMC_RX_BUF_DN<0>
CLK_ESPI_CPU0_CLK1
FPGA_IO3V3_RSVD_1
SPI_CPU0_LVC3_TPM_CS_N
RST_SRST_PLD_BMC_N
UART_CPU0_SCM_LVC3_UART1_RX
UART_BMC_BIC_BUF_RX
UART_2 BMC TO MB (BMC HOST)
UART_1 MB TO BMC (BMC SLAVE)
PRSNT0_N
UART_CPU0_SCM_LVC3_UART1_R1_TX
USB2_CPU0_P1_DP
TP_SPI_2_PLD_IO1
P2E_MB_BMC_TX_C_DP<0>
P2E_MB_BMC_TX_C_DN<0>
TP_PCIE_TXP[3]
USB2_HOST_BMC_B_DN
5%
1%
SCM CONN
SMB_1_PLD_3V3AUX_SDA_R3
SMB_PCIE2_3V3AUX_SDA_R0
JTAG_SCM_TCK
JTAG_SCM_TDO_R
JTAG_SCM_TDI_R
JTAG_SCM_TMS
SMB_PCIE2_3V3AUX_SCL_R0
UART_CPU0_SCM_LVC3_UART1_TX
UART_CPU0_SCM_LVC3_UART1_R_RX0
0402LF
CHIP
1/16W
5%
0
0
EMPTY
FM_SOL_UART_CH_SEL
1/16W
TP_PCIE_TXP[1]
TP_PCIE_TXN[1]
TP_BEEP_LED
LED_HDD_ACTIVITY_B_N
SMB_PCIE0_3V3AUX_SDA
SMB_PCIE0_3V3AUX_SCL
P2E_CPU0_P5_TX_C_DP
SMB_1_PLD_3V3AUX_SCL_R3
P2E_CPU0_P5_RX_DN
P2E_CPU0_P5_RX_DP
P2E_CPU0_P5_TX_C_DN
5%
0 5%
5%
0
1% CHIP33.2
1%
CHIP33.2 1%
5%0
1/16W0402LF
EMPTY
33.2 1% CHIP
CHIP1%
CHIP33.2
33.2
1%
33.2 CHIP
33.2 CHIP1%
CHIP1%
33.2 CHIP
1% CHIP
1% CHIP
33.2 1% CHIP 0
0402LF
CHIP
5%
IO
0
0
EMPTY
33.2
CHIP
CHIP1%
33.2 1%
33.2 1%
SMB_PMBUS_3V3AUX_SCL_R0
SMB_PMBUS_3V3AUX_SDA_R0
CHIP1%
33.2
SMB_PCIE3_3V3AUX_SDA_R
SMB_HOST_CLK_3V3AUX_SDA_R0
4.7K
5%
I3C_SCM_3_SCLI3C_SCM_3_R_SCL
I3C_SCM_2_SDAI3C_SCM_2_R_SDA
I3C_SCM_3_SDAI3C_SCM_3_R_SDA
I3C_SCM_1_SDA
I3C_SCM_1_SCLI3C_SCM_1_R_SCL
I3C_SCM_0_SDAI3C_SCM_0_R_SDA
SGPIO_SCM_CLK_<0>
SGPIO_SCM_DO_<0>
I3C_SCM_0_SCL
SGPIO_SCM_LD_<0>
I3C_SCM_1_R_SDA
I3C_SCM_2_R_SCL
33.2
33.2
VIRTUAL_RESEAT
I3C_SCM_0_R_SCL
SMB_OCP_SFF_3V3AUX_SCL_R0
SMB_OCP_SFF_3V3AUX_SDA_R0
SMB_CPU0_CPU1_APML_SCL_R
SMB_CPU0_CPU1_APML_SDA_R
SMB_VR_3V3AUX_SCL_R0
SMB_OCP_V3_2_3V3AUX_SCL_R0
SMB_OCP_V3_2_3V3AUX_SDA_R0
CLK_100M_CPU0_CLK01_DP
CLK_100M_CPU0_CLK01_DN
CHIP
33.2
CHIP
1/16W0402LF
33.2
SMB_2_BMC _GPU _SC L
SMB_2_BMC _GPU _SD A
SMB_1_PLD _3V3AU X_SC L
SMB_1_PLD _3V3AU X_SD A
S MB _CP U0_CP U1_A P ML_S CL
S MB _CP U0_CP U1_A P ML_S DA
SMB_VR _SEN SOR _3V3AU X_SC L
SMB_OC P_V3_2_3V3AU X_SD A
SMB_OC P_V3_2_3V3AU X_SC L
CHIP
SMB_VR_3V3AUX_SDA_R0
SMB_CPU0_CPU1_SEC_SCL_R
I3C_BMC_SWB_SCL
I3C_BMC_SWB_SDA
1%
1%
SMB_OC P_SFF_3V3AU X_SD A
SMB_OC P_SFF_3V3AU X_SC L
SMB_CPU0_CPU1_SEC_SDA_R
SMB_PMBU S_3V3AU X_SC L
SMB_PMBU S_3V3AU X_SD A 33.2 1% CHIP
SMB_FAN_3V3AUX_SCL
SMB_FAN_3V3AUX_SDA
0
SMB_PCIE3_3V3AUX_SCL_R
SMB_HOST_CLK_3V3AUX_SCL_R0
USB2_HOST_BMC_B_DP
TP_SPI_2_PLD_IO3
SMB_C PU 0_C PU 1_SEC _SD A
SMB_C PU 0_C PU 1_SEC _SC L
SMB_VR _SEN SOR _3V3AU X_SD A
I3C_SCM_2_SCL
U SB3_C PU 0_BMC _TX_BU F_C _D N
1%
RMII_OCP_BMC_CRSDV
RMII_BMC_OCP_TX_EN
RMII_BMC_OCP_TXD_0
RMII_BMC_OCP_TXD_1
RMII_BMC_OCP_RX_ER
RMII_OCP_BMC_RXD_0
RMII_OCP_BMC_RXD_1
TP_PECI_BMC
SGPIO_SCM_DO_R_<0>
ESPI_CPU0_D0
UART_BMC_BIC_TX
SCONN168_ME1016810202011
0 CHIP
FM_LPC_ESPI_SEL
CLK_50M_RMII_BMC_OCP
SPI_CPU0_LVC3_SCM_D3
SMLF
5%
CHIP
TP_PCIE_RXP[1]
TP_PCIE_RXN[1]
5% CHIP
SMB_1_BMC _GPU _SD A
SCM_IRQ_N
33.2S MB _HO S T_CLK _3V 3A UX _S DA
4.7K
0 5% CHIP FM_UARTSW_MSB_R
E MP TY
PWRGD_PS_PWROK_R
TP_STBY_EN
CHIP5%0SC M_SYS_PW R BTN _N0402LF
SGPIO_SCM_DI_R_<0>
SGPIO_SCM_LD_R_<0>
TP_SPI_2_PLD_IO2
TP_SPI_2_PLD_IO0
SGPIO_SCM_CLK_<1>
0.1UF
10%
0402
SGPIO_SCM_RESET_N
SGPIO_SCM_DI_<1>
SGPIO_SCM_DO_<1>
FW_RECOVERY
0
JTAG_SCM_DBREQ_N
FM_UARTSW_LSB_N
CHIP
80
CHIP
PU_JTAG_DBP_BMC_PRDY_N
FM_UARTSW_MSB_N
SCM_ROT_CPU_RST_N
SCM_HDT_DBREQ_N
FM_RST_PERST_SCM_N
USB3_CPU0_BMC_RX_DN
180
152
FM_UARTSW_LSB_R
IRQ0_A56
SCM_SYS_PWROK_R1
SCM_SYS_PWRBTN_R_N
RST_MB_STBY_R_N
USB3_CPU0_BMC_RX_DP
180
150
CLK_100M_BMC_RC_DN
CLK_100M_BMC_RC_DP
TP_SPI_2_PLD_CLK
FM_AC_PWR_BTN_N
SGPIO_SCM_INTR_R1_N
SGPIO_SCM_RESET_R_N
ESPI_CPU0_CS1_N
ESPI_CPU0_D1
ESPI_CPU0_D2
33.2
S MB _HO S T_CLK _3V 3A UX _S CL
FW_RECOVERY_R
PWRGD_PS_PWROK
RST_MB_STBY_N
80
84
SCM_ROT_CPU_RST_R_N
1/16W
EMPTY
0402LF
TP_CHASI
CHIP
5%
0
R8101
2 1 R6008
R6009
R6010
R6011
2 1 R6012
2 1R6000
R6026
R6013
R6015
R6014
2 1R6001
2 1R6002
2 1R6003
2 1R6004
2 1R6007
2 1R6005
2 1R6006
R6025
C6000
R6071
R2423
R2424
R4506
R4507
R6065
R6064
R6028
R3778
R2420
R2419
R3238
R3239
R2422
R2415
R2417
R2418
R2416
R1801
R2421
R2425
R3858
R2413
R2414
R3254
R1816
R4087
R6033
R1815
R6032
R3776
21R1798
R3777
OA3
A69
A68
A9
A8
A7
OA6
OB7
B69
B68
OA12 OB12
A15 B15
OA11 OB11
A14 B14
OA8
OA9
OA7
OB8
OB9
OB14OA14
OA5
OA4
A70 B70
A12
A42 B42
A10
B66
B63
B60
B57
B54
B51
B48
B45
B40
B37
B34
B31
B27
B24
B21
B18
B65
B62
B59
B56
B53
B50
B47
B44
B39
B36
B33
B30
B26
B23
B20
B17
OA2
OA1
A11
B10
A66
A63
A60
A57
A54
A51
A48
A45
A40
A37
A34
A31
A27
A24
A21
A18
A65
A62
A59
A56
A53
A50
A47
A44
A39
A36
A33
A30
A26
A23
A20
A17
OB1
OB2
OB3
OB13
OB10
OA13
OA10
B67
B64
B61
B58
B55
B52
B49
B46
B43
B41
B38
B35
B32
B29
B28
B25
B22
B19
B16
B13
A67
A64
A61
A58
A55
A52
A49
A46
A43
A41
A38
A35
A32
A29
A28
A25
A22
A19
A16
A13
A6
A5
A4
A3
A2
A1
G5
G4
G3
G2
G1
OB5
OB4
OB6
B9
B8
B7
B12
B6
B5
B4
B3
B2
B1
B11
R321
J41
DESIGN NOTE:
KEY
KEY
KEY
G5
G4
G3
G2
G1
PRSNTB3#
RFU1_NC_B69
RFU1_NC_B68
GND_B67
PETp15
PETn15
GND_B64
PETp14
PETn14
GND_B61
PETp13
PETn13
GND_B58
PETp12
PWRBRK0#
USB_DATp
USB_DATn
GND_A67
PERp15
PERn15
GND_A64
PERp14
PERn14
GND_A61
PERp13
PERn13
GND_A58
PERp12
PERn12
GND_A55
PERp11
PERn11
GND_A52
PERp10
PERn10
GND_A49
PERp9
PERn9
GND_A46
PERp8
PERn8
GND_A43
PRSNTB1#
GND_A41
PERp7
PERn7
GND_A38
PERp6
PERn6
GND_A35
PERp5
PERn5
GND_A32
PERp4
PERn4
GND_A29
GND_A28
PERp3
PERn3
GND_A25
PERp2
PERn2
GND_A22
PERp1
PERn1
GND_A19
PERp0
PERn0
GND_A16
REFCLKp1
REFCLKn1
GND_A13
PRSNTB2#
PERST1#
PRSNTA#
SMRST#
SMDAT
SMCLK
GND_A6
GND_A5
GND_A4
GND_A3
GND_A2
GND_A1
RBT_CLK_IN
GND_OA13
REFCLKp3
REFCLKn3
GND_OA10
RBT_TXD0
RBT_TXD1
RBT_TX_EN
SLOT_ID1
RBT_ARB_OUT
RBT_ARB_IN
WAKE#
PERST3#
PERST2#
PETn12
GND_B55
PETp11
PETn11
GND_B52
PETp10
PETn10
GND_B49
PETp9
PETn9
GND_B46
PETp8
PETn8
GND_B43
PRSNTB0#
GND_B41
PETp7
PETn7
GND_B38
PETp6
PETn6
GND_B35
PETp5
PETn5
GND_B32
PETp4
PETn4
GND_B29
GND_B28
PETp3
PETn3
GND_B25
PETp2
PETn2
GND_B22
PETp1
PETn1
GND_B19
PETp0
PETn0
GND_B16
REFCLKp0
REFCLKn0
GND_B13
AUX_PWR_EN
+3.3V_EDGE
PERST0#
BIF2#
BIF1#
BIF0#
+12V_EDGE_B6
+12V_EDGE_B5
+12V_EDGE_B4
+12V_EDGE_B3
+12V_EDGE_B2
+12V_EDGE_B1
RBT_CRS_DV
GND_OB13
REFCLKp2
REFCLKn2
GND_OB10
RBT_RXD0
RBT_RXD1
SLOT_ID0
CLK
DATA_OUT
DATA_IN
LD#
MAIN_PWR_EN
NIC_PWR_GOOD
2
1
2
1
2 1
2
1
21
21
21
21
21
21
2
1
21
2 1
2 1
2 1
21
21
21
21
21
21
2 121
21
21
2
1
2 1
2 1
2 1
21
21
21
21R4508
21R4509
21
21
21
2 1
21
21
21
21
21
21
21
2
1
2
1
1
SHEETDATE
23
7 3 2 16 5 4
E
A
B
C
E
D
C
B
A
7 6 5 4
D
DEPARTMENT
SIZE
PROJECT DOCUMENT NUMBER REV
REVIEWER
DESIGNER
BI
BI
BI
BI
IN
OUT
BI
BI
IN
BI
BI
BI
BI
BI
OUT
BI
OUT
IN
BI
OUT
IN
OUT
IN
BI
BI
BI
BI
IN
BI
BI
IN
IN
OUT
OUT
OUT
OUT
IN
IN
IN
IN
IN
OUT
IN
OUT
OUT
OUT
IN
OUT
OUT
OUT
OUT
OUT
OUT
OUT
OUT
OUT
OUT
IN
IN
OUT
OUT
BI
BI
BI
IN
OUT
OUT
IN
OUT
IN
IN
IN
IN
BI
BI
BI
BI
IN
IN
IN
IN
IN
IN
IN
OUT
OUT
OUT
IN
OUT
OUT
IN
OUT
IN
IN
OUT
BI
OUT
OUT
OUT
IN
OUT
BI
OUT
OUT
OUT
OUT
OUT
BI
BI
OUT
IN
IN
IN
IN
IN
OUT
R4809
R6034
R6035
C



20220113 CHANGE NET NAME
HSC
DEFAULT: POP R6067 & R6069, DE-POP R6066 & R6068
<NAME_2>
V02
151 OF 365
GTI MB FABC
<NAME_1>
Thu Aug 24 14:09:18 2023
S CM_V DD_RTC
P 3V _B A T_R
P3V3_AUX
P 3V 3_A UXP 5V _A UX
P 3V 3_A UX
P 3V 3_A UX
P V DD18_S 5_P 0
5%
0
0402LF CHIP 1/16W 151
150RST_MB_STBY_N1K 80
SCM SMBUS BUS CCBU
SGPIO_SCM_DO_<0>E MP TY
28 151
185
185
234
234
183
183
253 210
253 210
150
193
193
150151
150151
182
182
263
263
28 151
171
150160
150160
150249
150249
150160
217
224
217
224
200
184
184
80
268 269
268 269
80
150248
150249
150249
151150
150
150 80
258
171
200
150151
150151
150
81
81
80 150
15080
150 172
150 80
80 150
150 80
80
80
150248
164150
150 80
80 150
150 80
150 80
150249
150248
150164
150248
150151
150151
150249
258
365
365
28 151
80
80
150151
150151
151150
150151
150241
150241
150160
207
363
363
207
28 151
CHIP
CHIP 2.2K
2.2K S MB _CP U_5_S CL
CHIP 33 SMB_MUX_RT_ROM_R1_SDASMB_H OST_C LK_3V3AU X_SD A_R 1
SMB_MUX_RT_ROM_R1_SCLCHIP
0402LF
SMB_HOST_CLK_GEN2_3V3AUX_SDA
SMB_HOST_CLK_GEN2_3V3AUX_SCL
33SMB_H OST_C LK_3V3AU X_SC L_R 1
1/16W
1% CHIP33.2
SMB_9ZXL045_P1_SC L33 CHIP
SMB_9ZXL045_P1_SD A
SMB_VR_3V3AUX_SCL S MB _V R_3V 3S TB Y _S CL
SMB_VR_3V3AUX_SDA 33 S MB _V R_3V 3S TB Y _S DA
E MP TY JTAG_SCM_TDO_R
33
33
SMB_SCM_2_R3_SDA
33
33
SMB_SCM_2_R3_SCL
33.2 1% CHIP
CHIP
CHIP
33.2
0402LF
SMB_HOST_CLK_3V3AUX_SCL
CHIP
1/16W
SMB_HOST_CLK_3V3AUX_SDA
SMB_9ZXL045_P0_SC L
SMB_9ZXL045_P0_SD A
33 CHIP
33 CHIP
33 CHIP
1%
CHIP1%33.2
0402LF
CHIP
1/16W
SMB_SML1_PMBUS_HSC_SDA
SMB_SML1_PMBUS_HSC_SCL
S MB _CP U_5_S CL
JTAG_SCM_TDO
CO-LAY R6068 & R6069
CHIP
SMB_CPU0_CPU1_SEC_SCL
SMB_CPU0_CPU1_APML_SDA
I3C_BMC_SWB_SDA
I3C_BMC_SWB_SCL
SMB_CPU0_CPU1_APML_SCL
S MB _S CM_2_R1_S CL
S MB _S CM_2_R2_S DA
33 S MB _S CM_2_R1_S DA
S MB _S CM_2_R2_S CL
S MB _S CM_2_R5_S DA
33
33
33
33
SMB_MU X_R T_R 1_SD A
SMB_MU X_R T_R 1_SC L
SMB_1_PLD_3V3AUX_SDA_R1
SMB_SML1_PMBU S_H SC _R 1_SC L
SMB_SML1_PMBU S_H SC _R 1_SD A
SMB_1_PLD_3V3AUX_SCL_R1
0 CHIP
CHIP0
CHIP
CHIP
0402LF
1%33.2
0402LF
CHIP
1% CHIP
CHIP33.2 1%
33.2
SMB_OCP_SFF_3V3AUX_SCL
SMB_1_BMC_GPU_SDA
SMB_2_BMC_GPU_SDA
1/16W
0
0
SMB_1_PLD_3V3AUX_SDA
SMB_1_PLD_3V3AUX_SCL
EMPTY1%
1/16W0402LF
0402LF
EMPTY
2.2K 5% E MP TY
1/16W
2.2K 5% E MP TY
0402LF
1/16W
2K EMPTY1%
0402LF
0402LF
EMPTY1%2K
1/16W
2K
1/16W
EMPTY1%
1%2K EMPTY
2K 1%
2K EMPTY1%
EMPTY1%
1/16W0402LF
2K
2K
0402LF
SMB_SCM_2_R4_SDA
JTAG_SCM_TDI
33.2
33 S MB _S CM_2_R5_S CL
33.2SMB_PMBUS_3V3AUX_SCL
SMB_PMBUS_3V3AUX_SDA
1/16W
CHIP
5%
10K
0402LF
1/16W
E MP TY
5%
10K
0402LF
5%
E MP TY
1/16W
0402LF
10K
5%
10K
1/16W
0402LF
E MP TY
10K
5%
1/16W
E MP TY
0402LF
10K
5%
1/16W
E MP TY
0402LF
0
JTAG_SCM_TDI_R0 E MP TY
0 CHIP
0
S MB _CP U_5_R1_S DA
S MB _CP U_5_R1_S CL
SGPIO_SCM_INTR_N
E MP TY
4.7K
SGPIO_SCM_RESET_N
E MP TY
4.7K
JTAG_SCM_DBREQ_N4.7K
E MP TY
2K
E MP TY SGPIO_SCM_LD_<1>
SGPIO_SCM_DI_<1>
SGPIO_SCM_CLK_<1>
S CM_S P A RE _0
S CM_S P A RE _1
50V
220P F 220P F
5%
50V
E MP TY
2K
2K
2K
2K
2K
2K
SMB_OC P_V3_2_3V3AU X_SD A
0402LF 1/16W
2.2K
UA RT_CP U0_S CM_LV C3_UA RT1_TX
SGPIO_SCM_DO_<1>
SGPIO_SCM_DI_<0>
SGPIO_SCM_LD_<0>
SGPIO_SCM_CLK_<0>
SMB_2_BMC_GPU_SCL
SMB_OC P_V3_2_3V3AU X_SC L
UA RT_CP U0_S CM_LV C3_UA RT1_R_RX
SMB_OCP_SFF_3V3AUX_SDA
SMB_HOST_CLK_3V3AUX_SDA
SMB_HOST_CLK_3V3AUX_SCL
UA RT_V CC_J8
SMB_1_BMC_GPU_SCL
E MP TY
E MP TY
2K
E MP TY
C0402
1%
1%
C0402
5%
2.2K E MP TY5%
5% E MP TY
0402LF 1/16W
5%2.2K E MP TY
5%2.2K E MP TY
0402LF 1/16W
5%2.2K E MP TY
2.2K 5% E MP TY
0402LF 1/16W
2.2K 5% E MP TY
2.2K 5% E MP TY
5%2.2K E MP TY
0402LF 1/16W
2.2K 5% E MP TY
2.2K 5% E MP TY
1/16W
CO NN4_HFK 1040-L0P 1L-7H
IO
THLF
E MP TY5%2.2K
1%
0402LF 1/16W
33
33
SMB_SCM_2_R4_SCL
33.2
33.2
33.2 1%
1/16W
0
0
CO-LAY R6066 & R6067
P0V9_R ETIMER _C PU 1_PMSC L
P0V9_R ETIMER _C PU 1_PMSD A
S MB _CP U_5_S DA
1% SMB_2_PLD_3V3AUX_SCL_R1
SMB_2_PLD_3V3AUX_SDA_R1
SMB_PMBUS_3V3AUX_SDA
SMB_PMBUS_3V3AUX_SCL
SMB_1_PLD_3V3AUX_SDA
SMB_1_PLD_3V3AUX_SCL
SMB_FAN_3V3AUX_SCL
SMB_FAN_3V3AUX_SDA
SMB_CPU0_CPU1_SEC_SDA
33
33
S MB _S CM_2_R6_S CL
P0V9_R ETIMER _C PU 0_PMSC L
P0V9_R ETIMER _C PU 0_PMSD A33
S MB _S CM_2_R6_S DA
S MB _CP U_5_S DA
R6858
R6859
R351
R352
R349
R350
R6070
2 1R6067
2 1R6069
2 1R6068
2 1R6066
2
1
R891
2
1
R889
R130
2
1 C62
2 1R1453
21R1495
21R1496
21R6018
21R6019
21R6020
21R6022
21R6021
21R6023
21R6024
21R632
21R633
21R1321
21R1494
4
3
2
1
J8
2
1
R890
2
1
R888
2
1
R131
2
1 C63
2 1R1447
21R6027
R1546
21R6016
21R6017
21
R6783
R6782
R6857
R6856
R309
R308
R1517
R1516
R6865
R6864
R6863
R6862
R6785
R6784
21R1498
21R6077
21R6076
21R1497
R347
R348
R4150
R4149
R4151
R1319
R3062
R1384
R1385
R1386
R329
R6037
R6036
R330
R331
R332
R1460
R4152
CAD NOTE:
CAD NOTE:
1
2
3
4
21R364
2 1
2 1
21
21
21
21
21
21
21
21
21
21
21
21
2 1
2 1
21
21
21
21
21
21
21
21R3241
21R3242
21R2996
21R2995
21
21
21
21R3341
21R3340
21
21
21
21
21
21
21
21
21
21
21
21
21R2212
21R2213
21R2999
21R3004
21R3226 21R3227
21R3240
21R3243
2121
1
SHEETDATE
23
7 3 2 16 5 4
E
A
B
C
E
D
C
B
A
7 6 5 4
D
DEPARTMENT
SIZE
PROJECT DOCUMENT NUMBER REV
REVIEWER
DESIGNER
OUT
OUT
OUT
IN
BI
OUT
OUT
IN
BI
BI
IN
IN
OUT
OUT
OUT
OUT
OUT
OUT
OUT
OUT
BI
BI
IN
OUT
BI
BI
IN
BI
OUT
OUT
OUT
BI
OUT
BI
BI
OUT
OUT
OUT
IN
OUT
OUT
OUT
OUT
OUT
OUT
OUT
BI
BI
OUT
BI
OUT
BI
OUT
OUT
BI
BI
OUT
BI
OUT
OUT
BI
OUT
BI
OUT
BI
OUT
BI
OUT
OUT
BI
OUT
OUT
IN
OUT
IN
OUT
BI
BI
BI
OUT
BI
BI
OUT
BI
OUT
BI
OUT
BI
OUT
OUT
OUT
OUT
C



TDELAY: 6.29MS
TFAULT: 1.27MS
20211116 MODIFY FOR GTP12V_SCM_R
OCP=MAX*1.3=5.2A
DESIGN SPECIFICATION
IMAX=4A
MP5025A/
POP
MP5022A
MP5025C/
MP5022C
POP
PR4006
START UP TIME:8.21MS
ENABLE:
OVP: 14.91V
UVP: 10.17V
VIMON(MAX)= 1.610V @ IOUT=5.35A
START UP TIME:8.62MS
DE-POP
POPPR4009
DE-POP
DE-POP
VIMON(MAX)= 1.563V @ IOUT=5.34A
DE-POP
DE-POP
VTH>1.391V(HIGH)
POP
POP
PU299 OPTIONAL BOM
PR4010
PR4014
PC2239
2ND SOURCE OF PU300
Thu Aug 24 14:09:14 2023<NAME_2>
<NAME_1>
MB FABCGTI V02
152 OF 365
P12V_AUX
P3V3_AU X
P12V_AUX
P12V_AUX
P12V_SCM_R
P12V_SCM_R
P12V_AUX
P3V3_AUX
P3V3_AUX
P3V3_AUX
P3V3_AUX
SCM_P12V_MPS_BOM2
P12V_SC M_IMON
IC
RS31312R
SMLF
P12V_SC M_AVIN _PD
P12V_SC M_OV_FB
HP_LVC3_SCM_HSC_PWRGD_R
P12V_SC M_FLTB_N
P12V_SC M_EN _R 2
P12V_SC M_TIMER
P12V_SC M_ISET
P12V_SC M_SS
1/16W
P12V_SC M_C B
SCM_P12V_MAM_BOM1
C0402
X 6S
1UF
SC M_P12V_MPS_BOM2
CHIP
SC M_P12V_MPS_BOM2
152
152 81
15082
152 257
152
80
15281
152257
0.22UF
SCM_P12V_MPS_BOM2
SC M_P12V_MPS_BOM2
C0603
SCM_P12V_MPS_BOM2
0
100NF
SCM_P12V_MPS_BOM2
CHIP
SCM_P12V_MPS_BOM2
P12V_SC M_AVIN _PD
5%
30.1K
SCM_P12V_MPS_BOM2
1/16W
10K
2.2UF
16V1/16W
0402LF
SCM_P12V_MPS_BOM2
1%
CHIP
120K
X 7R
20%
SC M_P12V_MPS_BOM2
0402
1%
0.1UF
71.5K
1%
1/16W
CHIP
E MP TY
0402LF
SC M_P12V_MPS_BOM2
5%
1/16W
H P_LVC 3_SC M_H SC _PW R GD
0.047UF
1/16W
C0402
0402LF
SCM_P12V_MPS_BOM2
P12V_SCM_ISET_R
0402LF
1%
X 7R
50V
560P F
0402LF
P12V_SC M_EN
SCM_P12V_MAM_BOM1
FM_SCM_PRSNT1_R_N
1/16W
0402LF
SMLF
2N7002K
SC M_P12V_MAM_BOM1
0402LF
1/16W
PJT138K
SMLF
SC M_P12V_MAM_BOM1
0402LF
0
P12V_SC M_U V_R
1/16W
SCM_P12V_MAM_BOM1
CHIP
1/16W
SCM_P12V_MAM_BOM10
IC
E MP TY
1%
10M
SCM_P12V_MAM_BOM1
1/16W
CHIP
P12V_SC M_GATE
1/16W
1/16W
SC M_P12V_MAM_BOM1
CHIP
SCM_P12V_MAM_BOM1
SCM_P12V_MAM_BOM1
1%
C0402
MAX15090BEWI+T
SMLF
SCM_P12V_MAM_BOM1
0402LF
17.8K
P12V_SC M_OV P12V_SC M_SEN SE
SCM_P12V_MAM_BOM1
C0402 0402LF
1/16W
1%
100K
C0805
C0402
0.01UF
CHIP
0402LF
3900PF
SCM_P12V_MAM_BOM1
5%
0402LF
B340A-13-F
X7R
10UF
0402 C0805
X6S
0.1UF
IC
FM_SCM_PRSNT1_N
P12V_SCM_FAULT_R_N
VIRTUAL_RESEAT_FPGA_N
P12V_SCM
0402LF1/16W
IC
0
CHIP
22UF
16V16V
X6S
25V
CHIP
1/16W
CHIP
1%
1.33K
6.8K
1%
CHIP
1%
0402LF
CHIP
C0402
X 7R
10%
25V
CHIP
50V
C0402
1%
0402LF
E MP TY
1%
25V
CHIP
X 7R
25V
25V
CHIP0402LF
100 1%
1%
CHIP
IC
ICCHIP
0402LF
CHIP
1%
1/16W
1K
1%
CHIP
1/16W
CHIP 1/16W
5%
CHIP
1/16W
50V
0
CHIP
0402LF
H P_LVC 3_SC M_H SC _PW R GD
P12V_SCM_FAULT_R_N
0
1/16W
1%
100K
SCM_P12V_MAM_BOM1
50V
15K
1%
101UF
C0402
P12V_SC M_VC C
SCM_P12V_MAM_BOM1
SCM_P12V_MAM_BOM1
1UF
C0402
25V
SMLF
X 6S
160K
1%
CHIP
0402LF
1UF
X 6S
SCM_P12V_MAM_BOM1
CHIP
SC M_P12V_MAM_BOM1
0402LF
0402LF5%
1/16W
10K
IC
SMF14A
CHIP
1/16W
P12V_SC M_U V
P12V_SC M_PW R GD
P12V_SC M_FAU LT_N
P12V_SC M_R EG
25V
SMLF
P12V_SCM_EN_G
PJT138K
SC M_P12V_MAM_BOM1
5%0
10K
1/16W
0402LF
P12V_SCM_EN_R
1/16W
SC M_P12V_MAM_BOM1
0
X 7R
16V
0402
5%
SCM_P12V_MPS_BOM2
20K
SCM_P12V_MPS_BOM2
CHIP
1/16W
1%
24.3K
0402LF
0402LF
5%
0402LFSC M_P12V_MAM_BOM1
SC M_P12V_MPS_BOM2
10K
1/16W
CHIP
1%
0402LF
SC M_P12V_MPS_BOM2
0402LF
SCM_P12V_MPS_BOM2
0402LF
49.9
SCM_P12V_MPS_BOM2
1/10W
0603LF
CHIP
0402LF
1%10K
SCM_P12V_MPS_BOM2
SCM_P12V_MPS_BOM2
0402LF
1%
1/16W
X 7R
100
PR4014
21PR4012
PC2237
PR4010
G
G2
G1
S D
CA
S2 D2
D1S1
PD115
PR4009
R8031
R8030
R8012
PC2240
R4013PR4526
PR4003
PR4001
PR4002
PC2241
PR4011
R3836
PR4006
PR4005PC2340
PC2238
R4015
PR4008
PC2234
PC2233
PR4000
PR4004
PC2239
PC2235
PR4007
PC2231
PC2232
PC2230
R4071
R4062
PR4540PR3999
PC2229
R1856
20
19
18
17
16
15
14
13
26
25
24
23
21_22
4
6
10
11
2
5
87
9
3
1
12
PC2242
A2
D2
D1 D7
D3
D6
D4
C6
C4
B6
B4
A4
A1
D5
C5
C3
B5
B3
A5
A3
C2
C1
B2
A6
C7
B7
A7B15
2
G
4 3
1 6
S D
PU299
PU300
Q125
Q125
Q39
PD116
GND
SS
ISET
TIMER
ENTM
LOADEN
EN
VIN_26
VIN_25
VIN_24
VIN_23
IMON
FLTB
PG
OV
VOUT_13
AVIN
VOUT_14
VOUT_15
VOUT_16
VOUT_17
VOUT_18
VOUT_19
VIN_21_22
VOUT_20
S
G
D
PG
FAULT#
GND_C2
GND_C1
GND_B2
CDLY
GATE
OUT_D6
OUT_D4
OUT_C6
OUT_C4
OUT_B6
OUT_B4
OUT_A4
ISENSEOV
UV
REG
EN#
CB
IN_D5
IN_C5
IN_C3
IN_B5
IN_B3
IN_A5
IN_A3
VCC
CA
21
21
21
2
1
2
1
2
1
2
1
2
1
2
1
2
1
2
1
2
1
2
1
2
1
2
1
2
1
2
1 PC2236
2
1
2
1
2
1
2
1
2
1
21
2
1
2
1
R1857
21
21
R3998
2
1
2
1
21
2
1
CA
CA
2
1
2
1
1
SHEETDATE
23
7 3 2 16 5 4
E
A
B
C
E
D
C
B
A
7 6 5 4
D
DEPARTMENT
SIZE
PROJECT DOCUMENT NUMBER REV
REVIEWER
DESIGNER
OUT
OUT
OUT
OUT
OUT
IN
IN
IN
R3997
R3996
R1854
C



Thu Aug 24 14:09:34 2023<NAME_2>
<NAME_1>
MB FABCGTI V02
153 OF 365
P1V8_AUX
P V DD18_S 5_P 0P1V8_AUX
8183
81 15329
150 153
15381
153150
0402LF
0 5%
EMPTY1/16W
5%
FM_ESPI_CPU0_ALERT_R_SEL
ESPI_CPU0_ALERT_PLD_N
0402LF
0
ESPI_CPU0_ALERT_P0_N
0402LF
ESPI_CPU0_ALERT_N
CHIP
ESPI_CPU0_ALERT_R1_N
1/16W
IC
ESPI_CPU0_ALERT_PLD_N
EMPTY
1/16W
4.7K
5%
0402LF
EMPTY
5%
1/16W
4.7K
ESPI_CPU0_ALERT_N
SMLF25V
0.1UF
SCM_SW
10%
0402
X7R
NC7SB3157P6X
R8034
5
6
2
1
34
U8000
A
VCC
S
B0
GND
B1
21R1197
21
2
1
2
1
2
1
1
SHEETDATE
23
7 3 2 16 5 4
E
A
B
C
E
D
C
B
A
7 6 5 4
D
DEPARTMENT
SIZE
PROJECT DOCUMENT NUMBER REV
REVIEWER
DESIGNER
IN
IN
OUT
IN
IN
OUT
R8036R8035
C8007
C



Thu Aug 24 10:14:42 2023<NAME_2>
<NAME_1>
MB FABCGTI V02
154 OF 365Blank
1
SHEETDATE
23
7 3 2 16 5 4
E
A
B
C
E
D
C
B
A
7 6 5 4
D
DEPARTMENT
SIZE
PROJECT DOCUMENT NUMBER REV
REVIEWER
DESIGNER
C



M.2
OCP
Thu Aug 24 14:09:00 2023<NAME_2>
<NAME_1>
MB FABCGTI V02
155 OF 365
P 3V 3_A UX
P 3V 3_A UX
P V DD18_S 5_P 0
133
139
144
28 55155
155
IRQ_OCP_SFF_WAKE_BUF_N
IRQ_OCP_V3_2_WAKE_BUF_N
5%
5%
1/16W 0402LF
33 CHIP
CHIP
1/16W 0402LF
33
M2_0_P E W A K E _R_N 5%33
IRQ _W A K E _NIRQ _W A K E _R_N
5%33
CHIP 10K
0402LF
IRQ _LV C3_W A K E
1/16W
10K
CHIP
0402LF
1%
SMLF
IRQ _LV C3_W A K E _N IRQ _LV C3_W A K E
IC
2N7002K DW
2.2K
0402LF
WAKE
2
1 R437
21R1311
2 1R1009
2
1
R994
21R6063
21R116
21R1005
41
52
36
Q4
D2D1
S2S1
G2G1
1
SHEETDATE
23
7 3 2 16 5 4
E
A
B
C
E
D
C
B
A
7 6 5 4
D
DEPARTMENT
SIZE
PROJECT DOCUMENT NUMBER REV
REVIEWER
DESIGNER
OUT
IN
IN
OUT
IN
IN
C



Thu Aug 24 10:14:43 2023<NAME_2>
<NAME_1>
MB FABCGTI V02
156 OF 365
Blank
1
SHEETDATE
23
7 3 2 16 5 4
E
A
B
C
E
D
C
B
A
7 6 5 4
D
DEPARTMENT
SIZE
PROJECT DOCUMENT NUMBER REV
REVIEWER
DESIGNER
C



Thu Aug 24 10:14:43 2023<NAME_2>
<NAME_1>
MB FABCGTI V02
157 OF 365
Blank
1
SHEETDATE
23
7 3 2 16 5 4
E
A
B
C
E
D
C
B
A
7 6 5 4
D
DEPARTMENT
SIZE
PROJECT DOCUMENT NUMBER REV
REVIEWER
DESIGNER
C



Thu Aug 24 10:14:44 2023<NAME_2>
<NAME_1>
MB FABCGTI V02
158 OF 365
Blank
1
SHEETDATE
23
7 3 2 16 5 4
E
A
B
C
E
D
C
B
A
7 6 5 4
D
DEPARTMENT
SIZE
PROJECT DOCUMENT NUMBER REV
REVIEWER
DESIGNER
C



Thu Aug 24 14:09:00 2023<NAME_2>
<NAME_1>
MB FABCGTI V02
159 OF 365
P 3V 3_A UX
P 3V 3_A UX
P V DD11_S 3_P 1
P V DD11_S 3_P 0 P 3V 3_A UX
P V DD11_S 3_P 1
P 3V 3_A UX
P V DD11_S 3_P 1
P V DD11_S 3_P 0
P V DD11_S 3_P 0
P V DD11_S 3_P 0
P V DD11_S 3_P 1
8083
150
55
8083
55
80
150
28
28
92 93 94 95 96 97
92 93 94 95 96 97
86 87 88 89 90 91
98 99 100 101 102 103
150
150
150
150
104 105 106 107 108 109
80
80
8083
80
55
150
8083
86 87 88 89 90 91
150
55
98 99 100 101 102 103
104 105 106 107 108 109
28
28
RES R1295.1 & R1336.2 / R1296.1& R1337.2 CO-LAYOUT
CPU I3C BYPASS, RES R566.2 & R990.1 / R567.2 & R991.1 CO-LAYOUT
0 E MP TY
CPU I3C BYPASS, RES R564.2 & R988.1 / R565.2 & R989.1 CO-LAYOUT
FM_I3C_CP U1_MUX 1_O E _N
0402LF
1/16W
SMLF
0402LF
I3C_S CM_3_R_S DA
I3C_1_S P D_DDRG L_CP U1_R_S CL
E MP TY
P I3CS W 12ZUA E X
25V
10%
FM_I3C_CP U0_MUX 0_O E _N
1%
0
0
I3C_0_S P D_DDRA F_CP U1_R_S CL I3C_0_S P D_DDRA F_CP U1_S CL
FM_I3C_CP U1_MUX 0_S E L
E MP TY
P I3CS W 12ZUA E X
I3C_S P D_DDRG L_CP U0_LV C1_S DA
0.1UF
I3C_S P D_DDRA F_CP U0_B Y P A S S _S DA
I3C_S CM_0_R_S CL
E MP TY E MP TY
0
0
I3C_0_S P D_DDRA F_CP U0_R_S CL
I3C_0_S P D_DDRA F_CP U0_R_S DA
I3C_S P D_DDRG L_CP U0_S DA
I3C_S P D_DDRG L_CP U0_S CL
X 7R
0.1UF
10%
25V
I3C MUX - DDR5 SPD
I3C_S P D_DDRA F_CP U0_S DA
I3C_S P D_DDRA F_CP U1_S DA
IC
IC
25V
IC
0402
I3C_S P D_DDRG L_CP U1_LV C1_S CL
0402
I3C_S CM_1_R_S DA
I3C_S CM_2_R_S CL
I3C_S CM_2_R_S DA
I3C_S CM_3_R_S CL
I3C_S P D_DDRG L_CP U1_S DA
FM_I3C_CP U1_MUX 1_S E L
0402
FM_I3C_CP U0_MUX 1_S E L
SMLF
0402
X 7R
10%
SMLF
0.1UF
I3C_S P D_DDRA F_CP U0_LV C1_S CL
P I3CS W 12ZUA E X
0.1UF
25V
X 7R
IC
FM_I3C_CP U1_MUX 0_O E _N
10%
FM_I3C_CP U0_MUX 0_S E L
I3C_S P D_DDRG L_CP U0_LV C1_S CL
X 7R
0 I3C_0_S P D_DDRA F_CP U1_S DA
0
I3C_1_S P D_DDRG L_CP U1_R_S DA
0
I3C_S P D_DDRA F_CP U0_LV C1_S DA
0
0
0 I3C_0_S P D_DDRA F_CP U0_S CL
0 I3C_1_S P D_DDRG L_CP U0_S CL
0
0
0I3C_S P D_DDRG L_CP U1_LV C1_S DA
0 E MP TY
E MP TY0
E MP TY0 0 E MP TY
0 E MP TYI3C_S P D_DDRA F_CP U1_B Y P A S S _S DA
0
0
0
00 E MP TY I3C_S P D_DDRG L_CP U0_B Y P A S S _S CL
0 E MP TY 0 E MP TYI3C_S P D_DDRG L_CP U1_B Y P A S S _S CL
0 E MP TYI3C_S P D_DDRG L_CP U1_B Y P A S S _S DA
1%
1/16W
1K
1/16W
E MP TY
1K
1%
1/16W
1%
E MP TY
1K
0402LF
0402LF
1/16W
E MP TY
1%
1K
0402LF
1/16W
E MP TY
1K
0402LF
1K
1%
E MP TY
1%
1K
0402LF
1/16W
1K
E MP TY
1%
0402LF
1/16W
1/16W
E MP TY
0402LF
1K
1%
1K
E MP TY
0402LF
1/16W
E MP TY
1K
0402LF
1%
E MP TY
0402LF
1%
1K
1/16W 1/16W
E MP TY
0402LF
1K
1%
1/16W
1%
1K
0402LF0402LF
E MP TY
1/16W
1%
1K
1/16W
E MP TY
1K
1%
E MP TY
P I3CS W 12ZUA E X
0 I3C_0_S P D_DDRA F_CP U0_S DA
I3C_S CM_0_R_S DA
I3C_S P D_DDRA F_CP U0_B Y P A S S _S CL
FM_I3C_CP U0_MUX 1_O E _N
I3C_S P D_DDRA F_CP U0_S CL
I3C_S CM_1_R_S CL
I3C_1_S P D_DDRG L_CP U0_S DA
1%
I3C_0_S P D_DDRA F_CP U1_R_S DA
I3C_S P D_DDRA F_CP U1_S CL
0 I3C_1_S P D_DDRG L_CP U1_S CL
I3C_1_S P D_DDRG L_CP U1_S DA0
I3C_S P D_DDRG L_CP U1_S CL
CPU I3C BYPASS, RES R426.2 & R2310.1 / R427.2 & R2311.1 CO-LAYOUT
SMLF
0
RES R1297.1 & R1330.2 / R1298.1 & R1331.2 CO-LAYOUT
E MP TY
I3C_1_S P D_DDRG L_CP U0_R_S DA
I3C_1_S P D_DDRG L_CP U0_R_S CL
CPU I3C BYPASS, RES R428.2 & R986.1 / R429.2 & R987.1 CO-LAYOUT
I3C_S P D_DDRG L_CP U0_B Y P A S S _S DA
E MP TY
E MP TY
RES R1299.1 & R1332.2 / R1300.1 & R1333.2 CO-LAYOUT
1/16W
E MP TY
I3C_S P D_DDRA F_CP U1_LV C1_S CL
I3C_S P D_DDRA F_CP U1_LV C1_S DA
I3C_S P D_DDRA F_CP U1_B Y P A S S _S CL
RES R1293.1 & R1334.2 / R1294.1 & R1335.2 CO-LAYOUT
0402LF
R5020R5021
R5019 R5018
R5016R5017
R5014R5015
R5012R5013
R5011 R5010
R5009 R5008
R5007 R5006
21R1337
21R133621R990
21R991
21R1335
21R133421R988
21R989
21R987
21R986 21R1332
21R1333
21R1331
21R1330
21R2311
21R2310
2 1R567
2 1R566
2 1R564
2 1R565
2 1R429
2 1R428
2 1R427
2 1R426
10
9
6
5
7
8
4
3
2
1
U108
2
1
C1339
10
9
6
5
7
8
4
3
2
1
U107
2
1
C1338
2
1
C1337
10
9
6
5
7
8
4
3
2
1
U106
2
1
C1336
10
9
6
5
7
8
4
3
2
1
U105
2 1R1296
2 1R1295
2 1R1294
2 1R1293
2 1R1300
2 1R1299
2 1R1298
2 1R1297
CAD NOTE:
CAD NOTE:
CAD NOTE:
CAD NOTE:
CAD NOTE:
CAD NOTE:
CAD NOTE:
CAD NOTE:
D+
GND
1D-
VDD
S
OE#
D-
2D-
2D+
1D+
D+
GND
1D-
VDD
S
OE#
D-
2D-
2D+
1D+
D+
GND
1D-
VDD
S
OE#
D-
2D-
2D+
1D+
D+
GND
1D-
VDD
S
OE#
D-
2D-
2D+
1D+
2
1
2
1
2
1
2
1
2
1
2
1
2
1
2
1
2
1
2
1
2
1
2
1
2
1
2
1
2
1
2
1
1
SHEETDATE
23
7 3 2 16 5 4
E
A
B
C
E
D
C
B
A
7 6 5 4
D
DEPARTMENT
SIZE
PROJECT DOCUMENT NUMBER REV
REVIEWER
DESIGNER
BI
OUT
BI
OUT
BI
OUT
OUT
BI
IN
IN
IN
IN
IN
IN
IN
IN
IN
IN
BI
BI
IN
BI
IN
BI
BI
IN
BI
IN
IN
BI
BI
IN
C



INTERNAL PU
FROM 2ND SOURCE MUX
FROM MAIN SOURCE MUX
TBCINTERNAL PU
Thu Aug 24 14:09:20 2023<NAME_2>
<NAME_1>
MB FABCGTI V02
160 OF 365
P 3V 3
P 3V 3
P 3V 3_A UX
P 3V 3_A UX
P V DD18_S 5_P 0
P 3V 3_A UX
P V DD18_S 5_P 0
P V DD18_S 5_P 0
P 3V 3_A UX
P V DD11_S 3_P 0
P 3V 3_A UX
P 3V 3P 3V 3
P V DD11_S 3_P 0
P V DD11_S 3_P 0
160 161
160 161
150151160
160
160 161
160 161
160 161
160 161150151
150151
160
160161
160
160161
160
150151160
150151160
150151160
160
160
160
160
S MB _CP U0_CP U1_A P ML_B UF2_S CL_R1
25V
10%
CHIP SMB_CPU0_CPU1_APML_SDA_R20
SMB_CPU0_CPU1_APML_SCL_R2
S MB _CP U0_CP U1_A P ML_B UF2_S DA _R1 0 0402LF
0402LF0
P U_U2_E N
0.1UF
25V
10%PC A9617AD P
0.1UF
S MB _CP U0_CP U1_A P ML_B UF1_S CL
E MP TY
S MB _CP U0_CP U1_A P ML_B UF1_S DAE MP TY
S MB _CP U0_CP U1_A P ML_S DA
E MP TY
0
SMB_CPU0_CPU1_APML_BUF1_SDA_R2
E MP TY
E MP TY
E MP TY
E MP TY
SMB_CPU0_CPU1_APML_SCL_R2
SMB_CPU0_CPU1_APML_SDA_R2
0402LF
E MP TY
1/16W
0402
25V
0.1UF
10%
X 7R
5%
1/16W
E MP TY
0402LF
0402LF
1K
0402LF
1/16W
4.7K
X 7R
0402
X 7R
25V
10%
SMLF
EMPTY
S MB _CP U0_CP U1_S E C_S DA _R2
S MB _CP U0_CP U1_S E C_S CL_R2S MB _CP U0_CP U1_S E C_S CL
S MB _CP U0_CP U1_S E C_S DA S MB _CP U0_CP U1_S E C_S DA _R1
S MB _CP U0_CP U1_S E C_S CL_R1
X 7R
0402
10%
0.1UF
0
0
IC
25V 25V
0402
10%
X 7R
0.1UF
0402
I2C MUX - APML(1/2)
P U_U96_E N
4.7K
1/16W
0402LF
E MP TY
5%
5%
SMLF
PCA9617ADP
P U_U5_E N
0402LF
5%
4.7K
E MP TY
1/16W
5%
4.7K
E MP TY
0402LF
1/16W
5%
4.7K
0402LF
E MP TY
1/16W1/16W
E MP TY
0402LF
5%
S MB _CP U0_CP U1_A P ML_B UF1_S DA _R2
S MB _CP U0_CP U1_S E C_S CL_R2
S MB _CP U0_CP U1_A P ML_B UF1_S CL_R2
S MB _CP U0_CP U1_S E C_S DA _R2
R256/R274 R257/R281 CO-LAYR140/R151 R150/R162 CO-LAY
0
0
0 SMB_CPU0_CPU1_APML_BUF1_SCL_R2
0
E MP TY 0
0
0
S MB _CP U0_CP U1_A P ML_S CL
4.7K
SMLF 0.1UF
X 7R
IC
PCA9617ADP
S MB _CP U0_CP U1_A P ML_B UF2_S CL
S MB _CP U0_CP U1_A P ML_S DA
CHIP
S MB _CP U0_CP U1_A P ML_B UF1_S CL_R1
S MB _CP U0_CP U1_A P ML_B UF1_S DA _R1
0402
0402LF
CHIP
CHIP
0
S MB _CP U0_CP U1_A P ML_S CL 0402LF 0 CHIP
0 S MB _CP U0_CP U1_A P ML_B UF2_S DA
SMB_CPU0_CPU1_APML_BUF2_SDA_R2
SMB_CPU0_CPU1_APML_BUF2_SCL_R2
1%
1/16WEMPTY
4.7K
1K
1%
E MP TY
CHIP 0402LF
0402LFSMB_CPU0_CPU1_APML_BUF2_SDA_R2
SMB_CPU0_CPU1_APML_BUF2_SCL_R2
R322
C2
2
1
R406
2
1
R368
2
1
R365
2
1
R361
R78
2
1
C26
2
1
C23
21R1153
21R1154
2
1
C612
2
1 C611
U5
R290
R201
C3
R200
8 1
6 3
7 2
45
8 1
6 3
7 2
45
81
63
72
4 5
U2
U96
CAD NOTE:CAD NOTE:
GND
SCLB
SDAB SDAA
SCLA
VCCB VCCA
EN
GND
SCLB
SDAB SDAA
SCLA
VCCB VCCA
EN
GND
SCLB
SDABSDAA
SCLA
VCCBVCCA
EN
21
21
21
21
21
21 21
21
21R162
21R151
2
1
2
1
21
21
21
21
2
1
2
1
2
1
2
1
2
1
1
SHEETDATE
23
7 3 2 16 5 4
E
A
B
C
E
D
C
B
A
7 6 5 4
D
DEPARTMENT
SIZE
PROJECT DOCUMENT NUMBER REV
REVIEWER
DESIGNER
IN
IN
IN
IN
BI
IN
IN
BI
OUT
OUT
BI
OUT
BI
OUT
OUT
OUT
OUT
BI
OUT
OUT
BI
IN
R140
R150
R789
R790
R1152
R1151 R256
R257
R281
R274
R206
R202
C



TBC
TBC
ADDR:0XE0(8-BIT)/0X70(7-BIT)
U213 IS APML MUX MAIN SOURCE
U4 IS APML MUX 2ND SOURCE
Thu Aug 24 14:09:00 2023<NAME_2>
<NAME_1>
MB FABCGTI V02
161 OF 365
P V DD18_S 5_P 0
P 3V 3_A UX
P V DD11_S 3_P 0 P V DD18_S 5_P 0
P V DD11_S 3_P 1 P V DD18_S 5_P 1
P 3V 3_A UX
82 83
82 83
161 54
161 54
28 161
82 83
28 161
82 83
16127
55 161
16127
161 55
55161
16155
16154
16154
28161
160
160
28161
161 27
161 27
160161
160161
160161
160161
161 27
161 27
161 54
161 54
FM_APML_MUX2_OE_N
S MB _A P ML_CP U0_MUX 2_S CL
FM_APML_MUX2_SEL
S MB _CP U0_CP U1_A P ML_MUX 2_S DA
CHIP0 0402LF
CHIP
I3C_MUX _CP U0_V IO
1UF
10%
E MP TY
C0402
E MP TY
25V
E MP TY
E MP TY
6.3V
20%
0
0 33
33 S MB _A P ML_CP U1_S DA
S MB _A P ML_CP U1_S CL
33
33
R323/R326 R324/R325 CO-LAY
10%
X7R
0402
25V
0
0
S MB _CP U0_S E C_S CL0
X7R
0.1UF
0402
25V
10% PI3CSW12ZUAEX
FM_SEC_MUX_SEL
S MB _CP U0_S E C_R_S CL
S MB _CP U0_S E C_R_S DA S MB _CP U0_S E C_S DA
FM_SEC_MUX_OE_N
S MB _A P ML_CP U0_S DA
0402LF
0
S MB _CP U1_S E C_R_S CL
1K
CHIP
0402LF
1K
CHIP
S MB _CP U1_S E C_S DA
S MB _A P ML_CP U0_S CL
S MB _CP U1_S E C_S CL
0
E MP TY
E MP TY 0
S MB _CP U1_S E C_S DA
S MB _CP U1_S E C_S CL
S MB _A P ML_CP U1_S CL
I2C MUX - APML(2/2)
0
0
0
0
1%
1K
1% 1%
CHIP
1/16W
1K
1%
1/16W
0402LF
CHIP
1%
1/16W
1%
1K
1/16W
CHIP
0402LF
1K
1%
1/16W
0402LF
S MB _A P ML_CP U1_S DA
E MP TY
0
S MB _CP U1_S E C_R_S DA
1K
0402LF
CHIP
1/16W
1%
1K
0402LF
CHIP
1/16W
0402LF
S MB _CP U0_S E C_S DA
E MP TY
S MB _CP U0_CP U1_S E C_S DA _R2
S MB _CP U0_CP U1_S E C_S CL_R2
SMLF
IC
S MB _CP U0_S E C_S CL
CHIP
1/16W
E MP TY
E MP TY
0
R337/R1157 R338/R1158 CO-LAY
R327/R1156 R328/R1155 CO-LAY
0
SMLF
S MB _A P ML_CP U0_R_S CL
S MB _A P ML_CP U1_R_S CL
IML3112-Y2B000NCG8
1/16W
10K
1%
0402LF
CHIP
E MP TY
E MP TY
E MP TY S MB _A P ML_CP U0_S CL
S MB _A P ML_CP U0_S DA
10UF
E MP TY
EMPTY
EMPTY
C0402
S MB _A P ML_CP U1_R_S DA E MP TY
E MP TY
S MB _A P ML_CP U0_R_S DA
S MB _CP U0_CP U1_A P ML_MUX 1_S DA
S MB _CP U0_CP U1_A P ML_MUX 1_S CL
SMB_CPU0_CPU1_APML_SDA_R2
SMB_CPU0_CPU1_APML_SCL_R2
IC
0.1UF
SMLF
PI3CSW12ZUAEX
SMB_CPU0_CPU1_APML_SCL_R2 S MB _CP U0_CP U1_A P ML_MUX 2_S CL
0402LF0SMB_CPU0_CPU1_APML_SDA_R2
0402LF0 S MB _A P ML_CP U0_S CLCHIP
0 0402LFS MB _A P ML_CP U0_MUX 2_S DA S MB _A P ML_CP U0_S DACHIP
0 0402LFS MB _A P ML_CP U1_MUX 2_S CL S MB _A P ML_CP U1_S CLCHIP
0402LF0S MB _A P ML_CP U1_MUX 2_S DA S MB _A P ML_CP U1_S DACHIP
R1159
R1160
R1157
R1158
2
1
R367
2
1
R360
2
1
R362
21R1155
21R143
21R1161
21R1162
21R147
2
1
R370
2
1
R369
2
1
R363
2
1
R366
2
1
R359
21R1156
21R142
21R139
R5004
21R146
21R144
21R145
21R148
21R358
C9 C24
R338
R337
R328
R327
C11
C25
10
9
6
5
7
8
4
3
2
1
7
5
9
8
1
6
4
2
3
10
9
6
5
7
8
4
3
2
1
U4
U213
U6
CAD NOTE:
CAD NOTE:
CAD NOTE:
D+
GND
1D-
VDD
S
OE#
D-
2D-
2D+
1D+
D+
GND
1D-
VDD
S
OE#
D-
2D-
2D+
1D+
TH_GND
LSDA_1||HSAHSCL
LSCL_0
LSDA_0
VIO
LSCL_1
VDD
HSDA
2
1
2
1
21
21
21R326
21R325
21
21
21
21
2
1
21
21
21
21
2
1
2
1
1
SHEETDATE
23
7 3 2 16 5 4
E
A
B
C
E
D
C
B
A
7 6 5 4
D
DEPARTMENT
SIZE
PROJECT DOCUMENT NUMBER REV
REVIEWER
DESIGNER
BI
BI
OUT
OUT
IN
IN
IN
IN
BI
BI
BI
BI
OUT
BI
OUT
OUT
OUT
OUT
OUT
OUT
OUT
OUT
OUT
BI
BI
BI
IN
BI
BI
IN
R324
R323
C



Thu Aug 24 10:14:46 2023<NAME_2>
<NAME_1>
MB FABCGTI V02
162 OF 365
Blank
1
SHEETDATE
23
7 3 2 16 5 4
E
A
B
C
E
D
C
B
A
7 6 5 4
D
DEPARTMENT
SIZE
PROJECT DOCUMENT NUMBER REV
REVIEWER
DESIGNER
C



Thu Aug 24 10:14:47 2023<NAME_2>
<NAME_1>
MB FABCGTI V02
163 OF 365
Blank
1
SHEETDATE
23
7 3 2 16 5 4
E
A
B
C
E
D
C
B
A
7 6 5 4
D
DEPARTMENT
SIZE
PROJECT DOCUMENT NUMBER REV
REVIEWER
DESIGNER
C



CPU0 UART1
TO SCM UART1
Thu Aug 24 14:09:00 2023<NAME_2>
<NAME_1>
MB FABCGTI V02
164 OF 365
P V DD18_S 5_P 0
P 5V _A UX P 3V 3_A UX
P 3V 3_A UX
P 3V 3_A UX
P V DD18_S 5_P 0
P V DD18_S 5_P 0
P V DD18_S 5_P 0
164
16427
16427
164 150 151
164
164
81
164
164150151
150151164
164
164
164
150 151 164
164 27
164 27
27 164
27 76 164
27164
2776164
164
33UA RT_LS _E N_R_N UA RT_LS _E N_N
1/16W
5%
10K
0402LF
CHIP
5%
10K
1/16W
0402LF
CHIP
0402LF
1/16W
5%
10K
CHIP
5%
0402LF
1/16W
10K
CHIP
1/16W
CHIP
5%
10K
0402LF
10K
0402LF
E MP TY
5%
1/16W
5%
1/16W
E MP TY
0402LF
10K
5%
1/16W
E MP TY
0402LF
10K
1/16W
5%
0402LF
E MP TY
10K
10K
1/16W
E MP TY
5%
0402LF
UA RT_CP U0_S CM_UA RT1_R_RXUA RT_CP U0_S CM_UA RT1_RX 0
UA RT_CP U0_UA RT0_R_RXUA RT_CP U0_UA RT0_RX 0
UA RT_CP U0_S CM_LV C3_UA RT1_TXUA RT_CP U0_S CM_LV C3_UA RT1_R_TX 0
UA RT_CP U0_LV C3_UA RT0_TXUA RT_CP U0_LV C3_UA RT0_R_TX 0
UA RT_CP U0_LV C3_UA RT0_RXUA RT_CP U0_LV C3_UA RT0_R_RX 0
4.7K
1/16W
CHIP
0402LF
5%
SMLF
IC
10%
NX 138B K
SMLF
UA RT_LS _E N
IC
50V
25V 25V
CO NN4_HFK 1040-L0P 1L-7H
IO
X 7R
UART LEVEL SHIFT
THLF
220P F
UA RT_CP U0_LV C3_UA RT0_TX
220P F
C0402
50V
5%
UA RT_V CC_J13
5%
C0402
0402
S N74A V C4T774P W R
0.1UF
10%
X 7R
0402
UA RT_CP U0_S CM_LV C3_UA RT1_TX
UA RT_CP U0_S CM_LV C3_UA RT1_R_RX
UA RT_CP U0_LV C3_UA RT0_TX
UA RT_CP U0_LV C3_UA RT0_RX
UA RT_CP U0_LV C3_UA RT0_R_RX
UA RT_CP U0_S CM_LV C3_UA RT1_R_RX
0.1UFUA RT_CP U0_UA RT0_RX
UA RT_CP U0_S CM_UA RT1_RX
UA RT_CP U0_UA RT0_TX
UA RT_CP U0_S CM_UA RT1_TX
UA RT_CP U0_UA RT0_TX
UA RT_CP U0_S CM_UA RT1_TX
UA RT_LS _E N_N
164
21R1423
21R817
21R1425
21R818
21R819
2 1R1253
2
1
R822
2
1
R823
2
1
R824
2
1
R825
2
1
R813
2
1
R814
2
1
R815
2
1
R816
4
3
2
1
J13
2
1 C363
2
1 C364
2
1
R821
2
1C1352
2
1 C1354
2
1
R1419
G
Q61
21
R820
S D
1516
9
10
8
7
2
1
11
12
13
14
6
5
4
3
U116
GATE
1
2
3
4
VCCA VCCB
B1
B2
B3
B4
GND
OE
DIR4
DIR3
A4
A3
A2
A1
DIR2
DIR1
DRAINSOURCE
1
SHEETDATE
23
7 3 2 16 5 4
E
A
B
C
E
D
C
B
A
7 6 5 4
D
DEPARTMENT
SIZE
PROJECT DOCUMENT NUMBER REV
REVIEWER
DESIGNER
IN
IN
IN
OUT
IN
OUT IN
OUT
IN
OUT
OUT
OUT
OUT
OUT
OUT
OUT
OUT
OUT
IN
OUT
OUT
C



BIOS DBG MODE LED
Thu Aug 24 14:09:02 2023<NAME_2>
<NAME_1>
MB FABCGTI V02
165 OF 365
G ND
P 3V 3_A UX
P 3V 3_A UX
LED (1/2)
B IO S _DE B UG _MO DE
LE D_B IO S _DB G _MO DE _N
SMLF
IC
NX 138B K
SMLF
IC
NX 138B K
1K
CHIP
1/16W
1%
0402LF
LE D_B IO S _DB G _MO DE
S MLF
IC
LE D_B LUE
LTST-C281TBKT-5A
CHIP1% 1/16W130
LE D_B IO S _DB G _MO DE _R
0402LF
2816781
2
1
R1507
21R1444
G
Q30
G
Q29
CA
D9
S D
S D
GATE
GATE
A C
DRAINSOURCE
DRAINSOURCE
1
SHEETDATE
23
7 3 2 16 5 4
E
A
B
C
E
D
C
B
A
7 6 5 4
D
DEPARTMENT
SIZE
PROJECT DOCUMENT NUMBER REV
REVIEWER
DESIGNER
IN
C



BOOT-UP READY LED
SMERR LED
P12V POWER LED
P5V_AUX POWER LED
Thu Aug 24 14:09:01 2023<NAME_2>
<NAME_1>
MB FABCGTI V02
166 OF 365
P 1V 8_A UX
P 5V _A UX
P 3V 3_A UX
P 3V 3_A UX
P 5V _A UX
P 3V 3_A UX
P 3V 3_A UX
P 3V 3_A UX
P 3V 3_A UX
P 1V 8_A UX
81
81
2834
28
FM_S ME RR_B UF_R_LE D_N0
00
25V
0.1UF
1/16W
470 1%
LTST-C281TBKT-5A
0402LFCHIP
1/16W
470
S MLF
LTST-C281TBKT-5A
SMLF
P 12V _A LL_P W RO K _N
IC
LE D_B LUE
P U_P 12V _A LL_P W RO K _LE D
S MLF
IC
P U_S ME RR_LE D
LTST-C190KSKT-P
S ME RR_LE D
249 0402LF1% CHIP1/16W
LE D_Y E LLO W1/16W
2N7002K DW
S ME RR_LE D_N
S MLF
IC
IC
5%
SMLF
0402LF
1%
CHIP
IC
P 5V _S TB Y _P W R_LE D
LE D_B LUE
130 0402LF1% CHIP1/16W
1/16W
LTST-C281TBKT-5A
LE D_B LUE
S MLF
IC
2N7002K DW
B O O T_RDY _LE D_N
SMLF
CHIP
P U_B O O T_RDY _LE D
4.7K 4.7K
P 12V _A LL_P W RO K
FM_S ME RR_LE D_N
10%
0402
S MLF
S MLF
25V
S N74LV C1G 07DB V R
S N74LV C1G 07DB V R
10%
IC
X 7R
IC
X 7R
B O O T_RDY _LE D
LED (2/2)
NX 138B K
0402
IC
0.1UF
B O O T_RDY _R1_N
5%
CHIP
4.7K
1/16W
CHIP
5%
4.7K
1/16W
5%
CHIP
FM_B IO S _P O S T_CMP LT_N B O O T_RDY _B UF_R_LE D B O O T_RDY _B UF_LE D
FM_S ME RR_B UF_LE D_N
E MP TY
0B O O T_RDY _H
G
Q12
C A
D46
21
R1208
21
R1207
C A
D49
21R941
21
R934
4
5
13
2
U86
2
1 C219
4
5
13
2
U82
2
1 C218
21
R936
21 R935
41
52
36
Q112
1
R945
41
52
36
Q22
1
R944
2
1
R947
C A
D6
C A
D5
21R948
2
1
R946
21
R950
S D
AC
AC
GATE
AC
AC
NC
Y
GND
A
VCC
NC
Y
GND
A
VCC
D2D1
S2S1
G2G1
D2D1
S2S1
G2G1
DRAINSOURCE
1
SHEETDATE
23
7 3 2 16 5 4
E
A
B
C
E
D
C
B
A
7 6 5 4
D
DEPARTMENT
SIZE
PROJECT DOCUMENT NUMBER REV
REVIEWER
DESIGNER
IN
IN
IN
IN
C



SWITCH DEFAULT IS OFF
20220407: PU PVDD18_S5_P0, DE-POP R1538
ON: PASSWORD CLEAR
OFF: NORMAL (DEFAULT)
FPGA_DEBUG_LED_CTRL
OFF:POST LED(DEFAULT)
ON: DISABLE CPU1 DEBUG
OFF: CPU1 PRESENT FOR DEBUG (DEFAULT)
CPU1 BYPASS CHAIN CONTROL
ON: BMC SPD REMOTE DEBUG ENABLED
BMC JTAG SEL
ON: ENABLE ALL POWER ON
FORCE POWER ON
OFF: BMC SPD REMOTE DEBUG DISABLED (DEFAULT)
BMC SPD REMOTE DEBUG BIOS USB RECOVERY CPU0 BYPASS CHAIN CONTROL
OFF: CPU0 PRESENT FOR DEBUG (DEFAULT)
ON: DISABLE CPU0 DEBUG
HW ASD EN
ON: NORMAL OPERATION (DEFAULT)
OFF: BIOS USB FLASH RECOVERY MODE
PASSWORD CLEAR
ON:FPGA_DEBUG_LED
OFF: ENABLE JTAG MUX TO PLD (DEFAULT) BIOS RECOVERY
OFF: BIOS USB FLASH RECOVERY MODE
ON: NORMAL OPERATION (DEFAULT)
20220407: PU PVDD18_S5_P0, DE-POP R1264
ON:FRU
OFF:NORMAL(DEFAULT)
SWITCH DEFAULT IS OFF
FPGA_DEBUG_SW_SPARE
OFF: DISABLE ALL POWER ON (DEFAULT) OFF: ENABLE REMOTE DEBUG
ON: DISABLE REMOTE DEBUG (DEFAULT)
ON: ENABLE JTAG MUX TO HDT
Thu Aug 24 14:09:01 2023<NAME_2>
<NAME_1>
MB FABCGTI V02
167 OF 365
P V DD18_S 5_P 0P 1V 8_A UX
P 1V 8_A UX
P 1V 8_A UX
P 1V 8_A UX
P 3V 3_A UX
P 3V 3_A UX
P 1V 8_A UX
P 1V 8_A UX
P 3V 3_A UX
P 1V 8_A UX
P V DD18_S 5_P 0
P 3V 3_A UX P 1V 8_A UX
P 1V 8_A UX
P 3V 3_A UX
167
16781
167 81
167 81
167 27 81
167 81
81 167 28 165
167 82
167 82
167
167
167 167 81
167 28
167
167 81
8116728165
16728
167
16782
27
16782
1672781
16781
54
16781
16781
167
16781
167
167 172
167172
81167
81167
FM_FO RCE _A LL_P W RO N_O N
FM_FO RCE _A LL_P W RO N
0
0
1/16W
EMPTY
U124_V CC
SN74LVC1G07DBVR
SMLF
SW20S_DHNF-10F-Q-T/R
FM_S P D_CP U0_S W ITCH_CTRL_N
FM_FO RCE _A LL_P W RO N
FM_B IO S _US B _RE CO V E RY
FP G A _DE B UG _S W _S P A RE
B IO S _DE B UG _MO DE
FM_P RS NT_CP U0_N
FM_P RS NT_CP U1_N
FM_FO RCE _A LL_P W RO N_O N
P U_B IO S _US B _RE CO V E RY
DEBUG JUMPER
P U_FP G A _DE B UG _LE D_CTRL FP G A _DE B UG _LE D_CTRL
FM_P A S S W O RD_CLE A R_N
P D_B IO S _DE B UG _MO DE
P U_FP G A _DE B UG _S W _S P A RE
B MC_JTA G _S E L
MECH 0402LF
SMLF
1/16W
5%
CHIP
0402LF
5%
1/16W
CHIP
5%
4.7K
0402LF
B IO S _DE B UG _MO DE
FM_P A S S W O RD_CLE A R_N
2.2K
1/16W
P U_B IO S _US B _RE CO V E RY
0402LF
5%
CHIP
FM_P RS NT_CP U1_N
P RS NT_CP U0_N
FM_P RS NT_CP U0_N
FM_B IO S _US B _RE CO V E RY
B MC_JTA G _S E L
P RS NT_CP U1_N
FM_S P D_CP U0_S W ITCH_CTRL_N
100
100
0402LF
100
1%
CHIP
1/16W
100K CHIP
CHIP100K
FP G A _DE B UG _LE D_CTRL
CHIP
10K
10K
10K
10K
10K
10K
10K
1K
100K
P U_FP G A _DE B UG _LE D_CTRL
FP G A _DE B UG _S W _S P A RE
P U_FP G A _DE B UG _S W _S P A RE
JTAG_BMC_OE
10K
00
IC
1%
100
0402LF
E MP TY
1/16W
1/16W
E MP TY
0402LF
1%
0.1UF
25V
X 7R
0402
JTA G _B MC_O E
FM_JTA G _B MC_R_O E
100
FM_JTA G _B MC_R_O E
10K
21
21
21
2
1
R6107
2
1
R6106
2
1
R1356
2
1
R1357
2
1
R1358
2
1
R6040
2
1
R6042
2
1
R22
2
1R1265
2
1
R733
2
1
R1264
2
1
R5071
2
1R6044
2
1
R1262
R734
R744
2
1
R1261
21R1508
R6041
R6043
R8
U124
R8019
R8017 R8018
C693
20
19
18
17
16
15
14
13
12
11
10
9
8
7
6
5
4
3
2
1
4
5
13
2
SW1
ON
10
9
20
19
18
17
16
15
8
7
6
5
14
13
12
11
4
3
2
1
NC
Y
GND
A
VCC
2
1
2
1
2
1
21
21
2
1
1
SHEETDATE
23
7 3 2 16 5 4
E
A
B
C
E
D
C
B
A
7 6 5 4
D
DEPARTMENT
SIZE
PROJECT DOCUMENT NUMBER REV
REVIEWER
DESIGNER
IN
IN
OUT
IN
OUT
OUT
OUT
OUT
OUT
OUT
OUT
OUT
OUT
IN
OUT
OUT
IN
IN
OUT
OUT
OUT
OUT
OUT
OUT
OUT
OUT
OUT
OUT
IN
OUT
OUT
OUT
OUT
IN
C



Thu Aug 24 10:14:50 2023<NAME_2>
<NAME_1>
MB FABCGTI V02
168 OF 365
Blank
1
SHEETDATE
23
7 3 2 16 5 4
E
A
B
C
E
D
C
B
A
7 6 5 4
D
DEPARTMENT
SIZE
PROJECT DOCUMENT NUMBER REV
REVIEWER
DESIGNER
C



P3V3_AUX DISCHARGE
VTH(MAX)=2.2V
VTH(MAX)=1V
P12V_AUX DISCHARGE
VTH(MAX)=1V
VTH(MAX)=2.2V
Thu Aug 24 14:09:59 2023<NAME_2>
<NAME_1>
MB FABCGTI V02
169 OF 365
P12V_AUX
P12V_AUX
P12V_AUX
P12V_AUX
P3V3_AUX
P3V3_AUX
P3V3_AUX_DSC
EMPTY
PSMNR58-30YLH
SMLFP3V3_AUX_DSC_G2
DMP2035U-7
EMPTY
EMPTY
0402LF
EMPTY
1/16W
11.5K
0402LF
P3V3_AUX_DSC_VOL
2512LF
P12V_AUX_DSC
EMPTY
PSMNR58-30YLH
SMLF
EMPTY
0402LF
1/16W
1%
EMPTY
0402LF
EMPTY
1/16W
0402LF
EMPTY
P12V_AUX_DSC_G2
EMPTY
2W
1%
10
10K
EMPTY
1/16W
1%
10K
0402LF
P3V3_AUX_DSC_S1
P12V_AUX_DSC_S1
DMP2035U-7
SMLF
SMLF
EMPTY
C0805
20%
P12V_AUX_DSC_VOL
0402LF
1K
EMPTY
1K
1%
0402LF
EMPTY
EMPTY
DISCHARGE CIRCUIT
0402LF
P12V_AUX_DSC_G1
30K
1%
10M
1/16W
EMPTY
1/16W
1%
1%
2K
0402LF
11.5K
1%
EMPTY
1/16W
30K
1%
1/16W
1/16W
1%
BAT54CW
SMLF
EMPTY
16V
22UF
P3V3_AUX_DSC_G1
C0805
EMPTY
20%
16V
1%
1/16W
BAT54CW
SMLF
EMPTY
2512LF
10
1%
2W
22UF
3
1
2
S D 4
4S D3
1
2
G
5
3
2
1
5
3
2
1
G
Q7003
Q7001
U57
C
B
A
C
B
A
S D
D1
G1
S3 S2 S1
4
D1
G1
S3 S2 S1
4S DG
1
2 5
3
1
2 5
3
G
U60
Q7002
Q7000
S
G
D
S
G
D
2
1
2
1
2
1
2
1
2
1
2
1
2
1
2
1
2
1
2
1
2
1
2
1
2
1
2
1
1
SHEETDATE
23
7 3 2 16 5 4
E
A
B
C
E
D
C
B
A
7 6 5 4
D
DEPARTMENT
SIZE
PROJECT DOCUMENT NUMBER REV
REVIEWER
DESIGNER
R1092
R1052
R954
R896
C1114
R1475
R1481
R1480
R1474R1049
R1007
C1113
R855
R700
C



Thu Aug 24 10:14:51 2023<NAME_2>
<NAME_1>
MB FABCGTI V02
170 OF 365
Blank
1
SHEETDATE
23
7 3 2 16 5 4
E
A
B
C
E
D
C
B
A
7 6 5 4
D
DEPARTMENT
SIZE
PROJECT DOCUMENT NUMBER REV
REVIEWER
DESIGNER
C



JTAG ENABLE JUMPER
1-2 DISABLE(DEFAULT)
2-3 ENABLE
TBC
JTAG ENABLE JUMPER
1-2 DISABLE(DEFAULT)
2-3 ENABLE TBC
RSVD
CPLD
CPLD
CPU
Thu Aug 24 14:09:01 2023<NAME_2>
<NAME_1>
MB FABCGTI V02
171 OF 365
P 3V 3_A UX
P 3V 3_A UX
P 3V 3_A UX
P 3V 3_A UX
P 3V 3_A UX
P 3V 3_A UX
P 3V 3_A UX
P 3V 3_A UX
P 3V 3_A UX
P 3V 3_A UX
TP _JTA G _S CM_S LO T3_R_TDI
JTA G _S CM_P LD_R_TDO
JTA G _S CM_MUX _R_TDO
TP _JTA G _S CM_S LO T3_R_TDO
R6102 PLACE CLOSE TO U212
JTA G _S CM_P LD_TMS
JTA G _S CM_P LD_TCK
CHIP
22
1%
22
1%
22
CHIP
CHIP
5%
4.7K
0402LF
4.7K
CHIP
5%
1/16W
0402LF
1/16W
5%
4.7K
E MP TY
0402LF
E MP TY
5%
4.7K
0402LF
1/16W
JTA G _S CM_MUX _TDO
1/16W
X 7R
S MLF
S N74LV C1G 07DB V R
0402LF
0402
0402LF
0402LF
25V
16V
10K
0.1UF
0.1UF
10K
10K
10K 10K 10K
10K
1%
10%
10%
1%
1%
1% 1% 1%
1%
1%
E MP TY E MP TY
CHIP
X 7R
CHIP CHIP
CHIP
1/16W
1/16W 1/16W
JTA G _S CM_TDO
JTA G _S CM_TDI
JTA G _S CM_TMS
JTA G _S CM_TCK
JTA G _S CM_MUX _TDI
JTAG - BMC MUX
10K
E MP TY E MP TY
1%
0402LF
E MP TY
1% 1%
10K10K
1/16W
0402LF
10K
X 7R
1/16W
S CM_JTA G _MUX _S 0
0402LF
1/16W
E MP TY
5%
4.7K
C0402
CHIP
CHIP
4.7K
4.7K
5%
22
5%
0402LF
0402LF
4.7K
CHIP
4.7K
5%
PU_U212_EN_N
PD_U212_EN_N
1/16W
IO
74LV 4052P W
SMLF
IC
JTA G _S CM_TCK
CHIP
JTA G _S CM_TDI
S CM_JTA G _MUX _S 0_R2
JTA G _S CM_TDO
S CM_JTA G _MUX _S 1
1%
1%
JTA G _S CM_P LD_TDO
JTA G _S CM_P LD_TDI
JTA G _S CM_TMS
C0402
FW _RE CO V E RY _R
10%
16V
CHIP
TP _JTA G _S CM_S LO T3_R_TMS
5%
1/16W
0.1UF
JTA G _S CM_P LD_R_TCK
TP _JTA G _S CM_S LO T3_R_TCK
JTA G _S CM_P LD_R_TMS
R6101 PLACE CLOSE TO U160
U160_E N_N
S CM_JTA G _MUX _S 0_R1
CHIP
JTA G _S CM_MUX _TDI
CHIP
JTA G _S CM_MUX _R_TMS JTA G _S CM_MUX _TMS0
CHIP
JTA G _S CM_MUX _R_TCK JTA G _S CM_MUX _TCK0
5%
5%
0
CHIP
0402LF
5%
0
CHIP
JTA G _S CM_MUX _TDO
SMLF
JTA G _S CM_P LD_R_TDI
JTA G _S CM_MUX _R_TDI
0
0
8085
8085
172 171
171 151
151 171
171 150
171 150
171 172
171
172
80
171 150
151 171
171 151
80
8085
8580
171 150
150
172171
172171
172171
172171
C ON N 3_210-H P1-030BR 1
U212_E N_N
IC
74LV 4052P W
0402LF
1/16W
THLF
IO
C ON N 3_210-H P1-030BR 1
5%
E MP TY
172
171 JTA G _S CM_MUX _TCK
JTA G _S CM_MUX _TMS
PU_U160_EN_N
PD_U160_EN_N
THLF
1/16W
R1739
R6182
R1313
R6181
2
1
R1318
21 R6102
21 R6101
2
1
R1342
21R1740
21R1741
21R1736
21R1737
21R1742
21R1738
2
1 C553
4
5
13
2
U99
2
1
R1343
21R1743
2
1
R1658
2
1
R1659
2
1
R1729
2
1
R1730
2
1C194
2
1C1554
2
1
R1744
2
1
R1748
2
1
R1745
2
1
R1746
2
1
R1747
2
1
R1727
2
1
R1728
2
1
R1735
2
1
R1731
2
1
R1734
3
2
1
3
2
1
7
16
9
10
8
6
3 4
2
5
1
13
11
15
14
12
7
16
9
10
8
6
3 4
2
5
1
13
11
15
14
12
JP6001
JP6000
U212
U160
CAD NOTE:
CAD NOTE:
1
2
3
1
2
3
NC
Y
GND
A
VCC
VCC
1Y2
1Y1
1Z
1Y0
1Y3
S0
S1
GND
VEEE_N
2Y1
2Y32Z
2Y2
2Y0
VCC
1Y2
1Y1
1Z
1Y0
1Y3
S0
S1
GND
VEEE_N
2Y1
2Y32Z
2Y2
2Y0
21
2
1
2
1
2
1
1
SHEETDATE
23
7 3 2 16 5 4
E
A
B
C
E
D
C
B
A
7 6 5 4
D
DEPARTMENT
SIZE
PROJECT DOCUMENT NUMBER REV
REVIEWER
DESIGNER
OUT
OUT
OUT
OUT
IN
IN
IN
OUT
OUT
IN
OUT
IN
IN
IN
IN
OUT
OUT
OUT
OUT
OUT
OUT
OUT
OUT
C



BMC
H:BMC
L:HDT
HDT TO JTAG BUF
Thu Aug 24 14:09:01 2023<NAME_2>
<NAME_1>
MB FABCGTI V02
172 OF 365
P V DD18_S 5_P 0
P 3V 3_A UX
P V DD18_S 5_P 0
P V DD18_S 5_P 0
P V DD18_S 5_P 0
P V DD18_S 5_P 0
P V DD18_S 5_P 0
P V DD18_S 5_P 0
P V DD18_S 5_P 0
P 3V 3_A UX
P V DD18_S 5_P 0
P 3V 3_A UX
173
173
8381
2782
172
2782
2782
81
173
172
173
172
172
172
172
172
150151
80
172
172
172
172
171
167
171
172
171
171
173
173
81
81
0.01UF
50V
10%
E MP TY
C0402
0.1UF
R6108 PLACE CLOSE TO U146
X 7R
10%
16V
C0402
R6111 PLACE CLOSE TO U146
X 7R
B S S 138K
JTA G _B MC_O E _N
0402LF
1/16W
S N74A V C2T245RS W R
JTA G _B MC_R_D_O E
0402LF
JTA G _DB RE Q _N22
1%
JTA G _TRS T_N22
1%
P RS NT_HDT_R_NP RS NT_HDT_N 33
HDT_CP U0_X TRIG _L5CP U0_X TRIG _L5 33
HDT_HDR_TRS T_N 33
HDT_CP U0_X TRIG _L6CP U0_X TRIG _L6 33
HDT_CP U0_X TRIG _L7CP U0_X TRIG _L7 33
CP U0_HDT_CO NN_TE S TE N33
33
1%
0402LF
1K
CHIP
1/16W
1%
1K
1%
0402LF
1K
CHIP
1/16W
1%
1K
1%
1K
1%
1K
1%
1K
JTA G _TDO0
HDT_HDR_TDO _RHDT_HDR_TDO
CHIP
0
HDT_HDR_R_TCK 0
HDT_HDR_R_TMS 0
HDT_HDR_R_TDI 0
0
5%
CHIP
4.7K
4.7K
5%
1/16W
CHIP
SMLF
PLACE U146 AND U147 CLOSER
JTA G _TDI_R
JTA G _TDO _R1
SMLF
SMLF
SMLF
PLACE CAP AND RES NEAR J54
JTAG - HDT & BMC MUX
PLACE U149 AND U148 CLOSER
JTA G _TCK
HDT_HDR_TMS
HDT_HDR_TCK
HDT_HDR_TDO
HDT_HDR_TDI
HDT_HDR_DB RE Q _N
JTA G _TMS _R
JTA G _TRS T_R_N
JTA G _TCK _R
JTA G _DB RE Q _R_N
JTA G _S CM_DB RE Q _N
JTA G _S CM_TRS T_N
HDT_HDR_DB RE Q _N
HDT_HDR_TMS
HDT_HDR_TRS T_N
HDT_HDR_TCK
HDT_HDR_DB RE Q _R_N
HDT_CP U0_HDT_CO NN_TE S TE N
HDT_HDR_TRS T_N_R
JTA G _S CM_MUX _TDI
JTA G _B MC_O E
IC
X 7R
IC
X 7RX 7RX 7RX 7R
IO
X 7R
NP ONP ONP O
X 7R
IC
IC
X 7R
X 7R
IC
10%
10%10%
10%
5%5%5%
10%
10%
10%
10%
0.1UF
S CO NN20_HS U2101-L0000-7H
0.001UF
33P F33P F33P F
0.1UF
S N74A V C4T774P W R
0.1UF
S N74A V C2T245RS W R
16V
50V50V50V
50V
50V50V50V
16V
16V
16V
16V
C0402
C0402C0402
C0402
040204020402
C0402
C0402
C0402
C0402
SMLF
S N74A V C4T774P W R
SMLF
0.1UF
16V
JTA G _S CM_MUX _TDO
0.1UF
HDT_HDR_TDI
0.1UF
10%
X 7R
JTA G _S CM_MUX _TMS
JTA G _S CM_MUX _TCK
C0402
JTA G _TDI
CHIP
0
25V
X7R
10%
0402
0.1UF
JTA G _TMS0
5%
0
5%
HDT_HDR_RE S E T_N
HDT_HDR_P W RO K
10%10%
C0402C0402
0.001UF 0.001UF 0.001UF
50V
0.01UF
2
1 C86
21R6111
21
R6108
21R1528
2
1 C85
21R478
21R1620
21R476
21R477
2
1
R1621
2019
1817
1615
1413
1211
109
87
65
43
21
J54
2
1 C604
2
1 C605
2
1 C87
21R1353
21R1352
2
1 C551
2
1
R1630
2
1
R1628
2
1
R1627
2
1
R1626
21R1632
21R1631
2
1 R1629
2
1
R1624
21R1354
G
Q62
2
1
R617
21R1634
21
R1619
2
1
R1622
2
1
C1503
6
7
2
3
1
10
4
5
9
8
U146
2
1
C1505
2
1
C1506
2
1
C1504
21R1625
2
1
C1507
1516
9
10
8
7
2
1
11
12
13
14
6
5
4
3
U148
1516
9
10
8
7
2
1
11
12
13
14
6
5
4
3
U149
2
1
C1508
2
1 C1510
2
1 C1511
2
1 C1512
2
1
C1509
21R1636
21R1635
21R1633
6
7
2
3
1
10
4
5
9
8
U147
S D
C8006
CAD NOTE:
CAD NOTE:CAD NOTE:
CAD NOTE:
CAD NOTE:
DIR1
A2
A1
VCCA
VCCB
B1
B2
GND
OE_#
DIR2
VCCA VCCB
B1
B2
B3
B4
GND
OE
DIR4
DIR3
A4
A3
A2
A1
DIR2
DIR1
VCCA VCCB
B1
B2
B3
B4
GND
OE
DIR4
DIR3
A4
A3
A2
A1
DIR2
DIR1
2019
1817
1615
1413
1211
109
87
65
43
21
DIR1
A2
A1
VCCA
VCCB
B1
B2
GND
OE_#
DIR2
2
1
1
SHEETDATE
23
7 3 2 16 5 4
E
A
B
C
E
D
C
B
A
7 6 5 4
D
DEPARTMENT
SIZE
PROJECT DOCUMENT NUMBER REV
REVIEWER
DESIGNER
IN
OUT
IN
OUT
IN
IN
IN
IN
IN
IN
OUT
OUT OUTIN
IN
IN
IN
OUT
OUT
OUT
BI
BI
OUT
BI
OUT
OUT
IN
OUT
IN
OUT
IN
OUT
C



CPU0/1 TDI/TDO DAISY CHAIN
CPU0
CPU1
Thu Aug 24 14:09:02 2023<NAME_2>
<NAME_1>
MB FABCGTI V02
173 OF 365
P V DD18_S 5_P 0 P V DD18_S 5_P 0
P V DD18_S 5_P 0
P V DD18_S 5_P 0 P V DD18_S 5_P 0
P V DD18_S 5_P 1
174
172
172
172
172
172
81
174
172
27
27
27
54
54
54
54
27
81
0
R6103 PLACE CLOSE TO U152
SMLF
JTA G _CP UX _TDO
JTA G _TDI
C0402
X 7R
C0402
C0402
C0402
C0402
C0402
16V
16V
16V
16V
S N74A V C4T774P W R
0.1UF
0.1UF
S N74A V C2T245RS W R
0.1UF
0.1UF
0.1UF
10%
10%
10%
10%
IC
X 7R
IC
X 7R
X 7R
X 7R
JTA G _TMS
JTA G _DB RE Q _N
JTA G _TRS T_N
JTA G _TCK
CP U0_JTA G _B UF_O E
JTAG - BUFFER
SMLF
U152_O E _N
R6109 PLACE CLOSE TO U152 4.7K
5%
0402LF
CHIP
1/16W
JTA G _CP UX _TDI_R1 JTA G _CP UX _TDI
CHIP
0JTA G _TDO JTA G _TDO _R
CHIP 1%
22JTA G _P 0_R_TMS JTA G _CP U0_TMS
CHIP 1%
22JTA G _P 0_R_TRS T_N JTA G _CP U0_TRS T_N
CHIP 1%
22JTA G _P 0_R_TCK JTA G _CP U0_TCK
CHIP 1%
22JTA G _P 1_R_TCK JTA G _CP U1_TCK
CHIP 1%
22JTA G _P 1_R_TMS JTA G _CP U1_TMS
CHIP 1%
22JTA G _P 1_R_TRS T_N JTA G _CP U1_TRS T_N
CHIP 1%
22 JTA G _CP U1_DB RE Q _N
CHIP 1%
22JTA G _P 0_R_DB RE Q _N JTA G _CP U0_DB RE Q _N
CP U1_JTA G _B UF_O E
0.1UF
JTA G _P 1_R_DB RE Q _N
16V
10%
X 7R
SMLF
16V
10%
IC
S N74A V C4T774P W R
R6109
21 R6103
2
1
R1637
2
1
C1513
2
1
C1518
6
7
2
3
1
10
4
5
9
8
U152
2
1
C1515
2
1
C1517
21R1645
21R1644
21R1643
21R1642
1516
9
10
8
7
2
1
11
12
13
14
6
5
4
3
U151
21R1638
21R1640
21R1639
21R1641
2
1
C1514
2
1
C1516
1516
9
10
8
7
2
1
11
12
13
14
6
5
4
3
U150
CAD NOTE:
CAD NOTE:
VCCA VCCB
B1
B2
B3
B4
GND
OE
DIR4
DIR3
A4
A3
A2
A1
DIR2
DIR1
DIR1
A2
A1
VCCA
VCCB
B1
B2
GND
OE_#
DIR2
VCCA VCCB
B1
B2
B3
B4
GND
OE
DIR4
DIR3
A4
A3
A2
A1
DIR2
DIR1
21
1
SHEETDATE
23
7 3 2 16 5 4
E
A
B
C
E
D
C
B
A
7 6 5 4
D
DEPARTMENT
SIZE
PROJECT DOCUMENT NUMBER REV
REVIEWER
DESIGNER
IN
IN
IN
IN
OUT
OUT
IN
OUT
OUT
OUT
OUT
OUT
OUT
OUT
OUT
IN
IN
IN
C



CPU1 TDI
CPU0 TDI
H:CPU1
CPU1 TDO
H:CPU0
L:BYPASS
L:BYPASS CPU0 TDO
Thu Aug 24 14:09:02 2023<NAME_2>
<NAME_1>
MB FABCGTI V02
174 OF 365
P V DD18_S 5_P 0
P V DD18_S 5_P 0
P V DD18_S 5_P 0
P V DD18_S 5_P 0
P V DD18_S 5_P 0
P V DD18_S 5_P 0
P V DD18_S 5_P 0
P V DD18_S 5_P 0
54
173
27
54
81
81
27
173
0
0
10%
5%
0
CHIP
JTA G _CP U1_R_TDI JTA G _CP U1_TDI
C0402
CHIP 5%
0JTA G _CP U0_R_TDI
0402LF
1K
1%
CHIP
1/16W
0402LF
1K
1%
CHIP
1/16W
0402LF
CHIP
1%
1K
1/16W
0402LF
1K
1%
CHIP
1/16W
JTA G _CP UX _TDO0
CHIP
JTA G _CP U0_TDO _CP U1_TDI_R1
JTA G _CP U0_B Y P A S S _R1
R6110 PLACE CLOSE TO U154
JTA G _CP UX _TDO _R
JTA G _CP U0_B Y P A S S
R6105 PLACE CLOSE TO U13
R6104 PLACE CLOSE TO U13
E MP TY
C0402
JTA G _CP U0_TDI
JTA G _CP U0_TDO _CP U1_TDI
C0402
0.1UF
16V
SMLF
S N74A UC2G 66DCTR SMLF
SMLF
SMLF
SMLF
JTAG - TDI/TDO
JTA G _CP U1_B Y P A S S
JTA G _CP U1_TDO
FM_P LD_CP U1_P RS NT_HDT_N
FM_P LD_CP U0_P RS NT_HDT_N
CP U1_HDT_B Y P A S S _S E L
CP U0_HDT_B Y P A S S _S E L
IC
IC
X 7R
IC
IC
X 7R
X 7R
IC
10%
10%
0.1UF
S N74A UC2G 66DCTR
S N74A UC2G 66DCTR
0.1UF
0.1UF
B S S 138K
B S S 138K
16V
16V
50V
16V
C0402
C0402
10%
0.01UF
10%
X 7R
JTA G _CP U0_TDO
IC
JTA G _CP UX _TDI
S N74A UC2G 66DCTR
SMLF
R6110
21R6105
21 R6104
G Q64
G Q63
2
1
C1523
2
1
C1522
21 R1651
8
43
65
7 2
1
U154
2
1
R1650
2
1
R1649
8
43
65
7 2
1
U14
2
1
C1521
8
43
65
7 2
1
U13
2
1
C1519
2
1
R1647
2
1
R1646
2
1 C1520
21 R1648
8
43
65
7 2
1
U153
S D
S D
CAD NOTE:
CAD NOTE:
CAD NOTE:
2B
1B
GND
VCC
2C
2A
1C
1A
2B
1B
GND
VCC
2C
2A
1C
1A
2B
1B
GND
VCC
2C
2A
1C
1A
2B
1B
GND
VCC
2C
2A
1C
1A
21
1
SHEETDATE
23
7 3 2 16 5 4
E
A
B
C
E
D
C
B
A
7 6 5 4
D
DEPARTMENT
SIZE
PROJECT DOCUMENT NUMBER REV
REVIEWER
DESIGNER
IN
OUT
IN
OUT
OUT
IN
IN
IN
C



Thu Aug 24 10:14:54 2023<NAME_2>
<NAME_1>
MB FABCGTI V02
175 OF 365
Blank
1
SHEETDATE
23
7 3 2 16 5 4
E
A
B
C
E
D
C
B
A
7 6 5 4
D
DEPARTMENT
SIZE
PROJECT DOCUMENT NUMBER REV
REVIEWER
DESIGNER
C



TBC
ADDRESS : 0XA2 (8-BIT) / 0X51 (7-BIT)
Thu Aug 24 14:09:32 2023<NAME_2>
<NAME_1>
MB FABCGTI V02
176 OF 365
1/16W
P 3V 3_A UX
P5V_AUX P5V_AUX
P 3V 3_A UX
P5V_AUX
P 3V 3_A UX
P 3V 3_A UX
P 3V 3_A UX
176
178
179
251
180
180
180
180
246178235
176178179251
179251176178
180
180
180
180
180
180
179251176178
180
180
SMB_USB_CPU0_HUB1_SDA
CHIP
1/16W
U SB3_H U B1_C YP
1/16W
EMPTY
USB_CPU0_HUB1_MODE_SEL0
USB_CPU0_HUB1_MODE_SEL1
U SB3_H U B1_C YP
1/16W
1%
USB3_HUB1_CYP
USB_CPU0_ADD_A2
1/16W
EMPTY
0402LF
10K
1%
USB3_HUB1_CYP
10K
1/16W
CHIP
1%
0402LF
USB3_HUB1_CYP
10K
1%
1/16W
CHIP
0402LF
0402LF
EMPTY
1%
0402LF
0402LF
USB3_CPU0_BMC_HUB1_TX_DN
USB2_CPU0_P0_HUB1_R_DP
USB2_CPU0_P0_HUB1_R_DN
C0805
X6S
20%
16V
22UF
USB3_HUB1_CYP
0
1/16W
USB_CPU0_HUB1_VBUS_DS
CYUSB3304-68LTXI
USB3_HUB1_CYP
USB3_HUB1_CYP
25V
X6S
C0402
1UF
USB3.0 EXT HUB MAIN(1/2)
0402LF
MISC
26MHZ
USB3_HUB1_CYP
USB3_HUB1_CYP
0402LF
1/16W
0402LF
0402LF
1/16W
USB3_HUB1_CYP
USB3_CPU0_BMC_TX_C1_DP
U SB3_H U B1_C YP
RST_USB_CPU0_HUB1_R_N
10%
USB3_HUB1_CYP
C0402
1% CHIP1/16W
33.2
RST_USB_HUB_N
USB3_HUB1_CYP
XTAL_USB_CPU0_HUB1_XOUT
SMLF
USB3_HUB1_CYP
10K
1%
10K
USB3_HUB1_CYP USB3_HUB1_CYP
10K
1%
CHIP
0402LF 0402LF
CHIP
1/16W
1%
0402LF
CHIP
1%
SMB_USB_CPU0_HUB1_SDA
SMB_USB_CPU0_HUB1_SCL
USB3_HUB1_CYP
6.04K
10K
1%
1/16W
CHIP
TP_CPU0_USB_HUB1_SUSPEND
CHIP
USB3_CPU0_BMC_TX_C1_DN
USB3_CPU0_BMC_RX_HUB1_DP
USB3_CPU0_BMC_RX_HUB1_DN
USB2_CPU0_P0_R1_DPCHIP
USB3_HUB1_CYP
USB_CPU0_HUB1_VBUS_US
USB3_HUB1_CYP
10K
1%
10K
0402LF
0402LF
1/16W
CHIP
1%
IC
USB3_CPU0_BMC_HUB1_TX_DP
15PF
0402
USB2_CPU0_P0_R1_DN
IC
1/16W
SMLF
USB_CPU0_HUB1_RREF_SS200
1%
CHIP
1/16W
USB_CPU0_HUB1_RREF_USB2
U SB3_H U B1_C YP
5%
C0G
50V
PU_CPU0_USB_HUB_RESERVED1
PU_CPU0_USB_HUB_RESERVED2
12PF
50V
C0G
5%
XTAL_USB_CPU0_HUB1_XIN
10K
1%
0402LF
0402LF
EMPTY
1/16W
0.1%
47K
CHIP
0402LF
5%
0402
10%
X7R
50V
470PF
USB3_HUB1_CYP
U SB3_H U B1_C YP
10K
1%
E MP TY
0402
X 7R
10%
25V SMLF
0.1UF
PU_CPU0_USB_HUB_OVRCURR
PU_CPU0_USB_HUB_PWR_EN
0402LF
SMB_USB_CPU0_HUB1_SCL
33.2 E MP TY
USB3_HUB1_CYP
1%
1%33.2
1%
1/16W
E MP TY
USB3_HUB1_CYP
10K
U SB3_H U B1_C YP
1/16W
10K
U SB3_H U B1_C YP
10K
EMPTY
1/16W
1%
USB3_HUB1_CYP
1%
1/16W
CHIP
USB_CPU0_ADD_A0
USB_CPU0_ADD_A1
USB3_HUB1_CYP
USB3_HUB1_CYP0402LF
1K
PD_USB_CPU0_WP
SMB_U SB_C PU 0_H U B1_SD A_R 2
SMB_U SB_C PU 0_H U B1_SC L_R 2
USB3_HUB1_CYP
E MP TY
1/16W
1%
10K
USB3_CPU0_BMC_RX_C1_DP
USB3_CPU0_BMC_RX_C1_DN
USB3_HUB1_CYP
M24128-BWMN6TP
USB3_HUB1_CYP
0402LF
10K
CHIP
0402LF
1%
0402LF
10K
EMPTY
1/16W
U SB3_H U B1_C YP
U SB3_H U B1_C YP
10K
CHIP
0402LF
1%
1/16W
0402LF
EMPTY
10K
U SB3_H U B1_C YP
1/16W
1%
R6227 R6226
R6224
R6225
R4452
R6216R6214
C6083
R6220R6218
R6217
C6028C6027R4450
C2317
7
4
8
5
6 3
2
1
3 1
4 2
54
55
17 18
6
5
9
8
57
58
20
2
26
31
22
21
29
30
25
24
23
33
32
40
TH
11
12
15
14
67
68
38
39
35
36
65
64
41
42
45
44
62
63
47
48
51
50
60
59
U6003
Y9
U6001
E0
E1
E2
VSSSDA
SCL
WC#
VCC
X2
G2 G1
X1
1/2
EPAD
RESERVED1
RESERVED2
RESET#
OVRCURR
PWR_EN
NC_25
RREF_USB2
RREF_SS
US_TXM
US_TXP
US_RXM
US_RXP
US_DM
US_DP
VBUS_US
GND
MODE_SEL1
MODE_SEL0
XTL_OUT
XTL_IN
SUSPEND
I2C_DATA
I2C_CLK
VBUS_DS
DS4_TXM
DS4_TXP
DS4_RXM
DS4_RXP
DS4_DM
DS4_DP
DS3_TXM
DS3_TXP
DS3_RXM
DS3_RXP
DS3_DM
DS3_DP
DS2_TXM
DS2_TXP
DS2_RXM
DS2_RXP
DS2_DM
DS2_DP
DS1_TXM
DS1_TXP
DS1_RXM
DS1_RXP
DS1_DM
DS1_DP
MODE SEL GPIO.RREF.PWR & OVRCUR UP STREAM
DOWN STREAM
I2CCLOCK & RESET
2
1 C93
2
1
2
1 C91
2
1
2
1
R6215
2
1
2
1
R6213
2
1
2
1
21
21
2
1
R6223
2
1
2
1
2
1
2
1
2
1
R6221
2
1
R6219
2
1
R6222
2
1
R6209
2
1
R6208
2
1
R6207
2
1
R6206
2
1
R6205
2
1
R6204
21R6203
21R6202
2
1
2
121
2
1
2
1
21R4451
1
SHEETDATE
23
7 3 2 16 5 4
E
A
B
C
E
D
C
B
A
7 6 5 4
D
DEPARTMENT
SIZE
PROJECT DOCUMENT NUMBER REV
REVIEWER
DESIGNER
BI
BI
IN
BI
OUT
OUT
BI
IN
IN
IN
BI
BI
IN
IN
IN
OUT
OUT
R4453
C



Thu Aug 24 14:09:32 2023<NAME_2>
<NAME_1>
MB FABCGTI V02
177 OF 365
P 3V 3_A UX _CP U0_US B _A V DD33
P 1V 2_A UX
P 1V 2_A UX
P 1V 2_A UX
P 3V 3_A UX
P 1V 2_CP U0_US B _DV DD12
P 1V 2_A UX
USB3_HUB1_CYP
C0402
X6S
25V
10%
1UF
USB3_HUB1_CYP
0.1UF
25V
10%
X7R
0402
10%
X 7R
0.01UF
50V
X 7R
10%
C0402USB3_HUB1_CYP
50V
10%
X 7R
0.001UF
USB3_HUB1_CYP
0.01UF
50V
X 7R
C0402
10%
C0402USB3_HUB1_CYP
0.001UF
50V
10%
X 7R
USB3_HUB1_CYP
0.01UF
50V
10%
USB3_HUB1_CYP
0.001UF
10%
0.01UF
50V
10%
X 7R
C0402USB3_HUB1_CYP
C0402
X 7R
C0402
0.001UF
10%
50V
X 7R
USB3_HUB1_CYP
X 7R
10%
50V
0.01UF
C0402
X 7R
10%
50V
0.01UF0.001UF
C0402
X 7R
50V
10%
USB3_HUB1_CYP
USB3_HUB1_CYP
50V
10%
0.01UF
C0402
X 7R
C0402
0.01UF
10%
X 7R
USB3_HUB1_CYP
50V
0.001UF
X 7R
50V
C0402
10%
USB3_HUB1_CYP
USB3_HUB1_CYP
50V
0.001UF
C0402
10%
X 7R
0.01UF
50V
X 7R
10%
C0402
USB3_HUB1_CYP
X 7R
0.001UF
50V
10%
C0402
USB3_HUB1_CYP
0.01UF
10%
X7R
C04020402
0.01UF
25V
10%
X7R
USB3_HUB1_CYP
10%
25V
X6S
1UF
X6S
10%
25V
C0402
USB3_HUB1_CYP
22UF
C0603
6.3V
20%
X6S
X7R
10%
50V
U SB3_H U B1_C YP
X7R
USB3_HUB1_CYP
U SB3_H U B1_C YP
USB3_HUB1_CYP
X 7R
10%
25V
0.1UF 0.01UF
C0402
USB3_HUB1_CYP
X 7R
U SB3_H U B1_C YP
0402
USB3_HUB1_CYP
C0402
0.01UF
25V
0.1UF
10%
50V
0.1UF
X7R
50V
0.1UF
C0402
USB3_HUB1_CYPUSB3_HUB1_CYP
X7R
25V
1UF
X6S
10%
BLM21PG221SN1D
USB3_HUB1_CYP
USB3.0 EXT HUB MAIN(2/2)
C0402
X 7R
C0402
50V
10%
X 7R
25V
10%
1UF
X6S
50V
IND
0.01UF
C0402
SMLF
IC
CYUSB3304-68LTXI
IND
SMLF
6.3V
22UF
C0603
X6S
20%
USB3_HUB1_CYP
USB3_HUB1_CYP
0402
10%
C0402
USB3_HUB1_CYP
25V
10%
X 7R
25V
0.1UF
10%
0.01UF
0.01UF
50V
X 7R
10%
10%
25V
USB3_HUB1_CYP
USB3_HUB1_CYP
0402 C0402
X 7R
10%
X 7R
0.01UF
50V
USB3_HUB1_CYP
0402
10%
50V
BLM21PG221SN1D
SMLF
10%
X7R
C0402
U SB3_H U B1_C YP
22UF
6.3V
20%
C0402
1UF
U SB3_H U B1_C YP
0402
X7R
0.1UF
10%
25V
U SB3_H U B1_C YP
0402
X6S
C0603
0402
10%
25V
X7R
0.1UF
USB3_HUB1_CYP U SB3_H U B1_C YP
C0402
0.01UF
10%
X7R
50V
10%
X7R
25V
0.1UF
0402
USB3_HUB1_CYP
50V
C0402
X7R
10%
USB3_HUB1_CYP
0.1UF
USB3_HUB1_CYP
50V
X 7R
10%
50V
C0402
0.001UF
USB3_HUB1_CYP
USB3_HUB1_CYP C0402
USB3_HUB1_CYP
0.1UF
0402
X7R
10%
25V
USB3_HUB1_CYP
10%
25V
X6S
1UF
USB3_HUB1_CYP
C0402
22UF
6.3V
20%
X6S
C0603
USB3_HUB1_CYP
50V
X 7R
10%
0.001UF
C0402
0.01UF
USB3_HUB1_CYP
0402
0.1UF
U SB3_H U B1_C YP
X7R
C0402
USB3_HUB1_CYP
X6S
20%
6.3V
22UF
C0603
USB3_HUB1_CYP
USB3_HUB1_CYP
25V
10%
USB3_HUB1_CYP
USB3_HUB1_CYP
C0402
50V
0.01UF
C0402
USB3_HUB1_CYP
C6067 C6071 C6073 C6075C6069
C6062C6060C6058C6056C6054
C6037C6036C6032 C6033 C6034 C6035
21
21
28
19
43
37
13
7
49
27
3
1
66
61
56
4
53
52
46
34
16
10
L6001
L6000
U6001
1 2
1 2 2/2
AVDD12_5
AVDD12_4
AVDD12_3
AVDD12_2
AVDD12_1
VDD_IO
AVDD33_4
AVDD33_3
AVDD33_2
AVDD33_1
DVDD12_7
DVDD12_6
DVDD12_5
AVDD12_6
DVDD12_4
DVDD12_8
DVDD12_3
VDD_EFUSE
DVDD12_2
DVDD12_1
AVDD_CLK AVDD_RX
VDD_IOAVDD33
AVDD_TX
DVDD12
2
1
2
1
2
1
2
1
2
1
2
1
2
1
2
1
2
1
2
1
2
1
2
1
2
1
2
1
2
1
2
1
2
1
2
1
2
1
2
1
2
1
2
1
2
1
2
1
2
1
2
1
2
1
2
1
2
1
2
1
2
1
2
1
2
1
2
1
2
1
2
1
2
1
2
1
2
1
2
1
2
1
2
1
2
1
2
1
2
1
2
1
2
1
2
1
2
1
2
1
2
1
2
1
2
1 C6040
1
SHEETDATE
23
7 3 2 16 5 4
E
A
B
C
E
D
C
B
A
7 6 5 4
D
DEPARTMENT
SIZE
PROJECT DOCUMENT NUMBER REV
REVIEWER
DESIGNER
C6082C6081C6080
C6068 C6070 C6072 C6074 C6076
C6077 C6078 C6079
C6066C6065C6064
C6063C6061C6059C6057C6055
C6038 C6039
C6031C6030
C6052 C6053C6051C6050C6049C6048
C6047C6046
C6045C6044C6043C6042
C6041
C



MFR:TI
MFR PN:TUSB8042AIRGCR
QPN:AL008042000 3RD2ND
QPN:AL005734000
MFR PN:USB5734T/M
MFR:MRP
Thu Aug 24 14:09:34 2023<NAME_2>
<NAME_1>
MB FABCGTI V02
178 OF 365
USB3_HUB2_TI
P1V2_CPU0_USB2_DVDD12
P 3V 3_A UX
P 3V 3_A UX
P 3V 3_A UX _CP U0_US B 2_A V DD33
P1V2_CPU0_USB2_DVDD12
P 3V 3_A UX
P1V2_CPU0_USB2_DVDD12
P 3V 3_A UX
P1V2_CPU0_USB2_DVDD12
P 3V 3_A UX
P 3V 3_A UX
P 3V 3_A UX
P 3V 3_A UX
P 3V 3_A UX
P 3V 3_A UX
P5V_AUX
P 3V 3_A UX P 3V 3_A UX
P 3V 3_A UX
P1V2_CPU0_USB2_DVDD12
P 3V 3_A UX _CP U0_US B 2_A V DD33
180
180
180
180
180
180
178
246176
178235
180
180
180
180
178
180
246
176
178
235
180
179251
176
176179251
CHIP
SMLF
TUSB8042AIRGCR
USB3_HUB2
U SB_H U B2_TI_U SB_VBU S_MR P_R ESET_N
USB3_HUB2_TI
USB3_HUB2_MRP
USB3_HUB2_MRP
1/16W
U SB_H U B2_TI_U SB_R 1_MR P_R BIAS
12K
1%
0402LF
CHIP
USB3_CPU0_BMC_HUB2_TX_DP
USB3_CPU0_BMC_HUB2_TX_DN
0
5% 0402LF
CHIP
0
USB_HUB2_TI_USB_DP_DN3_MRP_VDD12
USB_HUB2_TI_USB_SSRXM_DN3_MRP_VDD12
USB3_CPU0_BMC_RX_C2_DN
USB3_CPU0_BMC_RX_C2_DP
USB2_CPU0_P0_HUB2_R_DN
USB2_CPU0_P0_HUB2_R_DP
USB_HUB2_MRP_CFG_STRAP
0402LF
0402LFUSB_HUB2_TI_USB_SSRXP_DN1_MRP_VDD12
USB3_HUB2_MRP
USB_HUB2_TI_USB_DP_DN1_MRP_CFG_STRAP
USB3_HUB2_MRP
CHIP
USB3_HUB2_MRP
CHIP
0402LF
U SB3_H U B2_MR P
U SB3_H U B2_MR P
US B 3_HUB 2_TI
USB_HUB2_TI_NC_MRP_ATEST
0402LF
CHIP0402LF
U SB3_H U B2_MR P
0402LF
U SB3_H U B2_TI
E MP TY
0402LF
US B 3_HUB 2_TI
0402LF CHIP
5%
CHIP
5%
1/16W
0
0402LF
0 5%
U SB_H U B2_TI_OVER C U R 3_MR P_C FG_BC _EN
USB_HUB2_TI_OVERCUR2_MRP_PROG_FUNC5
5%
CHIP
USB3_HUB2_TI
10K
1UF
0402LF
1%
0402LF
1%
10K
CHIP
U SB3_H U B2_TI
0402LF
U SB3_H U B2_TI
USB3_HUB2_TI
0402LF
CHIP
U SB_H U B2_TI_OVER C U R 1
CHIP
5%0
U SB3_H U B2_MR P
5%
EMPTY
10K
1/16W
CHIP
5%
0
RST_USB_HUB_N
10%
U SB3_H U B2_MR P
U SB3_H U B2_MR P
0402LF
25V
X6S
CHIP
5%
0402LF
0
US B 3_HUB 2_TI
47K
USB3_HUB2_TI
E MP TY
1/16W
0.1%
1%
E MP TY
0402LF
U SB_H U B2_TI_GR STZ_MR P_PR OG_FU N C 1
0402LF
4.7K
1/16W
0402LF
1%
USB3_HUB2_TI
US B 3_HUB 2_TI
U SB_H U B2_TI_PW R C TL_POL
U SB3_H U B2_MR P
5%0
1K
1/16W
USB3_HUB2_MRP
U SB3_H U B2_TI
0402LF
USB3_CPU0_BMC_TX_C2_DP
USB3_CPU0_BMC_RX_HUB2_DN
USB3_CPU0_BMC_RX_HUB2_DP
USB2_CPU0_P0_R2_DN
CHIP
IC
USB3.0 EXT HUB 2ND(1/2)
USB_HUB2_TI_NC_MRP_ATEST
5%
0402LF
1/16W
CHIP
9.53K
1%
0
0
90.9K
1/16W
CHIP
1%
10K
1%
CHIP
0402LF
1/16W
5%0
X 6S
10%
10UF
16V
5%0
5%0
1%
4.7K
1/16W
0402LF
1/16W
CHIP
1%
4.7K
4.7KCHIP
0402LF
1%
10K
CHIP
200K
1%
1/16W
CHIP
0402LF
5%
CHIP
0 CHIP5% 0402LF
0 CHIP0402LF
0
0
0402LF
200K
1/16W
1%
CHIP
200K
EMPTY
1%
1/16W
0402LF
USB2_CPU0_P0_R2_DP
0
RST_USB_HUB_N
10K
1%
47K
0402LF
EMPTY
0.1%
1/16W
EMPTY
USB_HUB2_MRP_RESET_N
U SB3_H U B2_MR P
U SB3_H U B2_MR P
0402LF
C0805
CHIP
US B 3_HUB 2_TI
CHIP
10K
0402LF
USB3_HUB2_MRP
CHIP0402LF5%
1K
0402LF
1%
1/16W
USB_HUB2_TI_USB_VBUS
U SB3_H U B2_MR P
U SB3_H U B2_TI
1%
0402LF
US B 3_HUB 2_TI
CHIP
0402LF
1/16W
EMPTY
USB_HUB2_MRP_VBUS_DET
U SB3_H U B2_MR P
CHIP
1%
10K
0402LF
1/16W
USB3_CPU0_BMC_TX_C2_DN
USB_HUB2_TI_PWRCTL_POL_MRP_VBUS_DETCHIP
0
CHIP
5%
US B 3_HUB 2_TI
C0402
0402LF
1%10K
SMB_USB_CPU0_HUB1_SCL
0402LF
USB_HUB2_TI_OVERCUR2
5% CHIP
1/16W
1/16W
CHIP
5% 0402LF
0
U SB_H U B2_TI_OVER C U R 1_MR P_PR OG_FU N C 4
5%
CHIP
0
US B 3_HUB 2_TI
0402LF
SMB_USB_CPU0_HUB1_SDA
0
0402LF
CHIP
EMPTY
200K
0402LF
USB_HUB2_TI_OVERCUR3
US B 3_HUB 2_TI
USB3_HUB2_MRP
1/16WUSB3_HUB2_MRP
USB_HUB2_MRP_CFG_BC_EN
USB3_HUB2_MRP
5%0
1%
0402LF
US B 3_HUB 2_TI
CHIP
0402LF
CHIP
1/16W
U SB3_H U B2_MR P
USB_HUB2_TI_OVERCUR4_MRP_I2C_SLV_CFG1
USB_HUB2_TI_OVERCCUR4
U SB3_H U B2_MR P
US B 3_HUB 2_TI
USB3_HUB2_MRP
1%
U SB3_H U B2_MR P
USB_HUB2_TI_PWRCTL2_MRP_VDD12
USB_HUB2_TI_PWRCTL3_MRP_VDD33
10K
1%
CHIP
0402LF
USB_HUB2_MRP_I2C_SLV_CFG1
USB_HUB2_MRP_PROG_FUNC6
U SB_H U B2_TI_TEST
U SB_H U B2_TI_TEST_MR P_PR OG_FU N C 6
USB_HUB2_TI_USB_DM_DN3_MRP_VDD33
0
USB3_HUB2_MRP
5%
5%
USB3_HUB2_MRP
5%
USB3_HUB2_MRP
0402LF
USB3_HUB2_MRP
USB_HUB2_TI_USB_SSRXM_DN4_MRP_VDD12
R6329
R6320
R6289
R6298 R6297
R6301
R6302
R6303
C6089
R6315
R6318
R6319
R6325
R6328 R6333
R6272
R6273
R6327
R6326
48
55
26
19
11
3
56
27
20
12
4
58
29
22
14
6
59
30
23
15
7
64
53
24
17
9
1
54
25
18
10
2
TH49
41
32
33
35
36
43
44
47
46
60
50
U6002
1/2
NC_1 USB_R1
TEST
OVERCUR4z
OVERCUR3z
OVERCUR2z
OVERCUR1z
GRSTz
PWRCTL_POL
PWRCTL4||BATEN4
PWRCTL3||BATEN3
PWRCTL2||BATEN2
PWRCTL1||BATEN1
USB_VBUS
USB_SSTXM_DN4
USB_SSTXP_DN3
USB_DM_DN2
USB_SSTXM_DN1
USB_SSTXP_DN1
USB_SSRXM_DN1
USB_DP_DN1
USB_SSTXM_UP
USB_DP_UP
TH_VSS
USB_SSRXP_DN3
USB_SSRXM_DN4
USB_SSRXP_DN4
USB_DM_DN4
USB_DM_DN1
USB_SSTXP_DN4
USB_SSRXP_DN1
USB_DP_DN2
USB_SSRXP_UP
USB_DP_DN3
USB_DP_DN4
USB_SSRXM_DN3
USB_DM_UP
USB_SSTXP_UP
USB_SSTXM_DN3
USB_DM_DN3
USB_SSTXM_DN2
USB_SSTXP_DN2
USB_SSRXP_DN2
USB_SSRXM_DN2
USB_SSRXM_UP
2
1
2
1
2
1
R6332
2
1
R6331
21R6312 21R6310
21R6311
2
1R6288
2
1R6287
2
1
21R6286
21
R6285
21
2
1
2
1
21R6296
21R6295
21 R6300
21 R6299
2
1
2
1
2
1
21R6259
21R6258
21R6263
21R6264
21R6268
2
1
21R6270
2
1
21R6313
21R6314
21R6266
21R6261
21
R6322
2
1R6321
2
1
C6088
21R6317
2
1
2
1
21R6316
21R6324
2
1
21R6323
21
2
1
2
1
2
1
21R6271
2
1
2
1
1
SHEETDATE
23
7 3 2 16 5 4
E
A
B
C
E
D
C
B
A
7 6 5 4
D
DEPARTMENT
SIZE
PROJECT DOCUMENT NUMBER REV
REVIEWER
DESIGNER
BI
BI
IN
OUT
IN
IN
IN
IN
OUT
OUT
BI
BI
BI
BI
BI
IN
IN
IN
R6330
C



XTAL:
MFR PN:USB5734T/MMFR PN:TUSB8042AIRGCR
3RD
QPN:AL005734000
2ND
MFR:TI MFR:MRP
QPN:AL008042000
TI=24MHZ
MRP=25MHZ
Thu Aug 24 14:09:33 2023<NAME_2>
<NAME_1>
MB FABCGTI V02
179 OF 365
P 3V 3_A UX _CP U0_US B 2_A V DD33P 3V 3_A UX
P 3V 3_A UX
P 1V 2_CP U0_US B 2_DV DD12P 1V 2_A UX
P 3V 3_A UX
P 3V 3_A UX
P 3V 3_A UX
P 3V 3_A UX _CP U0_US B 2_A V DD33
P 3V 3_A UX
P 3V 3_A UX
P 3V 3_A UX
P1V2_CPU0_USB2_DVDD12
P 3V 3_A UX _CP U0_US B 2_A V DD33
U SB3_H U B2_MR P
USB3_HUB2
USB3_HUB2
USB3_HUB2
0402LF
SMLF
24MHZ
USB3_HUB2
5%
50V
0402LF
0402
MISC
1/16W
XTAL_USB_CPU0_HUB2_XIN
XTAL_USB_CPU0_HUB2_XOUT
50V
27PF
5%
NPO
10
1/16W
0402LF
CHIP
1%
BLM21PG221SN1D
179
EMPTY
1K
U SB3_H U B2_MR P
U SB_H U B2_TI_H S_SU SPEN D
0402LF
176178251
251176178
179
1%
CHIP
1M
USB3_HUB2
U SB_H U B2_MR P_C FG_N ON _R EM
USB3.0 EXT HUB 2ND(2/2)
USB3_HUB2
US B 3_HUB 2
C0402
USB3_HUB2USB3_HUB2US B 3_HUB 2
USB3_HUB2
25V
0.1UF 10UF 50V 50V
0402
0.01UF
0.05P
COGX6SX7R
10% 10%
X7R
10%
X 7R
C0402
USB3_HUB2
50V 50V
25V
1PF
USB3_HUB2
1PF
COG X 7R
50V
10%
C0402
10%
X7R
25V
10%
0402
COG
0.1UF0.01UF
50V
USB3_HUB2
0.01UF
C0402
X7R
0.05P0.05P
US B 3_HUB 2US B 3_HUB 2
0402
10%
X7R
C0402
0.01UF
50V 25V 50V
USB3_HUB2
0.05P 10%10%0.05P10%
25V
0.1UF
10%
10UF
25V
0.05P
50V
1PF
US B 3_HUB 2
C0402 C0402 0402
X 7R
X7R
1PF
0402
10%
0.1UF
50V
USB3_HUB2USB3_HUB2
0.01UF 1PF
C0402
USB3_HUB2US B 3_HUB 2
50V
C0402
X6S
U SB3_H U B2
C0805
10%
USB3_HUB2
BLM21PG221SN1D
USB3_HUB2_TI
0
1/16W
1%
EMPTY
0402LF
10K
CHIP
1%
1/16W
USB_HUB2_TI_VDD33_MRP_PRT_CTL4_GANGPWR E MP TY
U SB3_H U B2_MR P
U SB3_H U B2_MR P
1%
1/16W
0402LF
E MP TY
10K
1/16W
1%
0402LF
10K
USB3_HUB2_TI
0
USB3_HUB2_TI
5%
USB3_HUB2_TI
0
USB_HUB2_TI_VDD_MRP_USB3DN_RXDP4
USB_HUB2_TI_VDD_MRP_USB3DN_TXDP4
USB_HUB2_TI_VDD_MRP_USB3DN_RXDM1
5%U SB_H U B2_TI_VD D _MR P_U SB3D N _TXD M1
0
C0402
10%
SMLF
IND
IND
SMLF
1UF
10%
X 7R
25V
X7R
0402
X 7R
C0402
X 7RCOG
0.01UF1PF
X7RX 7RCOG
C0402C0402
COG
0402
X 7R
C0402C0402
COG
0402C0402
0.05P
C0402
0.1UF
0402
25V
X7R
10%
C0402
X 7R
10%
C0402C0805
4.7K
1/16W
CHIP
1%
0402LF
EMPTY
1%
4.7K
0 5%
5%
0
CHIP
0 5%
5%0 CHIP0402LF
0 5%
5% 0402LF0
CHIP
1%
0402LF
1%
0
0402LF5%
CHIP
1%
0402LF
0 5%
CHIP
0
U SB3_H U B2_TI
200K
SMB_USB_CPU0_HUB1_SDA
1/16W
5%
0402LF
0402LF
1/16W
SMB_USB_CPU0_HUB1_SCL
5% 0402LF
CHIP
USB3_HUB2_TI
200K
US B 3_HUB 2_TI
CHIP
CHIP0402LF
USB3_HUB2_MRP
1K
1%
U SB3_H U B2_TI
USB_HUB2_TI_FULLPWRMGMTZ_MRP_PROG_FUNC3
EMPTY
U SB3_H U B2_TI
USB3_HUB2_TI
USB3_HUB2_TI
0402LF CHIP
USB_HUB2_TI_VDD_MRP_USB3DN_TXDP3
0402LF CHIP
0402LF
0402LF5%
USB_HUB2_TI_VDD33_MRP_PROG_FUNC7 0402LF
0402LF0 5%
USB3_HUB2_TI
CHIP
CHIP
CHIP
USB3_HUB2_TI
USB_HUB2_MRP_PRT_CTL4_GANGPWRUSB3_HUB2_MRP
1K
0402LF
1%
4.7K
0402LF
CHIP
1/16W
USB3_HUB2_TI
USB3_HUB2_TICHIP
USB3_HUB2_TI
SMB_USB_HUB2_TI_SDA_MRP_PRT_CTL2
SMB_USB_HUB2_TI_SCL_MRP_PRT_CTL1
U SB_H U B2_TI_H S_SU SPEN D _MR P_C FG_N ON _R EM
IC
TUSB8042AIRGCR
USB3_HUB2
SMLF
USB_HUB2_TI_GANGED_MRP_I2C_SLV_CFG0
USB_HUB2_TI_GANGED
1/16W
1PF
0.05P
COG
X6S
USB3_HUB2
25V
10%
50V50V
USB3_HUB2
USB3_HUB2_MRP
COG
0.01UF
CHIP
0.01UF
50V50V
USB3_HUB2
USB_HUB2_MRP_I2C_SLV_CFG0
0.1UF
25V
0.1UF
10%0.05P
1PF
USB3_HUB2 USB3_HUB2 USB3_HUB2
0.1UF
25V
USB3_HUB2
10%
50V
1PF
USB3_HUB2 USB3_HUB2
50V
0.01UF
USB3_HUB2
0.1UF
25V
USB3_HUB2
10%
50V
USB3_HUB2_MRP
US B 3_HUB 2
USB3_HUB2_TI
US B 3_HUB 2_TI
0402LF
USB_HUB2_TI_SMBUSZ_MRP_PROG_FUNC2
1K
1%
1/16W
1/16W
EMPTY
EMPTY
1/16W
0402LF
USB_HUB2_TI_GANGED_MRP_I2C_SLV_CFG0
NPO
0402LF
USB3_HUB2_TI
27PF
0402
R6284
R6257
R6309
R6307
R6306
R6308
R6281
R6282
R6277
R6278
R6294
R6292
R6283
C6119 C6120 C6121C6115 C6116 C6117C6112 C6113 C6114C6109 C6110 C6111C6106 C6107 C6108
C6103 C6104C6100 C6101C6097 C6098C6093 C6095C6094
X I
X O
V DD_31
V DD_21
V DD_57
V DD_5
V DD_8
A UTOENz||HS_SUSPEND
V DD_51
V DD33_63
SM BUSz||SS_SUSPEND
SCL||SM BCLK
GA NGED||SM BA 2||HS_UP
FULLPWRM GM Tz||FULLA UTOz||SM BA 1||SS_UP
V DD33_52
V DD33_34
V DD33_16
V DD_28
SDA ||SM BDA T
V DD_13
3 1
4 2
61
57
51
31
28
21
13
8
5
63
52
34
16
39
37
42
40
45
21
21
62 38
Y6000
U6002
C6118C6105
L6004
L6003
1 2
1 2
X2
G2 G1
X1
2/2
2
1
2
1
2
1
21R6260
21
2
1
2
1
2
1
2
1
21R6304
21R6305
21
R6279
21
R6280 21R6265
21R6274
2
1
2
1
21R6269
21R6262
21R6275 2
1
21R6276
2
1
21R6267
2
1
2
1
2
1
21R6290
21R6291
2
1
2
1
2
1
2
1
2
1
2
1
2
1
2
1
2
1
2
1
2
1
2
1
2
1
2
1
2
1
2
1
2
1
2
1
2
1
2
1
2
1
2
1
2
1
2
1
2
1 C6096
2
1
2
1
2
1
2
1
2
1
2
1 C6092
1
SHEETDATE
23
7 3 2 16 5 4
E
A
B
C
E
D
C
B
A
7 6 5 4
D
DEPARTMENT
SIZE
PROJECT DOCUMENT NUMBER REV
REVIEWER
DESIGNER
OUT
IN
BI
BI
C6091C6090
R6293
C6102C6099
C



TO 2ND HUB
FROM 2ND HUB
TO 1ST HUB
FROM CPU
TO 2ND HUB
TO 1ST HUB TO SCM
TO CPU
TO SCM
FROM CPU
FROM 2ND HUB
FROM SCM
FROM 1ST HUB
FROM 2ND HUB
TO 2ND HUB
FROM 1ST HUB
TO 1ST HUB
FROM 1ST HUB
Thu Aug 24 14:09:33 2023<NAME_2>
<NAME_1>
MB FABCGTI V02
180 OF 365
1%
1/20W
EMPTY
0201LF
49.9
1/20W
EMPTY
49.9
0201LF
1%
49.9
0201LF
1/20W
EMPTY
1% 1%
1/20W
EMPTY
0201LF
49.9
49.9
1/20W
0201LF
1%
EMPTY
0201LF
1/20W
EMPTY
1%
49.9
176
176
176
176
176
178
178
178
150
150
176
178
178
150
178
150
178
178
178
178
176
176
29
176
176
29
29
29
29
150
150
29176
176
178
178
USB3_CPU0_BMC_HUB1_TX_DP
USB3_CPU0_BMC_HUB1_TX_DN
USB3_HUB2
USB3_HUB2
25V0.1UF
10%
USB3_HUB1
US B 3_HUB 1
0402
X7R25V0.1UF
C6023/C6025 C6024/C6026 CO-LAYOUT
USB3_HUB2
USB3_HUB2
USB3_HUB1
USB2_CPU0_P0_HUB1_R_DP
USB3_HUB1
CHIP
1/20W
0
USB3_CPU0_BMC_RX_C1_DP
USB3_CPU0_BMC_RX_C1_DN
USB3_CPU0_BMC_RX_C2_DP
DIFF BUS_0.33UF
DIFF BUS_0.33UF
DIFF BUS_0.33UF
DIFF BUS_0.33UF
10%
C6019/C6021 C6020/C6022 CO-LAYOUT
USB3_HUB2
USB3_CPU0_BMC_HUB2_TX_DP
USB3_CPU0_BMC_HUB2_TX_DN
USB3_CPU0_BMC_TX_BUF_C_DN
USB3_CPU0_BMC_TX_BUF_C_DP
CHIP 0201LF
0201LF
USB2_CPU0_P0_HUB1_R_DN
0USB2_CPU0_P0_HUB2_R_DP
USB2_CPU0_P0_HUB2_R_DN
USB3_HUB2
USB3_HUB2
USB3_CPU0_BMC_RX_DN
USB3_CPU0_BMC_RX_C2_DN
USB3_HUB1
USB3_HUB1
C0402
6.3VX6S
USB3_CPU0_BMC_RX_DP
0201LF
0201LF
USB2_CPU0_P0_R2_DN
USB2_CPU0_P0_R2_DP
USB3_CPU0_BMC_TX_C2_DN
USB3_CPU0_BMC_TX_C2_DP
USB3_CPU0_BMC_TX_C1_DN
USB3_CPU0_BMC_TX_C1_DP
USB2_CPU0_P0_DN
USB2_CPU0_P0_R1_DP
USB2_CPU0_P0_R1_DN
5%
0
1/20W
USB3_CPU0_BMC_RX_HUB_C_DN
USB3.0 EXT HUB USB SIGNAL SELECT
0402LF
51
1/16W
EMPTY
5%
0402LF
1/16W
EMPTY
5%
51
USB2_CPU0_P0_DP
0201LF
USB3_CPU0_BMC_TX_DP
USB3_CPU0_BMC_TX_DN
R6194/R6196 R6195/R6197 CO-LAYOUT
0 USB2_HUB_EXT_DN
USB2_HUB_EXT_DP
0
CHIP
5%
0201LF
0201LFCHIP
USB3_CPU0_BMC_RX_HUB_C_DP
DIFF BUS_0.33UF
DIFF BUS_0.33UF
6.3V 10%
C0402
X6S
USB3_CPU0_BMC_RX_HUB1_DP
C6015/C6017 C6016/C6018 CO-LAYOUT
USB3_HUB1
USB3_CPU0_BMC_RX_HUB1_DN
USB3_HUB1
0.1UF
0402 10%
USB3_HUB2
USB3_CPU0_BMC_RX_HUB2_DN
USB3_CPU0_BMC_RX_HUB2_DP
USB3_HUB2
X7R25V
CHIP
0
0
USB3_HUB1
CHIP
CHIP
0201LF
CHIP
R6190/R6192/R339 R6191/R6193/R340 CO-LAYOUT
0
USB3_HUB1
USB3_HUB2
USB3_HUB2
C6003/C6013/R341 C6004/C6014/R342 CO-LAYOUT
0402
0.1UF 25V X7R
10%
USB3_HUB1
25V0.1UF
USB3_HUB1
USB3_HUB2
21
21
21
21
21
21
C6017
C6018
C6003
C6004
C6013
C6014
C6026
C6025
C6024
C6023
21
21
21
21 21
21
C6022
C6021
C6020
C6019 C6016
C6015
CAD NOTE:
CAD NOTE:
CAD NOTE:
CAD NOTE:
CAD NOTE:
CAD NOTE:
21
21
2
1
2
1
R341
21
21
21
21
21
21
21
21
2
1
2
1
2
1
2
1
2
1
2
1
R339
21R6197
21R6196
21R6194
21R6195
21R6190
21R6191
21R6193
21R6192
1
SHEETDATE
23
7 3 2 16 5 4
E
A
B
C
E
D
C
B
A
7 6 5 4
D
DEPARTMENT
SIZE
PROJECT DOCUMENT NUMBER REV
REVIEWER
DESIGNER
IN
IN
IN
IN OUT
OUT
IN
IN
OUT
OUT
OUT
OUT
BI
BI
BI
BI
BI
BI
OUT
OUT
IN
IN
IN
IN
OUT
OUT
OUT
OUT
IN
IN
BI
BI
BI
BI
BI
BI
R342
R344 R346
R343 R345
R340
C



Thu Aug 24 10:14:58 2023 181 OF 365
V02MB FABCGTI
<NAME_2>
<NAME_1>
Blank
1
SHEETDATE
23
7 3 2 16 5 4
E
A
B
C
E
D
C
B
A
7 6 5 4
D
DEPARTMENT
SIZE
PROJECT DOCUMENT NUMBER REV
REVIEWER
DESIGNER
C



9ZXL045 ADDRESS: 0XDE(8-BIT)/0X6F(7-BIT)
Thu Aug 24 14:09:42 2023<NAME_2>
<NAME_1>
MB FABCGTI V02
182 OF 365
P3V3_AUX
P3V3_AUX
P3V3_AUX
P3V3_9ZXL045_P0_VDDR
P3V3_9ZXL045_P0_VDDAP3V3_9ZXL045_P0_VDD
P3V3_9ZXL045_P0_VDDA
P3V3_9ZXL045_P0_VDD
P3V3_9ZXL045_P0_VDDR
P3V3_AUX
P3V3_AUX
28
28
182
151
288
277
182
277
288
299
299
310
310151
182 182
FM_9ZXL045_P0_3_OE_N
FM_9ZXL045_P0_2_OE_N
FM_9ZXL045_P0_1_OE_N
1/16W
0402LF
10K
1%
CLK_100M_CPU0_CLK13_DP
CLK_100M_CPU0_CLK13_DN
CLK_9ZXL045_P0_SADR0
C0402
X 7R X 7R X 7R
10%
25V25V6.3V
0402
20%
1/10W
FCM2012KF-601T/0.5A
SMLF
P3V3_9ZXL045_P0
C0402
0.1UF
25V
10%
1%
1/16W
10K
1%
0402LF
CHIP
NC_U314_FBOUT
NC_U314_FBOUT_N
SMB_9ZXL045_P0_SCL
IC
FCM2012KF-601T/0.5A
SMLF
FM_9ZXL045_P0_0_OE_N
CLK_100M_RETIMER_CPU0_P1_R_DN
CLK_100M_RETIMER_CPU0_P0_R_DP
C LK_9ZXL045_P0_H IBW
CHIPCHIP
1/16W
10K
1%
0402LF
10K
1%
0402LF
1/16W
CHIP
X 6S
1
10%
10%
0.1UF0.1UF0.1UF
4.75K
1
1/16W
CLK BUFFER _ 9ZXL045 _ CPU0 RETIMER
10%
X 7R
0402
0.1UF
25V
040204020402
10%
CHIP
CHIP
1/16W
10K
0402LF
IND
EMPTY
0402LF
10%
25V
0.1UF
25V
1%
0402
6.3V
20%
10UF
C0402
X 6S
20%
1%
10K
1%
0402LF
NC_U314_NC1
NC_U314_NC0
1/16W
10K
CHIP
CLK_100M_RETIMER_CPU0_P0_R_DN
CLK_100M_RETIMER_CPU0_P1_R_DP
CLK_100M_RETIMER_CPU0_P2_R_DP
CLK_100M_RETIMER_CPU0_P2_R_DN
CLK_100M_RETIMER_CPU0_P3_R_DP
CLK_100M_RETIMER_CPU0_P3_R_DN
NC_U314_NC3
NC_U314_NC2
X 6S X 7R
SMLF
9ZXL0451EKILFT
1%
10UF 0.1UF
6.3V 25V
10UF
0603LF
CHIP
CHIP
0402LF
SMB_9ZXL045_P0_SDA
X 7R
0402
IND
X 7R
1/10W0603LF
1%
1/16W
1%
4.75K
0402LF
C LK_9ZXL045_P0_SAD R 0
1/16W
C LK_9ZXL045_P0_H IBW
CHIP
FM_9ZXL045_P0_DEV_EN
R4493
R4475
5
26
24
18
15
2
31
29
25
21
16
12
6
7
30
17
11
10
8
9
33
4
3
28
27
23
22
20
19
14
13
32
1
21
21
U314
L19
L20
vSADR0_tri
NC2
NC3
VDD0
DIF3
DIF1
EPAD_GND
^HIBW_BYPM_LOBW#
VDD1
VDDA
NC0
DIF3#
DIF2#
vOE2#
DIF2
DIF1#
vOE1#
DIF0
DIF0#
^CKPWRGD_PD#
VDD2
SMBCLK
FBOUT_NC#
NC1
SMBDAT
vOE3#
vOE0#FBOUT_NC
VDD4
VDD3
VDDR
DIF_IN#
DIF_IN
1 2
1 2
2
1
R4476
2
1 C2328
2
1 C77
2
1 C76
2
1
R6802
2
1
R4520
2
1
R4519
2
1
R4518
2
1
2
1
2
1
2
1
2
1
2
1
2
1
21
2
1
2
1
21
2
1
2
1
1
SHEETDATE
23
7 3 2 16 5 4
E
A
B
C
E
D
C
B
A
7 6 5 4
D
DEPARTMENT
SIZE
PROJECT DOCUMENT NUMBER REV
REVIEWER
DESIGNER
OUT
OUT
OUT
OUT
OUT
OUT
OUT
OUT
IN
OUT OUT
IN
IN
IN
IN
IN
C2339C81C80C79C2329
R4491
R4492
C2334
C78
R4489
R4490
C



9ZXL045 ADDRESS: 0XD8(8-BIT)/0X6C(7-BIT)
Thu Aug 24 14:09:42 2023<NAME_2>
<NAME_1>
MB FABCGTI V02
183 OF 365
P3V3_AUX
P3V3_AUX
P3V3_9ZXL045_P1_VDDR
P3V3_AUX
P3V3_9ZXL045_P1_VDDR
P3V3_9ZXL045_P1_VDDAP3V3_AUX
P3V3_9ZXL045_P1_VDD
P3V3_9ZXL045_P1_VDD P3V3_9ZXL045_P1_VDDA
P3V3_AUX
332
321
321
183
354
343
183183
332
343
354
55
183
55
151
151
CLK_100M_RETIMER_CPU1_P1_R_DP
CLK_100M_RETIMER_CPU1_P0_R_DN
CLK_100M_RETIMER_CPU1_P0_R_DP
C LK_9ZXL045_P1_H IBW
20%
0.1UF 0.1UF 0.1UF0.1UF
FCM2012KF-601T/0.5A
1% CHIP
0.1UF
25V
10UF
FM_9ZXL045_P1_DEV_EN
0402LF
CHIP
10K
1%
1/16W
0402LF
CHIP
10K
1%
1/16W
FM_9ZXL045_P1_3_OE_N
FM_9ZXL045_P1_2_OE_N
NC_U10_NC2
NC_U10_NC3
FM_9ZXL045_P1_1_OE_N
FM_9ZXL045_P1_0_OE_N
10K
1%
1/16W
10K
CHIP
0402LF
1/16W
1%
0402LF
CHIP
1/16W
1%
10K
CHIP
0402LF
6.3V
C0402
X 6S
20%
10UF
6.3V
C0402
X 7R
10%
0402
10%
25V
1%
10%
FCM2012KF-601T/0.5A
CLK_100M_RETIMER_CPU1_P3_R_DN
CLK_100M_RETIMER_CPU1_P2_R_DP
C LK_9ZXL045_P1_H IBW
CHIP
1/16W
C LK_9ZXL045_P1_SAD R 0
CHIP
1/16W
SMLF
SMLF
P3V3_9ZXL045_P1
0603LF
25V 25V
0.1UF
10%
X 7R
0402
25V
10%
X 7R
10%
0402
X 7RX 7R
10%
0402
25V
X 7R
0402
SMLF
0402
0.1UF
1
10K
0402LF
CHIP
1%
0402LF
10K
1%
0402LF
4.75K
0402LF
1%
EMPTY
CLK BUFFER _ 9ZXL045 _ CPU1 RETIMER
4.75K
IND
CHIP
1/10W
IC
1
0402
9ZXL0451EKILFT
1%
1/16W
CLK_100M_RETIMER_CPU1_P1_R_DN
CLK_100M_RETIMER_CPU1_P2_R_DN
CLK_100M_RETIMER_CPU1_P3_R_DP
0603LF 1/10W
IND
C0402
6.3V
10UF
X 6S
1/16W
NC_U10_NC1
CLK_100M_CPU1_CLK13_DP
NC_U10_FBOUT
CLK_9ZXL045_P1_SADR0
CLK_100M_CPU1_CLK13_DN
NC_U10_NC0
NC_U10_FBOUT_N
SMB_9ZXL045_P1_SDA
SMB_9ZXL045_P1_SCL
X 7RX 6S
20%
25V
R560
R6803 R594R593R592
R586
R555
5
26
24
18
15
2
31
29
25
21
16
12
6
7
30
17
11
10
8
9
33
4
3
28
27
23
22
20
19
14
13
32
1
21
21
U10
L2
L1
vSADR0_tri
NC2
NC3
VDD0
DIF3
DIF1
EPAD_GND
^HIBW_BYPM_LOBW#
VDD1
VDDA
NC0
DIF3#
DIF2#
vOE2#
DIF2
DIF1#
vOE1#
DIF0
DIF0#
^CKPWRGD_PD#
VDD2
SMBCLK
FBOUT_NC#
NC1
SMBDAT
vOE3#
vOE0#FBOUT_NC
VDD4
VDD3
VDDR
DIF_IN#
DIF_IN
1 2
1 2
2
1
2
1 C28
2
1 C83
2
1 C82
2
1
2
1
2
1
2
1
2
1
2
1
2
1
2
1
2
1
2
1
2
1
2
1
2
1
21
21
2
1
2
1
1
SHEETDATE
23
7 3 2 16 5 4
E
A
B
C
E
D
C
B
A
7 6 5 4
D
DEPARTMENT
SIZE
PROJECT DOCUMENT NUMBER REV
REVIEWER
DESIGNER
IN
OUT
OUT
OUT
OUT
OUT
OUT
OUT
OUT
IN
OUTOUT
IN
IN
IN
IN
R578
R579
C75C99C98C90C58
C84
C68
R580
R585
C



TCA9548 ADDR: 0XE0 (8-BIT) /0X70 (7-BIT)
Thu Aug 24 14:09:49 2023<NAME_2>
<NAME_1>
MB FABCGTI V02
184 OF 365
P 1V 8_A UX
P 1V 8_A UX
P1V8_CPU1_RT_1D
P1V8_CPU0_RT_1D
151
151
184 277
184 277
184 288
184 299
184 310
184 299
184 310
184 288
184
184
184
81184
81184
184332
184354
184354
184343
184
184
184
184 299
184 299
184 310
184 310
184 288
184 288
184 277
184 277
184 343
184 343
184 354
184 354
184 332
184 332
184 321
184 321
184343
184332
184321
184321
SMB_MUX_RT_SCL 0201LF CHIP 1% 33.2
SMB_MUX_RT_SDA 0201LF CHIP 1% 33.2 SMB_MUX_RT_R1_SDA
SMB_MUX_RT_R1_SCL
SMB_RT_CPU0_P0_R_SDA
SMB_RT_CPU0_P0_R_SCL
SMB_RT_CPU0_P1_R_SDA
0201LF
0201LF
0201LF
0201LF
0201LFSMB_RT_CPU0_P0_SDA
SMB_RT_CPU0_P0_SCL
SMB_RT_CPU0_P1_SCL
5%
00201LF
CHIP0201LF
0201LF
CHIP
5%CHIP
5%
SMB_MUX_RT_R2_SCL CONN3_210-HP1-030BR1
IO
0201LF
SMB_MUX_RT_R2_SDA
SMB_RT_CPU0_P2_R_SDA
SMB_RT_CPU0_P3_R_SDA
SMB_RT_CPU0_P2_R_SCL
SMB_RT_CPU0_P3_R_SCL
SMB_RT_CPU0_P1_R_SCL
THLF
0
0
C0201
RT_SMB_MUX_ADDR0
RT_SMB_MUX_ADDR1
RT_SMB_MUX_ADDR2
CHIP
CHIP
0.1UF
SMB_RT_CPU0_P1_SDA
CHIP
SMB_RT_CPU0_P3_SCL
TCA9548APWR
RST_SMB_RT_R1_N
RST_SMB_RT_NCHIP0201LFRST_SMB_RT_R1_N
SMB_RT_CPU1_P1_R_SCL
SMB_RT_CPU1_P3_R_SDA
SMB_RT_CPU1_P3_R_SCL
SMB_RT_CPU1_P2_R_SDA
0201LF CHIP 5%
SMB_RT_CPU1_P0_SCL
SMB_RT_CPU1_P1_SDA
SMB_RT_CPU1_P1_SCL
SMB_RT_CPU1_P3_SDA
SMLF
0
CHIP
5%
5%0201LF CHIP 0
SMB_RT_CPU1_P2_SCL
SMB_RT_CPU1_P3_SCL
IC
SMB_RT_CPU1_P2_SDA
0201LF
RT_SMB_MUX_ADDR0
1/20W
CHIP
0201LF
RT_SMB_MUX_ADDR1
RT_SMB_MUX_ADDR2
SMB_RT_CPU0_P2_R_SCL
SMB_RT_CPU0_P2_R_SDA
SMB_RT_CPU0_P3_R_SCL
SMB_RT_CPU0_P3_R_SDA
SMB_RT_CPU0_P1_R_SDA
SMB_RT_CPU0_P1_R_SCL
SMB_RT_CPU0_P0_R_SCL
SMB_RT_CPU0_P0_R_SDA
SMB_RT_CPU1_P2_R_SCL
SMB_RT_CPU1_P2_R_SDA
SMB_RT_CPU1_P3_R_SDA
SMB_RT_CPU1_P3_R_SCL
SMB_RT_CPU1_P1_R_SCL
SMB_RT_CPU1_P1_R_SDA
SMB_RT_CPU1_P0_R_SCL
SMB_RT_CPU1_P0_R_SDA
CHIP
4.7K
0201LF
5%
1/20W
5%
4.7K
EMPTY
4.7K
1/20W
5%
0201LF
5%
4.7K
1/20W
EMPTY
0201LF
5%
1/20W
CHIP
0201LF
4.7K
EMPTY
0201LF
5%
1/20W
4.7K
0201LFCHIP1K
0201LFCHIP1K
0201LFCHIP1K
CHIP1K 0201LF
1K 0201LFCHIP
1K 0201LFCHIP
0201LFCHIP1K
0201LFCHIP1K
1% 1/20W
1K 0201LFCHIP
1K 0201LFCHIP
0201LF1K CHIP
1K 0201LFCHIP
0201LF1K CHIP
CHIP 0201LF1K
0201LFCHIP1K
1K CHIP 0201LF
1/20W1%
SMB_RT_CPU1_P2_R_SCL
5% 0
0
0201LF
CHIP 5%
5%
0201LF
0201LF
CHIP
CHIP
0201LF
CHIP
0201LF
SMB_RT_CPU0_P3_SDA
05%
X7S
10%
SMBUS - RETIMER
5%
0
5%
CHIP 0
0
0201LF
0
0
CHIP
5%
0
10V
CHIP 5%
0
0
SMB_RT_CPU1_P1_R_SDA
SMB_RT_CPU1_P0_R_SDA
SMB_RT_CPU1_P0_R_SCL
0201LF
1%
1/20W
SMB_RT_CPU1_P0_SDA
CHIP
10K
0
0
5%
5%
5%
SMB_RT_CPU0_P2_SDA
SMB_RT_CPU0_P2_SCL
5%
CHIP
CHIP
5% 0
R6780
R6779
R1514
R1515
R6776
C7500
R6761
R6759
R6760
R6757
R6756
R6758
R6755
R6754
R6748
R6749
R6746
R6747
R6737
R6736
R6811
R6810
3
2
1
24
23
19
17
15
13
10
8
6
4
22
20
18
16
14
11
9
7
5
3
12
21
2
1
JP6500
U6020
1
2
3
SD4
SC4
SD5
SC5
SD6
SC6
SD7
SC7
A2 SCL
SDA
VCC
GND
SC3
SD3
SC2
SD2
SC1
SD1
SC0
SD0
RESET#
A1
A0
21
21
21
21
2
1
21
2
1
R6771
2
1
R6772
2
1
R6775
2
1
R6770
2
1
R6774
2
1
R6773
2
1
21
21
21
21
21
21
21
21
21
21
21
21
21
21
21
21
21
21
21
21
21
21
21
21
21
21
21
21
21
21
21
21
1
SHEETDATE
23
7 3 2 16 5 4
E
A
B
C
E
D
C
B
A
7 6 5 4
D
DEPARTMENT
SIZE
PROJECT DOCUMENT NUMBER REV
REVIEWER
DESIGNER
IN
IN
IN
OUT
OUT
OUT
OUT
OUT
OUT
OUT
OUT
BI
OUT
BI
OUT
BI
OUT
BI
OUT
BI
OUT
OUT
OUT
OUT
OUT
OUT
BI
OUT
BI
OUT
OUT
OUT
BI
OUT
IN
BI
IN
IN
OUT
OUT
OUT OUT
R6778
R6769
R6768
R6766
R6767
R6765
R6764
R6763
R6762
R6753
R6752
R6751
R6750
R6739
R6738
R6719
R6718
C



FOR RT I2C MUX SIDE FOR RT I2C MUX SIDE
FOR RT EEPROM SIDEFOR RT EEPROM SIDE
TCA9548 ADDR: 0XE0 (8-BIT) /0X70 (7-BIT)
Thu Aug 24 14:09:51 2023<NAME_2>
<NAME_1>
MB FABCGTI V02
185 OF 365
CHIP
P1V8_CPU0_RT_1D
P1V8_CPU1_RT_1D
P1V8_CPU1_RT_1D
P 1V 8_A UX
P 1V 8_A UX
P1V8_CPU1_RT_1D
P1V8_CPU0_RT_1D
P1V8_CPU0_RT_1D
288 186
185
185
185
186 277
185
185
185
185
185
185
185
185
185
185
185
185
185
81185186
186
186
186
186
186
186
186
186
185
185
185
151
151
186
186
186
186
186
186
186
186
81185186
186 301
186 301
186 312
186 279
186 279
186 323
186 334
186 312
186 290
186 290
186 334
186 356
186 323
186 356
186 345
186 345
185
185
185
299 186
186 299
310 186
186 310
186 288
277 186
343 186
354 186
186 343
186 354
332 186
186 332
321 186
186 3210201LF
SMB_R T_C PU 0_P1_R OM_MU X_1D _SC L
1/20W1%
1K CHIP
1K CHIP 0201LF
0201LFCHIP1K
0201LFCHIP1K
0201LFCHIP1K
0201LF1K CHIP
0201LF1K CHIP
0201LF1K CHIP
0201LFCHIP1K
1K CHIP 0201LF
1K CHIP 0201LF
1K CHIP 0201LF
1K CHIP 0201LF
1K CHIP 0201LF
1K CHIP 0201LF
0201LFCHIP1K
1% 1/20W
SMB_R T_C PU 0_P3_R OM_MU X_2D _R _SC L
SMB_R T_C PU 0_P1_R OM_MU X_2D _R _SC L
SMB_R T_C PU 0_P0_R OM_MU X_2D _R _SC L
SMB_R T_C PU 0_P0_R OM_MU X_1D _SD A
CHIP
4.7K
4.7K
1/20W
SMB_R T_C PU 0_P0_R OM_MU X_2D _R _SD A
0201LFCHIP
4.7K
1/20W
SMB_R T_C PU 0_P1_R OM_MU X_2D _R _SD A
SMB_R T_C PU 0_P2_R OM_MU X_2D _R _SD A
SMB_R T_C PU 0_P2_R OM_MU X_2D _R _SC L
SMB_R T_C PU 0_P3_R OM_MU X_2D _R _SD A
SMB_R T_C PU 1_P2_R OM_MU X_2D _R _SC L
SMB_R T_C PU 1_P2_R OM_MU X_2D _R _SD A
SMB_R T_C PU 1_P1_R OM_MU X_2D _R _SD A
SMB_R T_C PU 1_P3_R OM_MU X_2D _R _SD A
SMB_R T_C PU 1_P3_R OM_MU X_2D _R _SC L
SMB_R T_C PU 1_P1_R OM_MU X_2D _R _SC L
SMB_R T_C PU 1_P0_R OM_MU X_2D _R _SD A
SMB_R T_C PU 1_P0_R OM_MU X_2D _R _SC L
0201LF4.7K CHIP
CHIP 0201LF
0201LFCHIP
CHIP4.7K 0201LF
0201LFCHIP4.7K
0201LFCHIP4.7K
4.7K
CHIP 0201LF
CHIP 0201LF4.7K
CHIP 0201LF
4.7K CHIP 0201LF
4.7K CHIP 0201LF
CHIP4.7K 0201LF
4.7K
5%
0201LF
CHIP 0201LF
4.7K CHIP 0201LF
SMB_R T_C PU 1_P1_R OM_MU X_2D _R _SC L
RST_SMB_RT_ROM_R1_N
SMB_R T_C PU 1_P2_R OM_MU X_2D _SD A
SMB_R T_C PU 1_P2_R OM_MU X_2D _SC L
SMB_R T_C PU 1_P3_R OM_MU X_2D _SC L
SMB_R T_C PU 1_P1_R OM_MU X_2D _SC L
SMB_R T_C PU 1_P3_R OM_MU X_2D _SD A
SMB_R T_C PU 1_P1_R OM_MU X_2D _SD A
SMB_R T_C PU 1_P0_R OM_MU X_2D _SC L
SMB_R T_C PU 1_P0_R OM_MU X_2D _SD A
RST_SMB_RT_ROM_N
SMB_R T_C PU 1_P2_R OM_MU X_2D _R _SD A
SMB_R T_C PU 1_P2_R OM_MU X_2D _R _SC L
SMB_R T_C PU 1_P3_R OM_MU X_2D _R _SD A
SMB_R T_C PU 1_P3_R OM_MU X_2D _R _SC L
SMB_R T_C PU 1_P1_R OM_MU X_2D _R _SD A
SMB_R T_C PU 1_P0_R OM_MU X_2D _R _SC L
SMB_R T_C PU 1_P0_R OM_MU X_2D _R _SD A
RT_ROM_SMB_MUX_ADDR2
RT_ROM_SMB_MUX_ADDR1
RT_ROM_SMB_MUX_ADDR0
SMB_MUX_RT_ROM_R1_SCLSMB_MUX_RT_ROM_SCL
SMB_MUX_RT_ROM_R1_SDASMB_MUX_RT_ROM_SDA
SMB_RT_CPU0_P2_ROM_MUX_2D_SDASMB_R T_C PU 0_P2_R OM_MU X_2D _R _SD A
SMB_RT_CPU0_P2_ROM_MUX_2D_SCLSMB_R T_C PU 0_P2_R OM_MU X_2D _R _SC L
SMB_RT_CPU0_P1_ROM_MUX_2D_SCLSMB_R T_C PU 0_P1_R OM_MU X_2D _R _SC L
SMB_RT_CPU0_P3_ROM_MUX_2D_SDASMB_R T_C PU 0_P3_R OM_MU X_2D _R _SD A
SMB_RT_CPU0_P0_ROM_MUX_2D_SCLSMB_R T_C PU 0_P0_R OM_MU X_2D _R _SC L
SMB_RT_CPU0_P1_ROM_MUX_2D_SDASMB_R T_C PU 0_P1_R OM_MU X_2D _R _SD A
SMB_RT_CPU0_P0_ROM_MUX_2D_SDASMB_R T_C PU 0_P0_R OM_MU X_2D _R _SD A
SMB_RT_CPU0_P3_ROM_MUX_2D_SCLSMB_R T_C PU 0_P3_R OM_MU X_2D _R _SC L
5%0201LF CHIP 0
0201LF 05%CHIP
CHIP 5% 00201LF
0201LF 5% 0CHIP
0201LF 05%CHIP
0201LF 5% 0CHIP
5%0201LF 0CHIP
05%CHIP0201LF
05%CHIP0201LF
10%
10V
C0201
X7S
0.1UF
00201LF CHIP 5%
5%CHIP 00201LF
0201LF 5%CHIP 0
0201LF CHIP 05%
0201LF 5% 0CHIP
0201LF 5% 0CHIP
5% 00201LF CHIP
0CHIP 5%0201LF
5% 00201LF CHIP
0201LF 5% 0CHIP
SMLF
IC
TCA9548APWR
RST_SMB_RT_ROM_R1_N
1%
10K
1/20W
0201LF
SMB_RT_CPU0_P2_ROM_R_SCL
SMB_RT_CPU0_P2_ROM_R_SDA
SMB_RT_CPU0_P3_ROM_R_SCL
SMB_RT_CPU0_P0_ROM_R_SCL
SMB_RT_CPU0_P0_ROM_R_SDA
SMB_RT_CPU1_P0_ROM_R_SDA
SMB_RT_CPU1_P1_ROM_R_SDA
CHIP
SMB_RT_CPU0_P3_ROM_R_SDA
SMB_RT_CPU0_P1_ROM_R_SCL
SMB_RT_CPU0_P1_ROM_R_SDA
0201LF
0201LF
CHIP
CHIP1K
1K
SMB_RT_CPU1_P1_ROM_R_SCL
SMB_RT_CPU1_P3_ROM_R_SDA
SMB_RT_CPU1_P0_ROM_R_SCL
SMB_RT_CPU1_P3_ROM_R_SCL
SMB_RT_CPU1_P2_ROM_R_SDA
SMB_RT_CPU1_P2_ROM_R_SCL
1K
SMBUS - RETIMER EEPROM
RT_ROM_SMB_MUX_ADDR0
RT_ROM_SMB_MUX_ADDR2
RT_ROM_SMB_MUX_ADDR1
0201LF
1/20W
5%
4.7K
CHIP
0201LF
4.7K
5%
1/20W
CHIP
0201LF
0201LF
1/20W
4.7K
5%
EMPTY EMPTY
0201LF
5%
4.7K
1/20W
0201LF
CHIP
1/20W
5%
4.7K
EMPTY
4.7K
5%
1/20W
0201LF
1K CHIP
1K CHIP
0201LF
0201LF1K
0201LFCHIP1K
0201LF1K
0201LF1K
0201LF1K CHIP
0201LFCHIP1K
CHIP 0201LF1K
0201LFCHIP
0201LF
0201LF
CHIP
CHIP
CHIP1K
1K
0201LF
1% 1/20W
1K
4.7K
4.7K
CHIP
CHIP
5%
1K
1/20W
0201LFCHIP
1%
SMB_R T_C PU 0_P2_R OM_MU X_1D _SC L
SMB_R T_C PU 0_P2_R OM_MU X_1D _SD A
SMB_R T_C PU 0_P3_R OM_MU X_1D _SC L
SMB_R T_C PU 0_P3_R OM_MU X_1D _SD A
SMB_R T_C PU 0_P1_R OM_MU X_1D _SD A
SMB_R T_C PU 0_P0_R OM_MU X_1D _SC L
SMB_R T_C PU 1_P2_R OM_MU X_1D _SC L
SMB_R T_C PU 1_P3_R OM_MU X_1D _SC L
SMB_R T_C PU 1_P2_R OM_MU X_1D _SD A
SMB_R T_C PU 1_P3_R OM_MU X_1D _SD A
SMB_R T_C PU 1_P1_R OM_MU X_1D _SC L
SMB_R T_C PU 1_P1_R OM_MU X_1D _SD A
SMB_R T_C PU 1_P0_R OM_MU X_1D _SC L
SMB_R T_C PU 1_P0_R OM_MU X_1D _SD A
185
185
185
185
185
185
185
185
185
185
185
185
185
185
185
185
R851
R850
R797
R799
R830
R829
R828
R832
R831
R833
C365
R802
R801
R803
R806
R805
R808
R809
R807
R848
24
23
19
17
15
13
10
8
6
4
22
20
18
16
14
11
9
7
5
3
12
21
2
1
U22
SD4
SC4
SD5
SC5
SD6
SC6
SD7
SC7
A2 SCL
SDA
VCC
GND
SC3
SD3
SC2
SD2
SC1
SD1
SC0
SD0
RESET#
A1
A0
21
21
21
21
21
21
21
21
21
21
21
21
21
21
21
21
21R1383
21R1382
21R1379
21R1375
21R1371 21R1374
21R1366
21R1367
21R1407
21R1403
21R1402
21R1399
21R1394
21R1393
21R1390
21R1361
21
21
21
21
21
21
21
21
21
21
21
21
21
21
21
21
21
21
2
1
21
21
21
21
21
21
21
21
21
21
21
21
21
21
21
21
21
2
1
2
1
R844
2
1
R847
2
1
R843
2
1
R842
2
1
R846
2
1
R845
1
SHEETDATE
23
7 3 2 16 5 4
E
A
B
C
E
D
C
B
A
7 6 5 4
D
DEPARTMENT
SIZE
PROJECT DOCUMENT NUMBER REV
REVIEWER
DESIGNER
OUT
OUT
OUT
OUT
OUT
BI
IN
OUT
BI
BI
BI
OUT
OUT
BI
OUT
OUT
OUT
OUT
IN
OUT
OUT
OUT
OUT
IN
IN
IN
BI
OUT
BI
OUT
BI
OUT
BI
OUT
OUT
OUT
OUT
OUT
OUT
OUT
OUT
OUT
OUT
OUT
OUT
OUT
OUT
OUT
OUT
OUT
IN
OUT
OUT
OUT
OUT
OUT
OUT
OUT
OUT
OUT
OUT
OUT
OUT
OUT
OUT
OUT
OUT
OUT
OUT
OUT
OUT
OUT
OUT
OUT
R1469
R1468
R1463
R1462
R1451
R1448
R1436
R1437
R1432
R1431
R1428
R1420
R1418
R1415
R1411
R1410
R6706
R6707
R6735
R6734
R810
R812
R826
R827
R834
R835
R836
R837
R839
R838
R840
R841
R849
C



Thu Aug 24 14:09:57 2023<NAME_2>
<NAME_1>
MB FABCGTI V02
186 OF 365
P 3V 3_A UX
P 3V 3_A UX
P 3V 3_A UX
P 3V 3_A UX
P 3V 3_A UX
P 3V 3_A UX
P 3V 3_A UX
P 3V 3_A UX
185332
185
185321
185321
81185186
185 356
185310
185310
185 279
185 279
185
185
185277
185277
81185186
81185186
81185186
185 345
81185186
185
185
185343
185 345
185343
81185186
185
185
185354
185 356
185354
81185186
185332
185
185
185 334
185 334
185 323
185 323
185
81185186
185288
185288
185
185 290
185
185 290
185
185
185 312
185 312
185299
185
185 301
185 301
185
185299
10V
1K
SMB_RT_CPU1_P1_ROM_MUX_1D_SCL
SMB_RT_CPU1_P0_ROM_MUX_2D_SCL
SMB_RT_CPU1_P0_ROM_MUX_1D_SDA
SMB_RT_CPU1_P0_ROM_MUX_1D_SCL
RST_SMB_RT_ROM_R1_N
FM_SMB_R T_R OM_MU X2_SEL
SMB_RT_CPU1_P3_ROM_R_SDA
0201LF CHIP 0
1KCHIP0201LF
PI3CSW12ZUAEX
SMLF
IC
1KCHIP0201LF
0CHIP0201LF
CHIP0201LF 1K
CHIP0201LF 0
SMLF
PI3CSW12ZUAEX
IC
X7S
10%
C0201
10V
0.1UF
0.1UF
10V
C0201
10%
X7S
1KCHIP0201LF
0CHIP0201LF
IC
PI3CSW12ZUAEX
SMLF
0.1UF
10V
10%
C0201
X7S
0.1UF
10V
10%
C0201
X7S
PI3CSW12ZUAEX
IC
SMLF
1KCHIP0201LF
0201LF CHIP 0
X7S
10%
C0201
10V
0.1UF
IC
PI3CSW12ZUAEX
SMLF
0201LF CHIP 1K
0201LF CHIP 0
X7S
10%
C0201
10V
0.1UF
IC
PI3CSW12ZUAEX
SMLF
CHIP0201LF
0CHIP0201LF
0.1UF
10V
10%
C0201
X7S
PI3CSW12ZUAEX
IC
SMLF
0CHIP0201LF
1KCHIP0201LF
0.1UF
10%
C0201
X7S
IC
PI3CSW12ZUAEX
SMLF
SMB_RT_CPU0_P3_ROM_MUX_1D_SCL
SMB_RT_CPU0_P3_ROM_MUX_1D_SDA
SMB_RT_CPU0_P0_ROM_R_SDA
SMB_RT_CPU0_P0_ROM_R_SCL
SMB_RT_CPU0_P0_ROM_MUX_2D_SDA
SMB_RT_CPU0_P0_ROM_MUX_2D_SCL
SMB_RT_CPU0_P0_ROM_MUX_1D_SDA
SMB_RT_CPU0_P0_ROM_MUX_1D_SCL
FM_SMB_R T_R OM_MU X5_SEL
RT_ROM_MUX5_OE_N
RST_SMB_RT_ROM_R1_N
RST_SMB_RT_ROM_R1_N
RST_SMB_RT_ROM_R1_N
SMB_RT_CPU1_P2_ROM_R_SDA
RST_SMB_RT_ROM_R1_N
SMB_RT_CPU1_P2_ROM_MUX_2D_SDA
SMB_RT_CPU1_P2_ROM_MUX_2D_SCL
SMB_RT_CPU1_P2_ROM_MUX_1D_SDA
FM_SMB_R T_R OM_MU X4_SEL
RT_ROM_MUX4_OE_N
SMB_RT_CPU1_P2_ROM_R_SCL
SMB_RT_CPU1_P2_ROM_MUX_1D_SCL
RST_SMB_RT_ROM_R1_N
SMB_RT_CPU1_P3_ROM_MUX_2D_SDA
SMB_RT_CPU1_P3_ROM_MUX_2D_SCL
SMB_RT_CPU1_P3_ROM_MUX_1D_SDA
RT_ROM_MUX3_OE_N
FM_SMB_R T_R OM_MU X3_SEL SMB_RT_CPU1_P3_ROM_R_SCL
SMB_RT_CPU1_P3_ROM_MUX_1D_SCL
RST_SMB_RT_ROM_R1_N
SMB_RT_CPU1_P1_ROM_MUX_1D_SDA
SMB_RT_CPU1_P1_ROM_MUX_2D_SDA
SMB_RT_CPU1_P1_ROM_MUX_2D_SCL
RT_ROM_MUX2_OE_N
SMB_RT_CPU1_P1_ROM_R_SDA
SMB_RT_CPU1_P1_ROM_R_SCL
RT_ROM_MUX1_OE_N
FM_SMB_R T_R OM_MU X1_SEL
SMB_RT_CPU1_P0_ROM_R_SDA
SMB_RT_CPU1_P0_ROM_R_SCL
SMBUS-RETIMER EEPROM MUX
SMB_RT_CPU1_P0_ROM_MUX_2D_SDA
RST_SMB_RT_ROM_R1_N
RT_ROM_MUX6_OE_N
FM_SMB_R T_R OM_MU X6_SEL
SMB_RT_CPU0_P1_ROM_MUX_1D_SCL
SMB_RT_CPU0_P1_ROM_MUX_1D_SDA
SMB_RT_CPU0_P1_ROM_MUX_2D_SCL
SMB_RT_CPU0_P1_ROM_R_SCL
SMB_RT_CPU0_P1_ROM_MUX_2D_SDA
SMB_RT_CPU0_P1_ROM_R_SDA
SMB_RT_CPU0_P3_ROM_MUX_2D_SCL
SMB_RT_CPU0_P3_ROM_MUX_2D_SDA
SMB_RT_CPU0_P3_ROM_R_SCL
SMB_RT_CPU0_P3_ROM_R_SDA
RT_ROM_MUX7_OE_N
FM_SMB_R T_R OM_MU X7_SEL
SMB_RT_CPU0_P2_ROM_MUX_1D_SDA
SMB_RT_CPU0_P2_ROM_MUX_2D_SDA
FM_SMB_R T_R OM_MU X8_SEL SMB_RT_CPU0_P2_ROM_R_SCL
SMB_RT_CPU0_P2_ROM_R_SDA
SMB_RT_CPU0_P2_ROM_MUX_2D_SCL
SMB_RT_CPU0_P2_ROM_MUX_1D_SCL
RT_ROM_MUX8_OE_N
R1209
R1206
R1210
R1211
R1200
R1198
R1199
R1201
10
9
6
5
7
8
4
3
2
1
10
9
6
5
7
8
4
3
2
1
10
9
6
5
7
8
4
3
2
1
10
9
6
5
7
8
4
3
2
1
10
9
6
5
7
8
4
3
2
1
10
9
6
5
7
8
4
3
2
1
10
9
6
5
7
8
4
3
2
1
10
9
6
5
7
8
4
3
2
1
U47
U46
U49
U48
U43
U41
U42
U45
D+
GND
1D-
VDD
S
OE#
D-
2D-
2D+
1D+
D+
GND
1D-
VDD
S
OE#
D-
2D-
2D+
1D+
D+
GND
1D-
VDD
S
OE#
D-
2D-
2D+
1D+
D+
GND
1D-
VDD
S
OE#
D-
2D-
2D+
1D+
D+
GND
1D-
VDD
S
OE#
D-
2D-
2D+
1D+
D+
GND
1D-
VDD
S
OE#
D-
2D-
2D+
1D+
D+
GND
1D-
VDD
S
OE#
D-
2D-
2D+
1D+
D+
GND
1D-
VDD
S
OE#
D-
2D-
2D+
1D+
21
21 R1217
21 R1216
21
21 R1218
21
2
1 C1071
2
1 C1070
21 R121921
2
1 C1072
2
1 C1073
21 R1214
21
2
1 C1068
21 R1212
21
2
1 C1066
21 R121321
2
1 C1067
21
21 R1215
2
1 C1069
1
SHEETDATE
23
7 3 2 16 5 4
E
A
B
C
E
D
C
B
A
7 6 5 4
D
DEPARTMENT
SIZE
PROJECT DOCUMENT NUMBER REV
REVIEWER
DESIGNER
BI
OUT
BI
OUT
IN
BI
BI
IN
BI
OUT
IN
BI
IN
BI
IN
BI
OUT
IN
BI
BI
IN
IN
BI
OUT
IN
BI
IN
OUT
BI
BI
IN
BI
IN
IN
BI
BI
OUT
IN
IN
IN
IN
IN
BI
IN
BI
IN
BI
IN
BI
IN
BI
BI
IN
IN
OUT
BI
C



CAD NOTE: R5051 R5052 CO-LAY
VDDBT_RTC_G POWERED FROM 3V: POP R5052 R5054 R5055,DEPOP R5051 R5053 R5056
AHL03003097
VDDBT_RTC_G POWERED FROM 1.5 OR 1.8V: POP R5051 R5053 R5056, DEPOP R5052 R5054 R5055
CAD NOTE:
CAD NOTE: R5053 R5054 CO-LAY
FPGA
2ND SOURCE OF U167
2-3 BIOS LOAD DEFAULT
1-2 NORMAL OPERATION(DEFAULT)
CLEAR CMOS JUMPER
Thu Aug 24 14:09:50 2023<NAME_2>
<NAME_1>
MB FABCGTI V02
187 OF 365
P 1V 5_B A T
P 3V 3_RTC_A UX
P 3V 3_A UX
187
187
187
82
187
187
187
0402LF
X 6S
X 7R
10%
50V
100NF
THLF
P 3V _B A T
CHIP
1%
1/16W
0402LF
1K
P 3V _B A T_R
10K
SMLF
NCP698SQ15T1G
1/16W
CHIP
BAT_LDO_EN
10%
25V
B A T_LDO _E N
P 1V 5_B A T_IN
CLR_CMO S
P 1V 5_B A T_O UT
U9_NR
CLR_CMO S _N
P 1V 5_B A T_O UT_R
P 1V 5_B A T_IN
P 3V 3_RTC_A UX _R
IO
CO NN2_A A A -B A T-029-Y 19
1K
CHIP
1%
1/16W
0402LF C0402
0.1UF
X 7R
16V
10%
5% 1/16W
CHIP
0402LF
SMLF
B A T54CW
IC
5%0
1/16W
CHIP
0402LF
0
5%
1/16W
TPS71715DCKR
SMLF
EMPTY
0.01UF
C0402
10%
EMPTY
50V
IC
SMLF
2N7002K DW
0402LF
CHIP
C0402
1UF
0402LF 1/16W
100 CHIP1%
25V
X 6S
10%
C0402
1K
0402LF
0
C0402
25V
10%
X 6S
1UF
X 6S
10%
25V
10UF
C0805
THLF
CONN3_210-HP1-030BR1
BATTERY
1/16W
0402LF 1%
EMPTY
P 1V 5_B A T_O UT
IO
EMPTY
1UF
5%
EMPTY
C0402
1K
1%
1/16W
P 3V 3_S TB Y _R
2
1
R1777
2
1 C5032
2
1 C1567
2
1 C1564
21R1779
2
1 C193
2
1C45
41
52
36
Q8
3
1
2
U166
2
1
C1563
2
1
R1776
R5054
R5053R5051
R5052
R5101
32
1 4
3
2
1
5
4
1
2
3
2 1
U167
JP12
U9
BT2
C
B
A
OUT
NR||FB
IN
EN
GND
2 1
EN
VIN VOUT
GND
1
2
3
D2D1
S2S1
G2G1
21R1775
2
1
21
2
1
21
2
1
21
1
SHEETDATE
23
7 3 2 16 5 4
E
A
B
C
E
D
C
B
A
7 6 5 4
D
DEPARTMENT
SIZE
PROJECT DOCUMENT NUMBER REV
REVIEWER
DESIGNER
OUT
IN
IN
IN
IN
OUT
OUT
OUT
C22
C



20220922 ADD U100,U6006 FOR 3V3
20220922 MODIFY FOR GTI
PUSH PULL OUTPUT
OD OUTPUT
20220317 ADD R4638,R4639,R4640,R4641
20220225 ADD U324
Thu Aug 24 14:09:15 2023 188 OF 365
V02MB FABC
<NAME_2>
GTI
<NAME_1>
P3V3_AUX
P5V
P5V
P5V
P12V_AUX
P12V_AUX
P3V3_AUX
P3V3P3V3_AUX
P3V3
P 3V 3
P 3V 3
P3V3_AUX
P12V_AUX
P12V_AUX
P5V_AUX
P5V
P 1V 8_A UX
P 3V 3_A UX
188
80
81
81
81
188
33
0402LF
0
0402LF
1/16W
10K
100NF
50V
1/16W
1K
C0402
2N7002K
SMLF
VR_P5V_EN_D
IC
VR_P5V_EN_N
1%
1/4W
1206LF 1206LF
10%
1/16W
IC
1%
100K
1%
0402LF
4.7K
100K
BAT547F
RT9818C-44GV
SMLF
CHIP
SW_P3V3_EN_ISO
0402LF
PJT138K
SMLF
PWRGD_P5V_R_N
0402LF
CHIP
1/16W
5%
4.7K
C0402
SMLF
IC
PJT138K
5%
0402LF
1K
SW_P3V3_EN_R
SW_P3V3_EN_ISO_R
SW_P3V3_EN_N
0.22UF
10%
0402LF
EMPTY
0402LF
PWRGD_P5V_R2
SMLF
PJT138K
10K
1%
CHIP
0
CHIP
10%
5%
0402LF
1/16W
CHIP
E MP TY PSMNR58-30YLH
1/16W
0402LF
VR_P5V_EN_D_R1
X7R
SMLF
C0402
CHIP
1%
243
PSMNR58-30YLH
SMLF
1% 0402LF
CHIP
1/16W
10%
PJT138K
1%
X7R
16V
10%
C0402
100NF
10%
50V
X 7R
C0805
10UF
X 6S
C0805
10UF
16V
C0805
10%
X 6S
16V
10UF
50V
10%
X 7R
100NF
0.22UF
CCBU
CHIP
CHIP
1/4W
CHIP
1/4W
243
1/4W
1%
243
CHIP
1%
243
X 7R
C0402
VR_P5V_EN
1%
FM_P5V_EN
0402LF
CHIP
10K
10%
100NF
50V
X 7R
C0402
10UF
C0805
X 6S
10%
16V
10%
E MP TY
10UF
16V
IC
25V
100NF
50V
10%
10UF
16V
10%
X 6S
C0805
1206LF
100K
0 5% CHIP
1/16W
IC
SMLF
0402LF 1/16W
IC
SMLF
IC
EMPTY
X7R
25V
10K
CHIP
5%
5%0 IC
10K
EMPTY
1/16W
1%
0
0
CHIP
PWRGD_P5V_R15%
0402LF
IC
CHIP
1/16W
0402LF
PWRGD_P5V_N
1/16W
1%
100K
IC
0402LF
CHIP
1/16W
1%
1%
PJT138K
SMLF
1/16W
0402LF
VR_P5V_EN_D_R
1206LF
0402LF
CHIP
1/16W
5%
C0402
IC
SMLF
SMLF
5%
CHIP
P W RG D_P 3V 3_E N
10K
5%
0402LF
1/16W
APX809-29SAG-7
SMLF
IC
X7R
10%
0.1UF
25V
0402
100K
CHIP
0402LF
1%
P5V & P3V3 SWITCH
PW R GD _P3V3_EN _R
5%
CHIP
P W RG D_P 3V 3_E N_N
B S S 138DW -7-F
P W RG D_P 3V 3_R1
E MP TY
0402LF
CHIP
P W RG D_P 3V 3_R2
SW_P3V3_EN
100K
1%
CHIP
0402LF
VR_P5V_EN_N
PWRGD_P5V_R
0402LF
C0805
10K
IC
PJT138K
21 R1362
2
1
41
52
36
Q27
2
1
G2
G1
G1
G
G2
G2
G1
S2 D2
D1S1
D1S1
S D
S2 D2
S2 D2
D1S1
R1491
R6501
21
R6500
R1493
R1492
R569R6050
C9226
R335
R334
R333
3
2
1
5
2
5
2
3
1
2
G
4 3
1 6
4 3
1 6
S D
U6006
Q3
Q3
Q1
Q1
U100
U324
Q57
Q56
D1
Q37
Q37
GND
RESET#
VDD
S
G
D
1
25
3
31
1
25
3
GND
RESET_L
VCC
D2D1
S2
G2G1
S1
D1
G1
S3 S2 S1
4
D1
G1
S3 S2 S1
4
2
1
2
1
2
1 C6500
2
1
2
1
R568
2
1
2
1
R554
2
1
21
R494
2
1
21
21R487
2
1
R496
2
1
21R490
2
1
R480
2
1
R479
2
1 C6122
2
1
2
1
2
1
2
1
2
1
2
1
5
3
2
1
2
1
2
1
2
1
21
2
1
2
1
2
1
5
3
2
1
2
1
2
1
2
12
1
31
2
1
5
2
1
221
4
4
4 3
1 6
1
SHEETDATE
23
7 3 2 16 5 4
E
A
B
C
E
D
C
B
A
7 6 5 4
D
DEPARTMENT
SIZE
PROJECT DOCUMENT NUMBER REV
REVIEWER
DESIGNER
IN
IN
IN
OUT
OUT
OUT
C29
R552
R492
R482
R4641R4640R4639
C61
C1331
C57C1170C1042
C1340C60C1333C1332
R4638
C1227
R1654
R336
C



3RD
1ST
2ND NA
2ND AL053318002/RS53318LR/REEDSEMI
3RD AL000548006/TPS548A28RWWR/TI
BOM CHANGE R&C TABLE
WORK FREQUENCY = 600KHZ
SLEW RATE = 1A/US
CURRENT STEP = 1A
OCP(IMAX*120%) = 4A
TDC = 1.8A
IMAX = 2.1A
DESIGN SPECIFICATION
OUTPUT VOLTAGE = 5.0V
DC TOLERANCE = +/-1.5%
OUTPUT RIPPLE & NOISE = +/-1.0%
TRANSIENT TOLERANCE = +/-5.0%
TBC
PCMB104E-4R7MS
10.3*11.2*4.0
ISAT=13A
P5V_AUX
VOUT=0.6(1+RA/RB)=5.003V
RA
DCR=15MOHM
RB
PR8089 CHANGE TO CS31402FB03
PC1877 CHANGE TO CH1156F0B00
PC1848 CHANGE TO CH5222KEB01
1ST AL008633007/MPQ8633AGLE-C807-Z/MPS
BOM NOTE
2022/5/14 MODIFY
Thu Aug 24 14:09:25 2023<NAME_2>
<NAME_1>
MB FABCGTI V02
189 OF 365
P12V_AUX
P5V_AUX
P5V_AUX_VCC
P5V_AUX_VCC
85 190
263268243254
SW_P5V_AUX_FLT
MPQ8633AGLE-C807-Z
C0402
0402LF
5%
CHIP
5%
0402LF
X6S
20%
16V
0.1UF
25V
10%
C0805
X6SX6S
IND
BLM18SN220TN1D/8000MA
SMLF
C0805
22UF
C0402
X6S
10%
16V
1UF
16V
22UF
20%
C0805
X6S
16V
20%
22UF
47PF
0402LF
11.8K
0.1UF
1/16W
CHIP
0.1%
IC
0402
X7R
10%
0.1UF
25V
X6S
C0805
22UF
10V
20%
22UF
C0805
20%
10V
X6SALUM
20%
6.3V
SMLF
220UF
4.7UH
IND
86.6K
CHIP 1%
5%
0402LF
CHIP
0
10K
1/16W
25V
C0402
X7R
10%
0.22UF
50V
0402
5% NPO
25V
16.9K
25V
C0402
X6S
10%
PWRGD_P5V_AUX
SW_P5V_AUX_SW
P5V_AUX_FB
P5V_AUX_CS
SW_P5V_AUX_BST
PWRGD_P5V_AUX_R
CHIP
1UF
1/16W
1%
1/16W
0
1/16W
P5V_AUX_EN0
CHIP
P5V_AUX_MODE
MB0_P12V_STBY_PWRGD
SMLF
1%
0402LF
P5V_AUX_REF
0402LF
CHIP
SMLF
1/16W
10%
X7R
0402
0402LF
MPQ8633A/P5V_AUX
R6097
PR3337
2
1 PC1852
2
1 PC1856
2
1 PC1855
2
1 PC1845
21
PL8065
21PR8092
R2316
2
1
R2356
PC1847
2
1
PR8091
21
PC18772
1
PC1853
2
1
PR8089
PC1846
2
1 PC1898
2
1 PC1850
2
1
PC1848
2
1 PC1849
21
PL8064
21
10
19
5
20
6
9
11_18
4
7
8
3
1
2
U326
1 2
VIN2
CS
MODE
TRK_REF
SW
RGND
VCC
AGND
FB
BST
EN
PGND
PGOODVIN1
1 221
21
21
2
1
2
1
2
1 PC1648
1
SHEETDATE
23
7 3 2 16 5 4
E
A
B
C
E
D
C
B
A
7 6 5 4
D
DEPARTMENT
SIZE
PROJECT DOCUMENT NUMBER REV
REVIEWER
DESIGNER
IN
OUT
C



TSS=4MS
ESR=9.5M OHM
P3V3_AUX
RB
RA
VO=0.8(1+RA/RB)=3.3V
WORK FREQUENCY = 600KHZ
CURRENT STEP = 10.5A
ESR=9.5M OHM
DESIGN SPECIFICATION
OUTPUT VOLTAGE = 3.3V+/-5%
OUTPUT RIPPLE & NOISE < 50MV
TDC = 19A
TRANSIENT TOLERANCE = 330MV
IMAX = 21A
OCP = 32A
SLEW RATE = 2.5A/US
ISAT=53A@100C
DCR=1.5M OHM
14.3*12.9*8.0
EM-15AM17VG1-QS
BOM NOTE
1ST
2022/5/14 MODIFY
1ST AL003284002/NCP3284AMNTXG/ONSEMI
PC8008 CHANGE TO CH5473KE902
PC569 CHANGE TO CH12206JB00
2ND PR836 EMPTY
2ND AL003889000/IR3889MTRPBF/INFINEON
BOM CHANGE R&C TABLE
BASE ON POC
TO IMPROVE INPUT RIPPLE
Thu Aug 24 14:09:08 2023<NAME_2>
<NAME_1>
MB FABCGTI V02
190 OF 365
PWRGD_P5V_AUX
P12V_AUX
P3V3_AUX
P3V3_AUX
P12V_AUX
P12V_AUX
P3V3_AUX
81 85 270
18985
1K
1%
1/16W
0402LF
CHIP
22UF
16V
X6S
20%
22UF
16V
20%
X 6S
C0805
20%
P3V3_AUX_EN
P3V3_AUX_VCC
P3V3_AUX_VDRV
22UF
16V
22UF
20% 20%
X6S
SMLF
100NH/16A
IND
SMLF
CHIP
0402LF
20%
22UF
PWRGD_P3V3_AUX
0402
P3V3_AUX_FB
X6S
10%
16V
X7R
25V
0.1UF
X6S
C0805
10%
X6S
NC_HICCUP
ICC0805
2.2UF
P3V3_AUX_VOS
1%1K
1/16W
0402LF
CHIP
SW_P3V3_AUX_BOOT_R
5%
EMPTY
5%0
SW_P3V3_AUX_BOOT 5% 0402LF
50V
1000PF
EMPTY
1/16W
0402
CHIP
50V
10V
560UF
20%
1.5UH/53A
SMLF
PWRGD_P3V3_AUX_R1
NCP3284AMNTXG
20%
16V
22UF
16V
10%
0402LF
EMPTY
1/16W
510K
20%
C0805
NCP3284/P3V3_AUX
10%
0.1UF
X7R
25V10V
20%
X6S
C0805
22UF
20%
X6S
22UF
10V
C0805
X6S
C0805
THLF
560UF
6.3V
OSCONOSCON
6.3V
20%
THLF
47K 0.1% 0402LF
10P F 1% NP O
0.22UF
10% X7R
25V
16V
1UF
10%
X7R
0603
0402
X6S
20%
22UF
C0805
22UF
16V
X6S
20%
C0805
22UF
16V
THLF
20%
OSCON
THLF
270UF
20%
X6S
16V16V
22UF
X6S
20%
C0402
25V
X6S
0.1UF
1 CHIP 0402LF
1%
C0603
21.5K
CHIP
0402LF
1%
1/16W
1/16W
EMPTY
1.5K
0402LF
1%
4.7UF
16V
C0603
0
5%
1/16W
CHIP
1/16W
CHIP
5%
0
10%
EMPTY
1% NC_PU9_2
NC_PU9_1
NC_PU9_3
P3V3_AUX_SS
NC_PU9_4
P3V3_AUX_ILIM
P3V3_AUX_MODE
0402
C0805
86.6K
0402
1/16W
5%
C0805
22UF
15K
0.1%
1/16W
CHIP
0402LF
25V
0.1UF
SW_P3V3_AUX_FLT
16V
20%
X6S
270UF
16V16V10%
X6S X6S
C0805
0402LF
0402LF
0402LF
1/16W
20%
0
CHIP
1/16W
IND
1/16W
SW_P3V3_AUX_BOOTR
SW_P3V3_AUX_SW
C0805 C0805
16V
22UF 22UF
C0805
OSCON
22UF
16V
C0805C0805
X6S
20%
16V
22UF
X6S
X6S
20%
16V
PC8014
PC8013
PC2344
PC1599 PC1600
C5015
21R6099
2
1
PR831
21
PR836
PC8008
PC2261
21
PL8045
2
1 PC591
2
1 PC581
2
1
PR832
2
1
PR8073
2
1 PC1869
2
1
2
1 PC1868PC1867PC1866
21
PL8066
21PC569
2
1
PR830
21PR835
21
PC568
2
1 PC577
2
1 PC8071
2
1 PC576
PC2343
2
1 PC571
2
1 PC570
PC2342PC2263
PC8567
PC2262
2
1
PC566PC3
PC2260
21
PR8389
2
1
PR834
2
1
PR833
R1571
2
1
PC1870
31
28
3
5
4
11_18
29
20_24
25
2
7_10-1934
33
36
1
35
37
6
30
27
26
32
PU9
1 2
1 2
GL2
SS
GL1
VDRV
EN
AGND
VOS
PGOOD
PVIN
SW
NC1
PGND
HICCUP#
VSNS-
VCC
PHASE
ILIM
BOOT
FB
VIN
MODE||FSET
NC2
2
1
2
1
2
1
2
1
2
1
2
1
2
1
2
1
2
1
2
1
2
1
2
1
2
1
2
1
2
1 PC1649
2
1
2
1
R3117
2
1
R3118
1
SHEETDATE
23
7 3 2 16 5 4
E
A
B
C
E
D
C
B
A
7 6 5 4
D
DEPARTMENT
SIZE
PROJECT DOCUMENT NUMBER REV
REVIEWER
DESIGNER
OUT
IN
C



Thu Aug 24 10:15:04 2023<NAME_2>
<NAME_1>
MB FABCGTI V02
191 OF 365
Blank
1
SHEETDATE
23
7 3 2 16 5 4
E
A
B
C
E
D
C
B
A
7 6 5 4
D
DEPARTMENT
SIZE
PROJECT DOCUMENT NUMBER REV
REVIEWER
DESIGNER
C



WORK FREQUENCY=600KHZ
SLEW RATE=2A/US
EFFICENCY>90%@TDC
EDC=6.2A
OVER CURRENT PROTECTION=9A
CURRENT STEP=2A
DCR=15MOHM
ISAT=16A@100C
PCMC063-1R5MN
2ND=CV-15I0MZ03
7*7*3
DCR=5M OHM
2ND=CX220Z06Z00
3RD=CX000220000
2022/5/14 MODIFY
3RD AL000548006/TPS548A28RWWR/TI
BOM NOTE
3RD PC118 CHANGE TO CH5222KEB01
BOM CHANGE R&C TABLE
2ND AL053318002/RS53318LR/REEDSEMI
1ST AL008633007/MPQ8633AGLE-C807-Z/MPS
1ST
2ND NA
VOUT=0.6(1+RA/RB)=3.3V
TDC=6A
DC & AC=3.13-3.46V
OUTPUT VOLTAGE=3.3V
PVDD_33_S5 SPECIFICATION
PVDD_33_S5
FCCM/FSW=600KHZ
RA
RB
IRATED=5A@125C
Thu Aug 24 14:09:25 2023<NAME_2>
<NAME_1>
MB FABCGTI V02
192 OF 365
P V DD_33_S 5
P V DD_33_S 5_V CC
P V DD_33_S 5_V CC
P 12V _A UX
81
81
33
1UF
25V
C0402
X 6S
10%
25V
10%
X 6S
C0402
1UF
E MP TY
10%
25V
0402
0.1UF
5%
X7R
1000PF
FM_P W RG D_P V DD33_S 5
SW_PVDD_33_S5_BST_R
50V
16V
22UF
S W _P 12V _A UX _P V DD_33_S 5_FLT
X 6S
20%
X 6S
22UF
C0805
22UF
X 6S
20%
C0402
S MLF
B LM18S N220TN1D/8000MA
X 6S
20%
PVDD_33_S5
10%
0.1UF
X 7R
25V
0402
C0805
16V
22UF
20%
X 6S
C0805
16V
22UF
X 6S
10K
C0805
22UF
16V
20%
16V
56K 1%
NP O
5%100P F 50V
0402
12.4K
1%
1/16W
X 7R
10%
0.1UF
0402
25V
6.98K
1%
CHIP
1/16W
0402LF
22UF
P V DD_33_S 5_FB
P V DD_33_S 5_RE F
P V DD_33_S 5_CS
MP Q 8633A G LE -C807-Z
16V
22UF
20%
CHIP
0402LF
0
1/16WCHIP
5%
P V DD33_S 5_E N
P V DD_33_S 5_MO DE
0402
25V
X 6S
0.1UF
10%
16V
20%
16V
IND
IC
C0805
20%
16V
X 6S
C0805 C0805
X 7R
C0805
X 6S
20%
0402
0402LF
5%
1/16W
0402LF
P W RG D_P V DD33_S 5
0402LF5%0
CHIP1/16W
S W _P V DD_33_S 5_B S T
0.1UF
25V
C0805
1/16W
CHIP
0402LF
X 6S
22UF
IND
S W _P V DD_33_S 5_S W
SMLF1.5UH
 PL72
PR8000
21
10
19
5
20
6
9
11_18
4
7
8
3
1
2
PU55
2
1
PC128
2
1 PC136
2
1 PC135
2
1 PC134
21 R225
2
1
R453PC126
2
1 PC123
2
1 PC130
2
1 PC129
21
PR455
21
PC1322
1
PR454
2
1 PC127
2
1
PR452
2
1 PC120
2
1 PC119
21
PL71
PC6000
2
1C348
2
1
PC118
PC8001 PC8000
C5002
PR6000
21 1 2
VIN2
CS
MODE
TRK_REF
SW
RGND
VCC
AGND
FB
BST
EN
PGND
PGOODVIN1
1 2
21
2
1
2
1
2
1
2
1
21
2
1
1
SHEETDATE
23
7 3 2 16 5 4
E
A
B
C
E
D
C
B
A
7 6 5 4
D
DEPARTMENT
SIZE
PROJECT DOCUMENT NUMBER REV
REVIEWER
DESIGNER
OUT
IN
C



IRM REV1.09
IRM REV1.09
SVI3 ADDRESS=PORT0 (0X2)
EFFICIENCY > 90% @TDC
WORK FREQUENCY=600KHZ
MAX LOAD RELEASE=95A
PVDDCR_SOC_P0 SPECFICATION
DEFAULT POWER-ON VID=0.9V
SVI3 ADDRESS=PORT0 (0X1)
EFFICIENCY > 90% @TDC
WORK FREQUENCY=600KHZ
LOAD-LINE=0.4MOHM
MAX LOAD RELEASE=200A
MAX LOAD STEP=200A
OCP=276A (EDC*1.2)
MIN AC=VID-EDC*LL-110MV
VID=0.75-1.2V
DC=+/-20MV
20220413:
DIFFERENTIAL PAIR
TRACE WIDTH = 10MIL
0X61
MAIN SOURCE:RENESAS BOM
PU42 = TBD/RAA229620GNP#HA0
2ND SOURCE:INFENEON BOM
2022/5/14 MODIFY
BOM NOTE
MAX LOAD STEP=45A
OCP=156A (EDC*1.2)
MIN AC=VID-150MV
MAX AC=VID+150MV
TDC=105A
EDC=130A
RENESAS 0/681 OHM
TRACE SPACING = 5MIL
DIFFERENTIAL PAIR
TRACE WIDTH = 10MIL
TRACE SPACING = 5MIL
DEFAULT POWER-ON VID=0.9V
PVDDCR_CPU0_P0 SPECFICATION
VID=0.55-1.5V
DC=+/-20MV
MAX AC=VID+200MV
TDC=175A
EDC=230A
/75K OHM
VR
INFINEON
MPS
0X4F
PU42 = TBD/XDPE192C3B
PR290 = CS25362FB02
PR531,PR440,PR441 = EMPTY
PC470 = CH5103KEB01
PC463,PC464 = CH12206KB14
PU42 = TBD/MP2857GQKT-001C-Z
PR5 = CS00002JB13
PR440,PR441,PC463,PC464 = EMPTY
PR599 = CS24992FB07
PC7 = CH21006JB10
PC470 =CH5103KEB01
PC469,PC472 = CH31004KB17
PR292,PR314 = CS37502FB05
PR290,PC462,PR531 = EMPTY
3RD SOURCE:MPS BOM
PC462 = CH3104J1B00
PC472,PC469 = CH11006JB00
PR306,PR307 = CS01002FB07
PR5 = CS21002FB06
PR283 IS CHANGED FROM 1K TO 0 OHM
PR306 IS CHANGED FROM 10 TO 0 OHM
PR307 IS CHANGED FROM 10 TO 0 OHM
0X4F
/681 OHM
ADDRESS(7-BIT) CONFIG/R
PMBUS ADDRESS AND CONFIG
20220413:
Thu Aug 24 14:09:03 2023<NAME_2>
<NAME_1>
MB FABCGTI V02
193 OF 365
I17
P V DD18_S 5_P 0
P 3V 3_A UX
P V DDCR_CP U0_P 0
P 3V 3_A UX
P 5V _A UX
P 3V 3_A UX
P V DD18_S 5_P 0
P 12V _A UX
P V DD18_S 5_P 0
P 3V 3_A UX
P V DDCR_S O C_P 0
P V DDCR_CP U0_P 0_P W M2
P V DDCR_CP U0_P 0_P MA LE RT_R5%P V DDCR_CP U0_P 0_P MA LE RT
193
194
194
195
195
195
195
196
196
198
198
198 199
199
199
194
198
196
198
196
194
27
80
27
78
151 193
151
193
194 195 196 198 199
151193
194
195
196
27
27193
82
82
82
27
27193
151
8381
27
82
P V DDCR_CP U0_P 0_IMO N2
P V DDCR_CP U0_P 0_IMO N3
P V DDCR_CP U0_P 0_P W M3
P V DDCR_CP U0_P 0_IMO N4
P V DDCR_CP U0_P 0_P W M4
P V DDCR_CP U0_P 0_IMO N5
P V DDCR_CP U0_P 0_P W M5
P V DDCR_S O C_P 0_IMO N1
P V DDCR_S O C_P 0_P W M1
P V DDCR_S O C_P 0_TE MP 1
P V DDCR_S O C_P 0_E N//A DDR_CFG
P V DDCR_S O C_P 0_IMO N3
P V DDCR_S O C_P 0_P W M3
NC_P V DDCR_CP U0_P 0_IMO N9
NC_P V DDCR_CP U0_P 0_P W M9
P V DDCR_CP U0_P 0_P W M1
P V DDCR_S O C_P 0_IMO N2
V S E NS E _P V DDCR_S O C_P 0_V S E N1
P V DDCR_CP U0_P 0_V INS E N
P V DDCR_CP U0_P 0_V MO N
P V DDCR_CP U0_P 0_P W M6
P W RG D_P V DDCR_CP U0_P 0_R
P V DDCR_S O C_P 0_P W M2
V S E NS E _P V DDCR_CP U0_P 0_V S E N0
NC_P V DDCR_CP U0_P 0_P W M7
NC_P V DDCR_CP U0_P 0_P W M8
P V DDCR_CP U0_P 0_P MS DA _R
P V DDCR_CP U0_P 0_E N_R
SVID _PVD D C R _C PU 0_P0_SVD _R 1
NC_P V DDCR_CP U0_P 0_IMO N8
NC_P V DDCR_CP U0_P 0_IMO N7
P V DDCR_CP U0_P 0_RE S E T_N_R
S V ID_P V DDCR_CP U0_P 0_S V TO _R
P V DDCR_CP U0_P 0_IMO N6
SVID _PVD D C R _C PU 0_P0_SVC _R 1
P V DDCR_CP U0_P 0_P MS CL_R
S V ID_P V DDCR_CP U0_P 0_S V TI_R
P V DDCR_CP U0_P 0_IMO N1
RA A 229620G NP #HA 0
IC
SMLF
1%49.9S V ID_P V DDCR_CP U0_P 0_S V TO
1/16W
0402LFCHIP
1%
0 5%
0402LF
CHIP
0
E MP TY
0402LF0402LF
CHIP
1/16W
0
1/16W
0402LF
CHIP
P V DDCR_CP U0_P 0_E N
CHIP
1/16W
S V ID_P V DDCR_CP U0_P 0_S V TI
10P F
50V
5%
1/16W
50V
5%S V ID_P V DDCR_CP U0_P 0_S V C_R
X 7R
1000P F
5%
0402LF
1/16W
5%
P V DDCR_CP U0_P 0_RE S E T_N
CHIP 1/16W
P V DDCR_CP U0_P 0_O CP _N_R
CHIP0402LF
0402LF
0402
PVDDCR_CPU0_P0/PVDDCR_SOC_P0 VR CONTROLLER
1%
1/16W
0402
S MB _S CM_2_R3_S CL
10%
50V
0402LF
1/16W
S MB _S CM_2_R3_S DA
C ON N 3_210-H P1-030BR 1
CHIP
33
5%
1000P F
CHIP
1/16W
1/16W
0402LF
P W RG D_P V DDCR_S O C_P 0_R
E MP TY
1000P F
1UF
0402
X 7R
3300P F
1000P F
X 7R
50V
0402
0.1UF
P V DDCR_CP U0_P 0_V CCS
0402LF
0
0402
0402
X 7R
0402LF
1/16W
5%
0402
5%
50V
10P F
S MB _S CM_2_R3_S CL
1/16W
P V DDCR_CP U0_P 0_TE MP 0
1%
470P F
0402LF
EMPTY
1/16W
5%
1/16W
CHIP
0
E MP TY
V S E NS E _P V DDCR_S O C_P 0_DP
V S E NS E _V S S _S E NS E _A _P 0
P V DDCR_S O C_P 0_E N
1%
P V DDCR_S O C_P 0_E N_RC
1000P F
CHIP
X 7R
0402
0402
CHIP
THLF
IO
5%
P V DDCR_S O C_P 0_E N_G D
E MP TY
1K
1/16W
1%
6.3V
5%
0402LF
10%
10K
1%
5%
5%0
CHIP 1/16W
25V
1UF
5%
0402LF
0402
0402LF
P JA 3415A E
0402LF
CHIP
1%1
10%
C0402
16V
X 6S
X 6S
20%
10UF
6.3V
C0402
10%
0402
0.1UF
X 7R
25V
10%
X 7R
1/16W 0 0402LF
CHIP 0402LF5%01/16W
0402LF5%01/16WCHIP
0402
50V
10%
0402
50V
470P F
10%
X 7R
E MP TY
1000P F
5%
1/16W
1K 1%
E MP TY
1K1K
5%
10%
0
1K 1% 1/16W0402LF CHIP
X 7R 10%
0402
50V
0402
25V
0.1UF
10%
X 7R
CHIP
0
1/16W
E MP TY
1%
4.99K
1%
1%1K
1/16W
CHIP
0402LF
49.9
1%
1/16W
CHIP
49.9
1K
CHIP
1/16W
1%
681
X 7R
25V
0.1UF
0402LF
CHIP
IC
1/16W
CHIP
1%
1K
0402LF
B S S 138K
IC
1/16W
40.2K 1%
1K
P V DDCR_CP U0_P 0_O CP _N
1/16W
0402LF
1/16W
E MP TY
E MP TY
0402LF
0402LF
1000P F
50V
X 7R
10K
P V DDCR_CP U0_P 0_V CC
5%
1/16W
5%
5%
1/16W
0402LF
50V 5% X 7R
X 7R50V 0402
50V
0402
5%
49.9
5%
1% 1%
0402LF
0
CHIP
0
0402LF
0
CHIP
1/16W
1K
1%
E MP TY
0402
50V
3300P F
0
0402LF
33
0402LF
5%
1/16W
CHIP
P W RG D_P V DDCR_S O C_P 0
1/16W
33 5%
1/16W
0402LF
0402LF
CHIP
1%
CHIP
0402LF 5%
0402LF
CHIP
0402LF
CHIP
V S E NS E _P V DDCR_CP U0_P 0_DP
V S E NS E _V S S _S E NS E _A _P 0
1/16W
E MP TY
49.9
1/16W
10P F
0402LF
S MB _S CM_2_R3_S DA
0402LF49.9 1%
1/16W
1/16W
0402
50V
CHIP
CHIP
0402LF
S V ID_P V DDCR_CP U0_P 0_S V D_R
CHIP
P W RG D_P V DDCR_CP U0_P 0
R6089
PR8006
PR8005
C5011
21C5017
21C5018
40
25
45
46
19
48
47
T H
43
44
23
24
21
22
39
26
18
12
11
10
9
8
7
6
5
4
3
2
1
13
14
20
16
41
15
42
17
27
28
29
30
31
32
33
34
35
36
37
38
PU42
21
PR316
2
1 PC471
2
1 PC470
2
1 PC12
21
PR531
21
PR440
PR441
2
1 PC472
2
1 PC469
21
C467
21
R8311
21
R8308
21
R8309
21
R8310
2
1
PR294
2
1
R8293
2
1
R8289
2
1
R8287
2
1 C298
21
PR306
2
1
PC464
21
PR307
21
R8313
21
PC466
21
C465
2
1 PC7
21
PR314
2
1
PR295
2
1
PR296
21
R82982
1 PR292
21
R8299
2
1 PC462
2
1
PR5
G
PQ13
2
1 PR285
G
PQ17
21
PR290
2
1
PR284
2
1
R8286
21
R8282
2
1 PC13
21
C468
21 R8312
21
R8304
21
PR305
21
R8300
2
1 C302
2
1 C299
2
1
PC463
21
R8301
21
R315
PR599
21R83172
1
PR297
2
1 C461
2
1
PR283
SD
S D
3
2
1
PJ1
S
G
D
G
1
2
3
CS10
PWM10
CS9
PWM9
CS8
PWM8
CS7
PWM7
CS0
PWM0
TEMP1
EN1||ADDR_CFG
TH_GND
OCP_L
CS2
PWM2
CS3
PWM3
PWM11
CS1
RGND1
VSEN1
VDDIO
TEMP0
VINSEN
VMON||IINSEN
VCCS
PWM6
PG0
PWM1
VSEN0
PWM5
PWM4
PMSDA
RGND0
EN0
nPMALERT
SVD
PG1
CS4
CS5
RESET_L
SVTO
CS6
SVC
PMSCL
SVTI
VCC
CS11
SD
21
21
2
1
2
1
1
SHEETDATE
23
7 3 2 16 5 4
E
A
B
C
E
D
C
B
A
7 6 5 4
D
DEPARTMENT
SIZE
PROJECT DOCUMENT NUMBER REV
REVIEWER
DESIGNER
IN
IN
IN
IN
IN
OUT
IN
BI
OUT
OUT
IN
OUT
IN
IN
IN
IN
OUT
IN
BI
OUT
OUT
IN
OUT
IN
OUT
IN
OUT
IN
IN
OUT
OUT
IN
OUT
IN
OUT
IN
OUT
IN
IN
C



PR320,PR321,PR346,PR347,PR353,PR431 = CS00002JB13
PC473_1,PC474_2,PC544_3,PC545_4,PC566_5,PC150_6 = EMPTY
PR446,PR322,PR323,PR348,PR349,PR354,PR432 = CS00002JB13
PR445,PR324,PR325,PR350,PR351,PR355,PR433 = EMPTY
PC473_1,PC474_2,PC544_3,PC545_4,PC566_5,PC150_6 = EMPTY
PU6,PU43,PU46,PU47,PU48,PU10 = AL087000A03/MP87000GMJTH-C11D-Z
3RD SOURCE:MPS BOM
2ND=CC72703MD39
PGL6303.151HLT
ISAT:70A@100C
11.0*7.5*12.5
DCR=1-4,0.105M OHM
2ND=CV+15^0TZ01
DCR=2-3,0.27M OHM
3RD=CVA50^0MZ08
PG2292.500HLT
MAIN=CH122KM8801
ESR=9.0M OHM
7.3*4.3*1.9
PGL6303.151HLT
ISAT:70A@100C
DCR=2-3,0.27M OHM
2ND=CV+15^0TZ01
DCR=1-4,0.105M OHM
11.0*7.5*12.5
PVDDCR_CPU0_P0_PHASE1
BOM NOTE
2ND SOURCE:INFENEON BOM
PU6,PU43,PU46,PU47,PU48,PU10 = AL099390004/ISL99390FRZ-TR5935
MAIN SOURCE:RENESAS BOM
2022/5/14 MODIFY
PU6,PU43,PU46,PU47,PU48,PU10 = AL021590000/TDA21590
PR322,PR323,PR348,PR349,PR354,PR432 = CS00002JB13
PR324,PR325,PR350,PR351,PR355,PR433 = EMPTY
PVDDCR_CPU0_P0_PHASE2
ISAT:70A@100C
6.0*6.1*7.0
DCR=0.09M OHM
2ND=CVA50^0MZ07
ESR=10M OHM
IRIPPLE:5.08A
6.3*8
Thu Aug 24 14:09:03 2023<NAME_2>
<NAME_1>
MB FABCGTI V02
194 OF 365
S W _P 12V _A UX _P V DDCR_CP U0_P 0_FLT
S W _P 12V _A UX _P V DDCR_CP U0_P 0_FLT
P V DDCR_CP U0_P 0
P 12V _A UX
P V DDCR_CP U0_P 0
P V DDCR_CP U0_P 0
P V DDCR_CP U0_P 0_P V CC
P V DDCR_CP U0_P 0_P V CC
P 3V 3_A UXP 5V _A UX
0.22UF
0402LFCHIP
193194195196198199
194
195196193
194
195
193
193
193
193
194
195196193
193194195196198199
194
196
10%
C0402
S W _P V DDCR_CP U0_P 0_B O O T1 5.6
C0402
X 6S
10%10%
S W _P V DDCR_CP U0_P 0_B O O T1_RC1%
1/16W
5.6 S W _P V DDCR_CP U0_P 0_B O O T2_RCS W _P V DDCR_CP U0_P 0_B O O T2
1/16W
0402LF
1%
CHIP
E MP TY
NC_P V DDCR_CP U0_P 0_DNC1
P V DDCR_CP U0_P 0_V CCS
0.1UF
P V DDCR_CP U0_P 0_TE MP 0
10%
THLF
0.1UF
25V
SMLF
IS L99390FRZ-TR5935
P V DDCR_CP U0_P 0_V CC2
560P F
10%
16V
0.22UF
S MLF
S P CA P
0402LF
IND_CP U0_P 0_CP L1
IND
270UF
20%
X 6SX 6S
0402
NC_P V DDCR_CP U0_P 0_G L2_1
S W _P V DDCR_CP U0_P 0_S W 1_RC
25V
1UF
X 6S
CHIP
S W _P V DDCR_CP U0_P 0_P H2
S W _P V DDCR_CP U0_P 0_S W 2
P V DDCR_CP U0_P 0_V O S 2
X 6S
C0805
X 6SX 7R
0402
PVDDCR_CPU0_P0 VR PHASE 1&2
0402LF
1K
1%
CHIP
1/16W
22UF
20%
X 6S
C0805
4V4V
22UF
X 6S
C0805
20%
0.1UF
25V
0402
X 7R
10%
X 7R
0402
10%
S MLF
50NH/86A
O S CO N
16V
270UF
20%20%
THLF
O S CO N
16V
IND
150NH
SMLF
16V
X 7R
4V
220UF
S MLF
S P CA P
20%
4V
22UF
20%
X 6S
C0805
20%
X 6S
C0805
4V
22UF
S P CA P
20%
S MLF
4V
220UF
4V
20%
220UF
S P CA P
S MLF
4V
220UF
20%
220UF
20%
S P CA P
S MLF
4V
SMLF
IND
150NH
X 7R
0402
X 6S
16V
22UF
16V
20%
22UF
20%
22UF
16V
C0402
10%
25V
0.1UF
X 7R
C0402
X 6S
10%
2.2UF
10V
0402LF
2.2
1%
CHIP
1/16W
0402LF
1/16W
8.87K 1%
C0402
X 6S
10%
2.2UF
0
1/16W
22UF
16V
C0805
16V
20%
22UF22UF
20%10%
0402LF
0 5%
CHIP
1/16W
1/8W
E MP TY
1%
1.5
0402LF
IC
X 7R
10%
25V
0402
X 6S
10%
C0402
2.2UF
1%
CHIP
1/16W
2.2
0402LF
IC
X 6S
10%
2.2UF
10V
C0402
8.87K 1%
E MP TY 1/16W
X 7R
10%
0.1UF
25V
0402
0402LF
0
5%
1/16W
E MP TY
0402LF
0
5%
CHIP
1/16W
IND_CP U0_P 0_CP L2
P V DDCR_CP U0_P 0_IMO N1
P V DDCR_CP U0_P 0_LS E T1
NC_P V DDCR_CP U0_P 0_G L1_2
NC_P V DDCR_CP U0_P 0_G L2_2
P V DDCR_CP U0_P 0_P W M1
P V DDCR_CP U0_P 0_IMO N2
P V DDCR_CP U0_P 0_P W M2
P V DDCR_CP U0_P 0_TE MP 0
P V DDCR_CP U0_P 0_LS E T2
10V
0402LF
P V DDCR_CP U0_P 0_V CCS
NC_P V DDCR_CP U0_P 0_DNC2
0402LF
IND_CP U0_P 0_CP L1
10V
1/8W
C0805
E MP TY
P V DDCR_CP U0_P 0_V O S 1
16V
C0805
P V DDCR_CP U0_P 0_V CC1
SMLF
0402
50V
X 6S
20%
C0402
E MP TY
50V
10%
1.5
1%
E MP TY
IND_CP U0_P 0_CP L5
S W _P V DDCR_CP U0_P 0_S W 2_RC
5%
S W _P V DDCR_CP U0_P 0_P H1
S W _P V DDCR_CP U0_P 0_S W 1
560P F
NC_P V DDCR_CP U0_P 0_G L1_1
25V
1UF
25V
0.1UF
IS L99390FRZ-TR5935
C0805C0805
PR447
2
1 PC502_1
2
1 PC500_1
2
1 PC497
PC479
21
PL53
2
1 PC492
2
1 PC491
4
32
1
PL51
2
1
PC489
2
1 PC498
2
1 PC501_2
2
1
PC490
2
1 PC487_1
2
1 PC485_1
2
1 PC483_1
21
PR322
2
1 PC178
PC481_1
2
1 PC479_1
2
1 PC477_C0P0_1
2
1
PR318
21
PR320
2
1 PC475
21
PR324
2
1
PR495
2
1 PC488_2
2
1 PC486_2
2
1 PC484_2
2
1 PC480_2
21
PR325
2
1
PR496
2
1 PC473_1
2
1 PC476
21
PR321
2
1 PC474_2
2
1 PC499_2
2
1 PC496
2
1 PC495
2
1 PC494
2
1 PC108
4
32
1
PL52
2
1 PC482_2
21
PR323
2
1 PC179
1
30
25_29
3
36
10_19
39
34
4
32
40
7_9-20_24
5
37
38
41
6
35
31
33
2
PU6
2
1 PC478_C0P0_2
2
1
PR319
1
30
25_29
3
36
10_19
39
34
4
32
40
7_9-20_24
5
37
38
41
6
35
31
33
2
PU43
PR446PR445
1 2
1 4
32
1 4
32
PGND2
GL2
GL1
DNC
EN
PGND3
VOS
VIN2
PGND1
SW
LSET
IOUT
TOUT_FLT
PVCC
PHASE
VIN1
BOOT
AGND
VCC
REFIN
PWM
PGND2
GL2
GL1
DNC
EN
PGND3
VOS
VIN2
PGND1
SW
LSET
IOUT
TOUT_FLT
PVCC
PHASE
VIN1
BOOT
AGND
VCC
REFIN
PWM
2
1
2
1
1
SHEETDATE
23
7 3 2 16 5 4
E
A
B
C
E
D
C
B
A
7 6 5 4
D
DEPARTMENT
SIZE
PROJECT DOCUMENT NUMBER REV
REVIEWER
DESIGNER
BI
BIBI
BI
OUT
OUT
IN
IN
OUT
IN
OUT
IN
C



DCR=1-4,0.105M OHM
PGL6303.151HLT
ISAT:70A@100C
11.0*7.5*12.5
2ND=CV+15^0TZ01
DCR=2-3,0.27M OHM
DCR=2-3,0.27M OHM
DCR=1-4,0.105M OHM
2ND=CV+15^0TZ01
11.0*7.5*12.5
ISAT:70A@100C
PGL6303.151HLT
PVDDCR_CPU0_P0_PHASE3
PVDDCR_CPU0_P0_PHASE4
Thu Aug 24 14:09:03 2023<NAME_2>
<NAME_1>
MB FABCGTI V02
195 OF 365
S W _P 12V _A UX _P V DDCR_CP U0_P 0_FLT
P V DDCR_CP U0_P 0_P V CC
P V DDCR_CP U0_P 0_P V CC
S W _P 12V _A UX _P V DDCR_CP U0_P 0_FLT
P V DDCR_CP U0_P 0
P V DDCR_CP U0_P 0
193194195196198199
193
194
195196193
193
193194195196198199
193
194
195196193
193
195
194 195
0402 C0402
5.6
CHIP
22UF
20%
X 6S
S W _P V DDCR_CP U0_P 0_S W 3
22UF
0402LF
X 7R
25V
1UF
S W _P V DDCR_CP U0_P 0_P H4
10%
50V
560P F
IS L99390FRZ-TR5935
560P F
P V DDCR_CP U0_P 0_V CCS
P V DDCR_CP U0_P 0_P W M4
P V DDCR_CP U0_P 0_LS E T4
NC_P V DDCR_CP U0_P 0_DNC4
P V DDCR_CP U0_P 0_TE MP 0
P V DDCR_CP U0_P 0_IMO N4
P V DDCR_CP U0_P 0_V CC4
S W _P V DDCR_CP U0_P 0_S W 4
NC_P V DDCR_CP U0_P 0_G L2_4
NC_P V DDCR_CP U0_P 0_G L1_4
S W _P V DDCR_CP U0_P 0_S W 4_RC
P V DDCR_CP U0_P 0_V O S 3
P V DDCR_CP U0_P 0_V CCS
P V DDCR_CP U0_P 0_LS E T3
NC_P V DDCR_CP U0_P 0_DNC3
P V DDCR_CP U0_P 0_IMO N3
P V DDCR_CP U0_P 0_TE MP 0
P V DDCR_CP U0_P 0_P W M3
P V DDCR_CP U0_P 0_V CC3
S W _P V DDCR_CP U0_P 0_S W 3_RC
S W _P V DDCR_CP U0_P 0_P H3
P V DDCR_CP U0_P 0_V O S 4 IND_CP U0_P 0_CP L3
IND_CP U0_P 0_CP L2 IND_CP U0_P 0_CP L3
0402
25V
0.1UF
10%
X 7R
C0402
10V
2.2UF
10%
X 6S
IS L99390FRZ-TR5935
IC
SMLF
1/16WE MP TY
1%8.87K
0402LF
1/16W
CHIP
1%
2.2
0402LF
10%
C0402
10V
2.2UF
X 6S
0402LF
1.5
1%
E MP TY
1/8W
C0402
E MP TY
25V
0.1UF
10%
X 7R
22UF
16V
C0805
X 6S
22UF
20%
16V
C0805
1/16W
CHIP
5%0
0402LF
0402
25V
0.1UF
10%
X 7R
1/16WE MP TY
1%8.87K
0402LF
C0402
10V
2.2UF
10%
X 6S
1/16W
CHIP
1%
2.2
SMLF
IC
C0402
10V
2.2UF
10%
X 6S
0.1UF
1%
0402LF
1.5
E MP TY
1/8W
10%
E MP TY
C0402
50V
20%
16V
C0805
X 6S
16V
C0805
1/16W
CHIP
5%0
0402LF
150NH
IND
SMLF
0402
16V
0.22UF
10%
X 7R
C0805
20%
16V
22UF
X 6S
C0805
X 6S
20%
22UF
4V
C0805
X 6S
20%
22UF
4V
0402
16V
0.22UF
10%
X 7R
150NH
IND
SMLF
16V
22UF
20%
C0805
X 6S
C0805
X 6S
20%
22UF
4V
C0805
X 6S
20%
22UF
4V
PVDDCR_CPU0_P0 VR PHASE 3&4
0402
10%
25V
NC_P V DDCR_CP U0_P 0_G L1_3
NC_P V DDCR_CP U0_P 0_G L2_3
X 6S
20%
10%
X 6S
C0402
1UF
25V
10%
X 6S
1/16W
CHIP
1%
0402LF
S W _P V DDCR_CP U0_P 0_B O O T4 S W _P V DDCR_CP U0_P 0_B O O T4_RC5.6
1%
0402LF
1/16W
S W _P V DDCR_CP U0_P 0_B O O T3 S W _P V DDCR_CP U0_P 0_B O O T3_RC
2
1 PC564_3
2
1 PC562_3
2
1 PC558_3
4
32
1
PL59
2
1
PC560
2
1 PC565_4
2
1 PC563_4
2
1 PC559_4
2
1
PC561
4
32
1
PL60
21
PR351
2
1 PC556_3
2
1 PC554_3
2
1 PC550_3
21
PR348
2
1 PC180
2
1
PR498
2
1 PC552_3
2
1 PC548_C0P0_3
1
30
25_29
3
36
10_19
39
34
4
32
40
7_9-20_24
5
37
38
41
6
35
31
33
2
PU46
2
1
PR344
2
1 PC546
2
1 PC544_3
2
1 PC557_4
2
1 PC553_4
2
1 PC549_C0P0_4
2
1
PR345
21
PR347 1
30
25_29
3
36
10_19
39
34
4
32
40
7_9-20_24
5
37
38
41
6
35
31
33
2
PU47
2
1 PC547
2
1 PC545_4
21
PR346
21
PR350
2
1 PC555_4
2
1 PC551_4
21
PR349
2
1 PC181
2
1
PR499
PGND2
GL2
GL1
DNC
EN
PGND3
VOS
VIN2
PGND1
SW
LSET
IOUT
TOUT_FLT
PVCC
PHASE
VIN1
BOOT
AGND
VCC
REFIN
PWM
1 4
32
1 4
32
PGND2
GL2
GL1
DNC
EN
PGND3
VOS
VIN2
PGND1
SW
LSET
IOUT
TOUT_FLT
PVCC
PHASE
VIN1
BOOT
AGND
VCC
REFIN
PWM
1
SHEETDATE
23
7 3 2 16 5 4
E
A
B
C
E
D
C
B
A
7 6 5 4
D
DEPARTMENT
SIZE
PROJECT DOCUMENT NUMBER REV
REVIEWER
DESIGNER
IN
OUT
BIBI
BI
OUT
OUT
IN
IN
OUT
IN
C



PGL6312.121AHLT
ISAT:60A@100C
2ND=CV+12^0EZ04
DCR=0.17M OHM
6.5*6.5*10.0
PVDDCR_CPU0_P0_PHASE5
DCR=1-4,0.105M OHM
2ND=CV+15^0TZ01
2ND=CV+15^0TZ01
DCR=1-4,0.105M OHM
DCR=2-3,0.27M OHM
11.0*7.5*12.5
ISAT:70A@100C
PGL6303.151HLT
ISAT:70A@100C
PGL6303.151HLT
11.0*7.5*12.5
DCR=2-3,0.27M OHM
PVDDCR_CPU0_P0_PHASE6
Thu Aug 24 14:09:26 2023<NAME_2>
<NAME_1>
MB FABCGTI V02
196 OF 365
P V DDCR_CP U0_P 0_P V CC
S W _P 12V _A UX _P V DDCR_CP U0_P 0_FLT
S W _P 12V _A UX _P V DDCR_CP U0_P 0_FLT
P V DDCR_CP U0_P 0
P V DDCR_CP U0_P 0
P V DDCR_CP U0_P 0_P V CC
193
193
194
195196193
193
193194195196198199
194196
196
193
194
195196193
193194195196198199
C0402
CHIP
5.6
10%
S W _P V DDCR_CP U0_P 0_B O O T5_RCS W _P V DDCR_CP U0_P 0_B O O T5
0402LF
1%
1/16W
5.6 S W _P V DDCR_CP U0_P 0_B O O T6_RCS W _P V DDCR_CP U0_P 0_B O O T6
CHIP
1/16W
0402LF
1%
E MP TY
IND
0402
SMLF
150NH
560P F
1UF
16V
X 6S
C0805
S W _P V DDCR_CP U0_P 0_S W 5_RC
C0402
1.5
C0805
0.1UF
X 7R
C0402
S W _P V DDCR_CP U0_P 0_P H5
0402LF
25V
X 6S
C0805
20%
IS L99390FRZ-TR5935
10%
P V DDCR_CP U0_P 0_P W M5
1/16W
0402LF
2.2
1%
CHIP
1/16W
P V DDCR_CP U0_P 0_V CC6
P V DDCR_CP U0_P 0_IMO N6
2.2UF
10V
10%
X 6S
0402LF
20%
1UF
25V
SMLF
50V
50V
10%
16V
P V DDCR_CP U0_P 0_TE MP 0
P V DDCR_CP U0_P 0_P W M6
P V DDCR_CP U0_P 0_V CCS
IC
X 6S
PVDDCR_CPU0_P0 VR PHASE 5&6
SMLF
IC
IS L99390FRZ-TR5935
4V
22UF
20%
X 6S
C0805
4V
22UF
20%
X 6S
C0805
20%
22UF
16V
X 6S
IND
150NH
SMLF10%
16V
0.22UF
4V
22UF
20%
X 6S
C0805
4V
22UF
20%
X 6S
C0805
X 6S
16V
22UF
20%
X 7R
10%
0.22UF
16V
22UF
20%
E MP TY
10%
560P F
X 6S
10%
2.2UF
10V
C0402
2.2
1%
CHIP
X 6S
10%
2.2UF
10V
C0402
8.87K 1%
E MP TY 1/16W
X 7R
10%
0.1UF
25V
0402
0402LF
0 5%
CHIP
1/16W
1/8W
E MP TY
0402LF
1%
16V
20%
22UF
C0805
X 6S
C0805
22UF
X 6S
10%
25V
0.1UF
X 7R
10%
25V
0402
1%
1.5
0402LF
1/8W
E MP TY
0402LF
0 5%
CHIP
1/16W
C0402
X 6S
10%
2.2UF
10V
C0402
1/16WE MP TY
1%8.87K
0402LF
X 7R
10%
0.1UF
25V
0402
IND_CP U0_P 0_CP L5IND_CP U0_P 0_CP L6
IND_CP U0_P 0_CP L6
S W _P V DDCR_CP U0_P 0_P H6
S W _P V DDCR_CP U0_P 0_S W 5
NC_P V DDCR_CP U0_P 0_G L1_5
NC_P V DDCR_CP U0_P 0_G L2_5
P V DDCR_CP U0_P 0_V CC5
NC_P V DDCR_CP U0_P 0_DNC5
P V DDCR_CP U0_P 0_LS E T5
P V DDCR_CP U0_P 0_IMO N5
P V DDCR_CP U0_P 0_TE MP 0
P V DDCR_CP U0_P 0_V O S 5
S W _P V DDCR_CP U0_P 0_S W 6_RC
P V DDCR_CP U0_P 0_V O S 6
S W _P V DDCR_CP U0_P 0_S W 6
NC_P V DDCR_CP U0_P 0_G L1_6
NC_P V DDCR_CP U0_P 0_G L2_6
NC_P V DDCR_CP U0_P 0_DNC6
P V DDCR_CP U0_P 0_V CCS
P V DDCR_CP U0_P 0_LS E T6
0402
X 7R
0402
16V
22UF
C0805
X 6S
IND
120NH/69A
C0402
IND_CP U0_P 0_CP L0
S MLF
1
30
25_29
3
36
10_19
39
34
4
32
40
7_9-20_24
5
37
38
41
6
35
31
33
2
PU10
2
1 PC576_5
2
1 PC575_5
2
1 PC573_5
4
32
1
PL61
2
1
PC574
2
1 PC166_6
2
1 PC163_6
2
1 PC159_6
2
1
PC161
4
32
1
PL70
21
PL50
2
1 PC572_5
2
1 PC571_5
2
1 PC569_5
2
1 PC184
21
PR354
2
1 PC570_5
2
1 PC568_C0P0_5
2
1
PR352
2
1 PC567
21
PR353
2
1 PC566_5
21
PR355
2
1
PR501
2
1 PC158_6
2
1 PC157_6
2
1 PC154_6
21
PR432
2
1 PC153_6
2
1 PC182
2
1
PR500
21
PR433
1
30
25_29
3
36
10_19
39
34
4
32
40
7_9-20_24
5
37
38
41
6
35
31
33
2
PU48
2
1 PC152_C0P0_6
2
1
PR430
2
1 PC151
21
PR431
2
1 PC150_6
PGND2
GL2
GL1
DNC
EN
PGND3
VOS
VIN2
PGND1
SW
LSET
IOUT
TOUT_FLT
PVCC
PHASE
VIN1
BOOT
AGND
VCC
REFIN
PWM
1 4
32
1 4
321 2
PGND2
GL2
GL1
DNC
EN
PGND3
VOS
VIN2
PGND1
SW
LSET
IOUT
TOUT_FLT
PVCC
PHASE
VIN1
BOOT
AGND
VCC
REFIN
PWM
1
SHEETDATE
23
7 3 2 16 5 4
E
A
B
C
E
D
C
B
A
7 6 5 4
D
DEPARTMENT
SIZE
PROJECT DOCUMENT NUMBER REV
REVIEWER
DESIGNER
OUT
OUT
BIBI
IN
BI
OUT
OUT
IN
IN
IN
C



Thu Aug 24 10:15:08 2023<NAME_2>
<NAME_1>
MB FABCGTI V02
197 OF 365Blank
1
SHEETDATE
23
7 3 2 16 5 4
E
A
B
C
E
D
C
B
A
7 6 5 4
D
DEPARTMENT
SIZE
PROJECT DOCUMENT NUMBER REV
REVIEWER
DESIGNER
C



MAIN SOURCE:RENESAS BOM
PU49,PU50,PU51 = AL021590000/TDA21590
PR360,PR361,PR366 = CS00002JB13
PR358,PR359,PR365 = CS00002JB13
PU49,PU50,PU51 = AL087000A03/MP87000GMJTH-C11D-Z
PC577_7,PC578_8,PC605_9 = EMPTY
2ND SOURCE:INFENEON BOM
PU49,PU50,PU51 = AL099390004/ISL99390FRZ-TR5935
2022/5/14 MODIFY
PC577_7,PC578_8,PC605_9=EMPTY
PR362,PR363,PR367=EMPTY
PR360,PR361,PR366 = CS00002JB13
PVDDCR_SOC_P0_PHASE2
2ND=CC72703MD39
6.3*8
IRIPPLE:5.08A
ESR=10M OHM
6.0*6.1*7.0
ISAT:70A@100C
PR362,PR363,PR367 = EMPTY
3RD SOURCE:MPS BOM
BOM NOTE
ISAT:70A@100C
PGL6303.151HLT
11.0*7.5*12.5
DCR=1-4,0.105M OHM
DCR=2-3,0.27M OHM
2ND=CV+15^0TZ01
3RD=CVA50^0MZ08
DCR=0.09M OHM
PG2292.500HLT
2ND=CVA50^0MZ07
2ND=CH747LM8822
7.3*4.3*1.9
ESR=4.5M OHM
ISAT:70A@100C
PGL6303.151HLT
11.0*7.5*12.5
DCR=1-4,0.105M OHM
DCR=2-3,0.27M OHM
2ND=CV+15^0TZ01
PVDDCR_SOC_P0_PHASE1
Thu Aug 24 14:09:04 2023<NAME_2>
<NAME_1>
MB FABCGTI V02
198 OF 365
S W _P 12V _A UX _P V DDCR_S O C_P 0_FLT
P V DDCR_CP U0_P 0_P V CC
P V DDCR_CP U0_P 0_P V CC
P V DDCR_S O C_P 0
P V DDCR_S O C_P 0
P 12V _A UX
P V DDCR_S O C_P 0
S W _P 12V _A UX _P V DDCR_S O C_P 0_FLT
198
199193
193194195196198199
198
199193
193
193194195196198199
193
193
199 198
198
193
X 7R X 6S
20%
16V
22UF
0402LF
E MP TY
1/8W
1.5
S W _P V DDCR_S O C_P 0_S W 1_RC
S W _P V DDCR_S O C_P 0_B O O T1_RC1%
0402
5.6
20%
C0805
X 6S
X 6S
C0805
16V
22UF
16V
20%
25V
10%
IS L99390FRZ-TR5935
C0402
E MP TY
0402
IND
C0805
X 6S
20%
16V 20%
270UF
IND
C0805
X 6S
22UF22UF
16V16V
20% 20% 20%
16V
1UF 22UF
C0402 C0805
0.22UF
16V
22UF 22UF
560P F
10%
S W _P V DDCR_S O C_P 0_S W 1
S W _P V DDCR_S O C_P 0_P H1
P V DDCR_S O C_P 0_TE MP 1
0402LF
P V DDCR_S O C_P 0_V CC1
PVDDCR_SOC_P0 VR PHASE 1&2
NC_P V DDCR_S O C_P 0_DNC2
P V DDCR_CP U0_P 0_V CCS
P V DDCR_S O C_P 0_TE MP 1
P V DDCR_S O C_P 0_P W M2
NC_P V DDCR_S O C_P 0_G L2_2
NC_P V DDCR_S O C_P 0_G L1_2
P V DDCR_S O C_P 0_V O S 2
S W _P V DDCR_S O C_P 0_S W 2_RC
P V DDCR_S O C_P 0_V O S 1
P V DDCR_CP U0_P 0_V CCS
NC_P V DDCR_S O C_P 0_DNC1
P V DDCR_S O C_P 0_IMO N1
P V DDCR_S O C_P 0_P W M1
P V DDCR_S O C_P 0_LS E T1
NC_P V DDCR_S O C_P 0_G L2_1
NC_P V DDCR_S O C_P 0_G L1_1
IND_S O C_P 0_CP L3 IND_S O C_P 0_CP L2
IND_S O C_P 0_CP L2
P V DDCR_S O C_P 0_LS E T2
10%
25V
0.1UF
X 7R
0402
1/16WE MP TY
0402LF
8.87K 1%
C0402
1/16W
CHIP
1%
2.2
10%
X 6S
C0402
10V
2.2UF
1/16W
5%
CHIP
0
0402LF
0402LF
1.5
1%
E MP TY
1/8W
0402 C0402
X 6S X 6S
0402LF
5%
1/16W
CHIP
0
25V
0402
X 7R
10%
0.1UF
1/16WE MP TY
1%8.87K
10%
X 6S
C0402
10V
2.2UF
2.2
1/16W
CHIP
1%
0402LF
10%
X 6S
C0402
10V
2.2UF
IC
10%
X 7R
0.1UF
1%
50V
C0805
10%
16V
0.22UF
0402
X 7R
150NH
IND
SMLF
20%
C0805
X 6S
20%
C0805
X 6S
22UF
4V
20%
C0805
X 6S
22UF
4V
S MLF
2.5V
20%
E MP TY
470UF
S MLF
S P CA P
20%
2.5V
470UF
S MLF
2.5V
470UF
20%
S P CA P
16V
10%
X 7R
SMLF
150NH
O S CO N
THLF
16V
50NH/86A
S MLF
25V
10%
X 7R
0402
0.1UF
10%
25V
0.1UF
0402
X 7R
C0805
X 6S
20%
22UF
4V
1/16W
CHIP
1%
1K
0402LF
C0805
X 6S
20%
22UF
4V
10%
C0402
50V
560P F
E MP TY
SMLF
IC
S W _P V DDCR_S O C_P 0_P H2
S W _P V DDCR_S O C_P 0_S W 2
C0805
1UF
25V
C0805
10%
0.1UF
P V DDCR_S O C_P 0_IMO N2
P V DDCR_S O C_P 0_V CC2
0402LF
2.2UF
10V
10%
X 6S
SMLF
IS L99390FRZ-TR5935
25V
X 6S X 6S
10%
25V
X 6S
22UF
22UF
16V
20%
16V
22UF
CHIP 0402LF
1/16W
S W _P V DDCR_S O C_P 0_B O O T1
1%
0402LF
1/16W
CHIP
S W _P V DDCR_S O C_P 0_B O O T2 S W _P V DDCR_S O C_P 0_B O O T2_RC5.6
20%
X 6S
C0805
PC8010
PC8009
1
30
25_29
3
36
10_19
39
34
4
32
40
7_9-20_24
5
37
38
41
6
35
31
33
2
PU50
2
1 PC187
PR334
2
1 PC602_1
PC583
21
PL65
2
1 PC596PC593_1
2
1 PC598
2
1 PC603_2
2
1 PC600_2
PC595_2
2
1 PC592_2
4
32
1
PL64
2
1 PC591_1
2
1 PC589_1
2
1 PC587_1
2
1 PC185
2
1
PR502
2
1 PC585_1
1
30
25_29
3
36
10_19
39
34
4
32
40
7_9-20_24
5
37
38
41
6
35
31
33
2
PU49
2
1 PC581_SOP0_1
2
1
PR356
2
1 PC579
21
PR358
21
PR362
2
1 PC586_2
21
PR363
2
1 PC582_SOP0_2
2
1
PR357
2
1 PC580
21
PR359
2
1 PC604_1
2
1 PC599
4
32
1
PL63
2
1
PC593
2
1 PC601
2
1 PC597
2
1
PC594
21
PR360
2
1 PC583_1
2
1 PC577_7
2
1 PC590_2
2
1 PC588_2
2
1 PC584_2
21
PR361
2
1
PR503
2
1 PC578_8
PGND2
GL2
GL1
DNC
EN
PGND3
VOS
VIN2
PGND1
SW
LSET
IOUT
TOUT_FLT
PVCC
PHASE
VIN1
BOOT
AGND
VCC
REFIN
PWM
1 2
1 4
32
1 4
32
PGND2
GL2
GL1
DNC
EN
PGND3
VOS
VIN2
PGND1
SW
LSET
IOUT
TOUT_FLT
PVCC
PHASE
VIN1
BOOT
AGND
VCC
REFIN
PWM
2
1
2
1
2
1
1
SHEETDATE
23
7 3 2 16 5 4
E
A
B
C
E
D
C
B
A
7 6 5 4
D
DEPARTMENT
SIZE
PROJECT DOCUMENT NUMBER REV
REVIEWER
DESIGNER
OUT
IN
BI
BI
OUT
OUT
IN
BI
IN
OUT
IN
C



PVDDCR_SOC_P0_PHASE3
DCR=1-4,0.105M OHM
DCR=2-3,0.27M OHM
2ND=CV+15^0TZ01
11.0*7.5*12.5
ISAT:70A@100C
PGL6303.151HLT
2ND=CV+22Y0EZ01
HCME656510Q-221QL
DCR=0.17M OHM
6.5*6.5*10.0
ISAT:30A@100C
Thu Aug 24 14:09:04 2023<NAME_2>
<NAME_1>
MB FABCGTI V02
199 OF 365
P V DDCR_S O C_P 0
S W _P 12V _A UX _P V DDCR_S O C_P 0_FLT
P V DDCR_CP U0_P 0_P V CC
198
193
198
193
193
193194195196198
C0402
10%
25V
1UFIS L99390FRZ-TR5935
P V DDCR_S O C_P 0_V CC3
1%
5.6 S W _P V DDCR_S O C_P 0_B O O T3_RCS W _P V DDCR_S O C_P 0_B O O T3
CHIP 0402LF
1/16W
1%
1.5
C0402
10%
X 7R
PVDDCR_SOC_P0 VR PHASE 3
IC
SMLF
0402 C0805
X 6S
22UF
16V
20%
22UF
C0805
X 6S
16V
20%
C0805
22UF
16V
20%
X 7R
10%
0.22UF
16V
0402
4V
20%
X 6S
C0805
22UF
4V
22UF
20%
X 6S
C0805
SMLF
150NH
IND
0.22UH/33A
22UF
16V
20%
X 6S
10%
2.2UF
10V
C04020402LF
2.2
1%
CHIP
1/16W
10%
2.2UF
10V
C0402
X 6S
560P F
50V
E MP TY
0402LF
0 5%
CHIP
1/16W
1/8W
E MP TY
1%
0402LF
0402LF
8.87K
E MP TY 1/16W
X 7R
10%
0.1UF
25V
0402
IND_S O C_P 0_CP L3IND_S O C_P 0_CP L0
S W _P V DDCR_S O C_P 0_P H3
P V DDCR_S O C_P 0_IMO N3
S W _P V DDCR_S O C_P 0_S W 3_RC
P V DDCR_S O C_P 0_V O S 3
NC_P V DDCR_S O C_P 0_G L2_3
NC_P V DDCR_S O C_P 0_G L1_3P V DDCR_S O C_P 0_LS E T3
NC_P V DDCR_S O C_P 0_DNC3
P V DDCR_S O C_P 0_TE MP 1
P V DDCR_S O C_P 0_P W M3
P V DDCR_CP U0_P 0_V CCS
IND
SMLF
X 6SX 6S
10%
25V
S W _P V DDCR_S O C_P 0_S W 3
C0805
X 6S
0.1UF
PL62
PC612_3
2
1
PC612
2
1 PC614_3
2
1 PC607_SOP0_3
2
1
PR364
2
1 PC606
2
1 PC188
21
PR367
2
1
PR505
2
1 PC605_9
1
30
25_29
3
36
10_19
39
34
4
32
40
7_9-20_24
5
37
38
41
6
35
31
33
2
PU51
2
1 PC609_3
2
1 PC613_3
2
1 PC611_3
2
1 PC615_3
4
32
1
PL66
2
1 PC610_3
2
1 PC608_3
21
PR366
21
PR365 21
PGND2
GL2
GL1
DNC
EN
PGND3
VOS
VIN2
PGND1
SW
LSET
IOUT
TOUT_FLT
PVCC
PHASE
VIN1
BOOT
AGND
VCC
REFIN
PWM
1 4
321 2
1
SHEETDATE
23
7 3 2 16 5 4
E
A
B
C
E
D
C
B
A
7 6 5 4
D
DEPARTMENT
SIZE
PROJECT DOCUMENT NUMBER REV
REVIEWER
DESIGNER
OUT
IN
BI
OUT
IN
C



MAX LOAD RELEASE=37A
EFFICIENCY > 90% @TDC
IRM REV1.09
IRM REV1.09
SVI3 ADDRESS=PORT1 (0X2)
OCP=168A (EDC*1.2)
DEFAULT POWER-ON VID=1.1V
PVDDIO_P0 SPECFICATION
EFFICIENCY > 90% @TDC
SVI3 ADDRESS=PORT1 (0X1)
WORK FREQUENCY=600KHZ
LOAD-LINE=0.4MOHM
MAX LOAD RELEASE=200A
MAX LOAD STEP=200A
OCP=276A (EDC*1.2)
VID=0.9-1.2V
DC & AC=+/-80MV
PR68 IS CHANGED FROM 10 TO 0 OHM
20220413:
/66.5K
/1.07K
TRACE SPACING = 5MIL
TRACE WIDTH = 10MIL
DIFFERENTIAL PAIR
DIFFERENTIAL PAIR
TRACE SPACING = 5MIL
TRACE WIDTH = 10MIL
MAX LOAD STEP=44A
TDC=120A
EDC=140A
EDC=230A
TDC=175A
DC=+/-20MV
MAX AC=VID+200MV
VID=0.55-1.5V
PVDDCR_CPU1_P0 SPECFICATION
MIN AC=VID-EDC*LL-110MV
DEFAULT POWER-ON VID=0.9V
WORK FREQUENCY=600KHZ
MPS 0X4E
0X4E
VR
INFINEON
RENESAS
PC67 = CH3104J1B00
2022/5/14 MODIFY
PU12 = TBD/RAA229620GNP#HA0
PC68,PC71 = CH12206KB14
PC77,PC78 = CH11006JB00
PC76 = CH5103KEB01
PR67 = CS21072FB04
PR68,PR69 = CS01002FB07
PR532,PR32 = EMPTY
PR54 = CS21002FB06
PR53 = CS25362FB02
PU12 = TBD/XDPE192C3B
PR532,PR32 = EMPTY
PC76=CH5103KEB01
PC74 = CH21006JB10
PC68,PC71 = EMPTY
PC77,PC78 = CH31004KB17
PR600 = CS24992FB07
PR74 = CS37502FB05
PR67 = CS36652FB03
PR54 = CS00002JB13
PR53,PC67 = EMPTY
3RD SOURCE:MPS BOM
20220413:
BOM NOTE
MAIN SOURCE:RENESAS BOM
2ND SOURCE:INFENEON BOM
PU12 = TBD/MP2857GQKT-001B-Z
PR40 IS CHANGED FROM 1K TO 0 OHM
PR69 IS CHANGED FROM 10 TO 0 OHM
1/1.96K
CONFIG/R
0X62
ADDRESS(7-BIT)
PMBUS ADDRESS AND CONFIG
Thu Aug 24 14:09:26 2023<NAME_2>
<NAME_1>
MB FABCGTI V02
200 OF 365
I6
P V DDCR_CP U1_P 0
P V DD18_S 5_P 0
P 3V 3_A UX
P 5V _A UX
P V DD18_S 5_P 0
P 3V 3_A UX
P V DD18_S 5_P 0
P 3V 3_A UX
P V DDIO _P 0
P 3V 3_A UX
P 12V _A UX
201
0402LF
1515%
201
201
202
202
202
202
203
203
205
205
206
206
206
206
201
205
203
205
203
27
82
27
82
78
81
27
201 202 203 205 206
205 206
201 202 203
8382
81
82
27207
27
27
151
27
P V DDCR_CP U1_P 0_IMO N2
P V DDCR_CP U1_P 0_P W M2
P V DDCR_CP U1_P 0_IMO N3
P V DDCR_CP U1_P 0_P W M3
P V DDCR_CP U1_P 0_IMO N4
P V DDCR_CP U1_P 0_P W M4
P V DDCR_CP U1_P 0_IMO N5
P V DDCR_CP U1_P 0_P W M5
P V DDIO _P 0_IMO N1
P V DDIO _P 0_P W M1
P V DDCR_CP U1_P 0_E N1_A DDR_CFG
P V DDCR_CP U1_P 0_O CP _N_R
P V DDIO _P 0_IMO N3
P V DDIO _P 0_P W M3
P V DDIO _P 0_IMO N4
P V DDIO _P 0_P W M4
P V DDCR_CP U1_P 0_P W M1
P V DDIO _P 0_IMO N2
P V DDCR_CP U1_P 0_V MO N
P V DDCR_CP U1_P 0_P W M6
P W RG D_P V DDCR_CP U1_P 0_R
P V DDIO _P 0_P W M2
NC_P V DDCR_CP U1_P 0_P W M7
NC_P V DDCR_CP U1_P 0_P W M8
S MB _DIO _P V DDCR_CP U1_P 0_R
P V DDCR_CP U1_P 0_E N_R
P V DDCR_CP U1_P 0_S MB _A LE RT_R
SVID _PVD D C R _C PU 1_P0_SVD _R 1
P W RG D_P V DDIO _P 0_R
NC_P V DDCR_CP U1_P 0_IMO N8
NC_P V DDCR_CP U1_P 0_IMO N7
S V ID_P V DDCR_CP U1_P 0_S V TO _R
P V DDCR_CP U1_P 0_IMO N6
SVID _PVD D C R _C PU 1_P0_SVC _R 1
S MB _CLK _P V DDCR_CP U1_P 0_R
S V ID_P V DDCR_CP U1_P 0_S V TI_R
P V DDCR_CP U1_P 0_V CC
P V DDCR_CP U1_P 0_IMO N1
SMLF
RA A 229620G NP #HA 0IC
1%49.9
S V ID_P V DDCR_CP U1_P 0_S V TO
1/16WCHIP
0402LF
FM_P V DDCR_CP U1_P 0_E N
0402LF
S V ID_P V DDCR_CP U1_P 0_S V D_R
P W RG D_P V DDCR_CP U1_P 0
1/16W
0
E MP TY
1/16W
CHIP
1000P F
0402LF
X 7R
0402
3300P F
0402LF5%
100
P V DDCR_CP U1_P 0_RE S E T_N
1/16WCHIP 0402LF1%
PVDDCR_CPU1_P0/PVDDIO_P0 VR CONTROLLER
B S S 138K
P W RG D_P V DDIO _P 0
V S E NS E _P V DDCR_CP U1_P 0_V S E N0
X 7R
0402
1%
1%
0402LF
X 7R
10%
50V
0402LF
5%
V S E NS E _P V DDCR_CP U1_P 0_DP
1/16W
V S E NS E _P V DDIO _P 0_V S E N1
S MB _S CM_2_R5_S CL
P V DDCR_CP U1_P 0_V CCS
P V DDIO _P 0_TE MP 1
P V DDCR_CP U1_P 0_RE S E T_N_R
P V DDCR_CP U1_P 0_TE MP 0
P V DDCR_CP U1_P 0_V INS E N
5%
0402LF
CHIP 1/16W
5%
50V
5%
1/16W
1/16W
P V DDCR_CP U1_P 0_S MB _A LE RT
E MP TY
0
0402LF
0402LF
5%
0402
E MP TY
1/16W
50V
X 7R
50V5%
0402X 7R
40.2K
CHIP
0402
50V
X 7R
CHIP
1/16W
0402LF1%
49.9
CHIP
CHIP
1/16W
0402LF
1/16W
0
0
50V
25V
20%
C0402
10K
1%
1/16W
P V DDIO _P 0_E N
5%
0
50V
5%
CHIP
1/16W
0402LF
1/16W
1000P F
0402
0402LF
0
5%
P V DDCR_CP U1_P 0_O CP _N
CHIP 1/16W 0
1/16W
0402LF
0.1UF
25V
CHIP1
1/16W
X 6S
10%
1UF
16V
C0402
6.3V
10UF
X 6S
X 7R
10%
0.1UF
25V
0402
10%
X 7R
0402
0.1UF
50V0402LF1K
CHIP
0 5%
1000P F 50V
5%
X 7R
10%
0402
1/16W 0402LF0 5%
CHIP 0402LF0 5%1/16W
X 7R
10%
470P F
50V
0402
0402
470P F
0402LF1K 1% CHIP
3300P F
10%
1K 1%
5% 0402LF
1UF 10%0402X 7R
10%
X 7R
25V
0.1UF
0402
1/16W
0402LF
4.99K
1%
E MP TY
0402
E MP TY
5%
50V
CHIP
1K 1%
0402LF
0 5%
CHIP
1/16W
0402
X 7R
10%
0402LF
1%1%
1/16W
E MP TY
0402LF
E MP TY
1/16W
50V
E MP TY
5%
10P F
0402
50V
E MP TY
10P F
0402
E MP TY
0402LF
1%
1/16W
1% 0402LF
CHIP 1/16W
1%
49.9
0402LF
CHIP 1/16W
1%
1/16W
0402LF
1K
1%
CHIP
0402LF
P JA 3415A E
IC
1.96K
1%
1/16W
1%0402LF
10K
CHIP
IC
V S E NS E _V S S _S E NS E _C_P 0
V S E NS E _P V DDIO _P 0_DP
V S E NS E _V S S _S E NS E _B _P 0
6.3V
0402LF
1000P F
1K
1%
1K 1K1K1K
1/16W
1%
0402
CHIP
5%0
0
49.9
1/16W
0402LF5%
CHIP
33
5%33
5%
1/16W
1000P F
1/16W
S MB _S CM_2_R5_S DA
X 7R
EMPTY
0402LF
CHIP
CHIP
49.9
P V DDIO _P 0_E N_R
CHIP
P V DDIO _P 0_E N_G
1000P F
0402
1/16W
CHIP 0402LF
0402LF
1/16WCHIP
1000P F
CHIP
5%
0402LF
E MP TY
1/16W
1%
CHIP
33
10P F
CHIP
S V ID_P V DDCR_CP U1_P 0_S V TI
50V
5%
CHIP
5%
0402LF0
CHIP 1/16W
5%
0402LF
S V ID_P V DDCR_CP U1_P 0_S V C_R
1/16W
R6086
PR8007
PR8008
21C5004
21C5005
C5013
40
25
45
46
19
48
47
T H
43
44
23
24
21
22
39
26
18
12
11
10
9
8
7
6
5
4
3
2
1
13
14
20
16
41
15
42
17
27
28
29
30
31
32
33
34
35
36
37
38
PU12
21PR76
2
1
PC75
2
1
PC76
2
1 PC14
2
1 PC15
21C807021R8056
21R8057
21R8058
21C8069
21R8071
21
PR62
21
R61
21R8072
21R8073
2
1
PC68
21PR68
21
PR32
PR532
2
1 PC77
2
1 PC78
21
R8075
21PR69
2
1
PC71
21R8070
21
R8063
21
R8064
21
PC73
2
1
PC74PR600
21C807221R8065
21R8066
21
PR74
2
1
PC67
2
1
R8048
2
1
R8045
2
1
R8043
2
1
PR41
21PR51
2
1 C305
2
1 C304
2
1 C303
2
1
R8042
2
1
PR40
21PR49
21PR52
21PR50
2
1
PR55
G
PQ10
2
1 PR67
21
PR53
2
1
PR54
G
PQ14
2
1 C8066
21
R8047
SD
S D
S
G
D
G
CS10
PWM10
CS9
PWM9
CS8
PWM8
CS7
PWM7
CS0
PWM0
TEMP1
EN1||ADDR_CFG
TH_GND
OCP_L
CS2
PWM2
CS3
PWM3
PWM11
CS1
RGND1
VSEN1
VDDIO
TEMP0
VINSEN
VMON||IINSEN
VCCS
PWM6
PG0
PWM1
VSEN0
PWM5
PWM4
PMSDA
RGND0
EN0
nPMALERT
SVD
PG1
CS4
CS5
RESET_L
SVTO
CS6
SVC
PMSCL
SVTI
VCC
CS11
SD
21
21
2
1
2
1
1
SHEETDATE
23
7 3 2 16 5 4
E
A
B
C
E
D
C
B
A
7 6 5 4
D
DEPARTMENT
SIZE
PROJECT DOCUMENT NUMBER REV
REVIEWER
DESIGNER
OUT
OUT
IN
OUT
IN
OUT
BI
IN
IN
IN
OUT
IN
IN
IN
IN
OUT
OUT
IN
OUT
IN
OUT
IN
OUT
IN
OUT
IN
OUT
IN
OUT
IN
OUT
IN
OUT
IN
IN
OUT
IN
IN
IN
C



PR84,PR83,PR92,PR91,PR96,PR421 = EMPTY
3RD SOURCE:MPS BOM
PR443,PR81,PR82,PR89,PR90,PR95,PR420 = CS00002JB13
PC84_1,PC83_2,PC114_3,PC113_4,PC132_5,PC111_6 = EMPTY
PU13,PU2,PU15,PU14,PU16,PU11 = AL087000A03/MP87000GMJTH-C11D-Z
PR442,PR84,PR83,PR92,PR91,PR96,PR421 = EMPTY
PC84_1,PC83_2,PC114_3,PC113_4,PC132_5,PC111_6 = EMPTY
IRIPPLE:5.08A
PVDDCR_CPU1_P0_PHASE2
2ND=CVA50^0MZ07
3RD=CVA50^0MZ08
6.0*6.1*7.0
DCR=0.09M OHM
PG2292.500HLT
ISAT:70A@100C
ESR=10M OHM
11.0*7.5*12.5
DCR=1-4,0.105M OHM
DCR=2-3,0.27M OHM
2ND=CV+15^0TZ01
6.3*8
7.3*4.3*1.9
ESR=9M OHM
MAIN=CH122KM8801
PGL6303.151HLT
ISAT:70A@100C
11.0*7.5*12.5
DCR=1-4,0.105M OHM
DCR=2-3,0.27M OHM
2ND=CV+15^0TZ01
PVDDCR_CPU1_P0_PHASE1
ISAT:70A@100C
PGL6303.151HLT
2ND=CC72703MD39
MAIN SOURCE:RENESAS BOM
BOM NOTE
PU13,PU2,PU15,PU14,PU16,PU11=AL099390004/ISL99390FRZ-TR5935
2022/5/14 MODIFY
PR78,PR77,PR86,PR85,PR93,PR7 = CS00002JB13
PR82,PR81,PR90,PR89,PR95,PR420 = CS00002JB13
PU13,PU2,PU15,PU14,PU16,PU11 = AL021590000/TDA21590
2ND SOURCE:INFENEON BOM
Thu Aug 24 14:09:04 2023<NAME_2>
<NAME_1>
MB FABCGTI V02
201 OF 365
P V DDCR_CP U1_P 0
P 12V _A UX
P V DDCR_CP U1_P 0
P V DDCR_CP U1_P 0
S W _P 12V _A UX _P V DDCR_CP U1_P 0_FLT
S W _P 12V _A UX _P V DDCR_CP U1_P 0_FLT
P V DDCR_CP U1_P 0_P V CCP 3V 3_A UXP 5V _A UX
P V DDCR_CP U1_P 0_P V CC
201
202
203
201
200
200
201202
203200
200
201202
203200
200201202203205206
200
200201202203205206
C0402
X 6S
10%
25V
1UF
5.6
S W _P V DDCR_CP U1_P 0_B O O T1_RS W _P V DDCR_CP U1_P 0_B O O T1
1/16W
1%
CHIP
0402LF
5.6
S W _P V DDCR_CP U1_P 0_B O O T2_RS W _P V DDCR_CP U1_P 0_B O O T2
CHIP
1% 1/16W
0402LF
NC_P V DDCR_CP U1_P 0_G L2_1
P V DDCR_CP U1_P 0_LS E T1
X 6S
C0805
0.22UF
0.22UF
IS L99390FRZ-TR5935
10%
PVDDCR_CPU1_P0 VR PHASE 1&2
0402LF
1K
1%
CHIP
1/16W
X 6S
4V
22UF
20%
C0805
10%
X 7R
0402
25V
0.1UF
4V
22UF
20%
X 6S
C0805
X 7R
10%
0.1UF
25V
0402
50NH/86A
S MLF
IND
O S CO N
20%
THLF
270UF
16V
4V
22UF
20%
X 6S
C0805
S MLF
4V
220UF
20%
S P CA P
S MLF
4V
220UF
20%
S P CA P
4V
S MLF
S P CA P
20%
220UF
S P CA P
20%
4V
220UF
S MLF
4V
220UF
S P CA P
20%
S MLF
4V
22UF
20%
X 6S
C0805
20%
THLF
O S CO N
270UF
16V
C0805
X 6S
22UF
16V
20%
X 6S
C0805
22UF
16V
20%
SMLF
150NHIND
10%
X 7R
16V
0402
C0805
22UF
16V
20%
X 6S
10%
X 6S
25V
1UF
E MP TY
10%
560P F
50V
C0402
0402
25V
0.1UF
X 7R
0
1/16W
5%
0402LF
CHIP
C0805
X 6S
22UF
16V
20%
22UF
16V
20%
1/8W
1%
1.5
C0805
X 6S
22UF
16V
20%
IND
SMLF
150NH
X 7R
0402
0402LF
0
CHIP
1/16W
5%
E MP TY
10%
560P F
E MP TY
1/8W
1%
1.5
0402LF
10%
0.1UF
25V
0402
SMLF
IC
IS L99390FRZ-TR5935
SMLF
IC
X 6S
10%
2.2UF
10V
C04020402LF
2.2
1%
CHIP
1/16W
0402LF
0
5%
E MP TY
1/16W
X 6S
10%
2.2UF
10V
C0402
0402LF
0
5%
CHIP
1/16W
0402LF
8.87K
1%
E MP TY
1/16W
2.2UF
X 6S
10%
10V
C0402
1/16W
0402LF
2.2
1%
CHIP
X 7R
10%
0.1UF
25V
0402
X 6S
10%
2.2UF
10V
C0402
1/16W
E MP TY
1%
8.87K
0402LF
X 7R
10%
0.1UF
25V
0402
IND_CP U1_P 0_CP L1
IND_CP U1_P 0_CP L2
IND_CP U1_P 0_CP L5
NC_P V DDCR_CP U1_P 0_G L1_1
S W _P V DDCR_CP U1_P 0_B O O TR1
NC_P V DDCR_CP U1_P 0_DNC1
P V DDCR_CP U1_P 0_V CC1
P V DDCR_CP U1_P 0_V O S 1
IND_CP U1_P 0_CP L1
S W _P V DDCR_CP U1_P 0_S W 2_RC
NC_P V DDCR_CP U1_P 0_G L2_2
NC_P V DDCR_CP U1_P 0_G L1_2
S W _P V DDCR_CP U1_P 0_B O O TR2
P V DDCR_CP U1_P 0_V O S 2
S W _P V DDCR_CP U1_P 0_S W 2
P V DDCR_CP U1_P 0_V CC2
NC_P V DDCR_CP U1_P 0_DNC2
P V DDCR_CP U1_P 0_P W M1
P V DDCR_CP U1_P 0_IMO N1
P V DDCR_CP U1_P 0_TE MP 0
P V DDCR_CP U1_P 0_P W M2
P V DDCR_CP U1_P 0_TE MP 0
P V DDCR_CP U1_P 0_LS E T2
P V DDCR_CP U1_P 0_V CCS
P V DDCR_CP U1_P 0_IMO N2
P V DDCR_CP U1_P 0_V CCS
C0402
50V
10%
16V
X 7R
S W _P V DDCR_CP U1_P 0_S W 1
C0402
0402LF
E MP TY
S W _P V DDCR_CP U1_P 0_S W 1_RC
PR444
2
1
PC105_1
2
1
PC102_1
2
1
PC99
21 PL12
2
1
PC104
2
1
PC108_2
2
1 PC100
2
1 PC98
2
1 PC97
2
1 PC102
2
1
PC106_2
2
1
PC91_1
4
32
1
PL10
2
1 PC92
2
1
PC89_1
2
1
PC87_1
2
1 PC189
PR82
2
1
PC85_1
21
PR84
2
1
PC96_2
2
1
PC93_2
2
1
PR506
2
1
PC90_2
2
1 PC94
21
PR83
PR81
2
1
PR507
2
1
PC86_2
1
30
25_29
3
36
10_19
39
34
4
32
40
7_9-20_24
5
37
38
41
6
35
31
33
2
PU13
1
30
25_29
3
36
10_19
39
34
4
32
40
7_9-20_24
5
37
38
41
6
35
31
33
2
PU2
2
1 PC81_C1P0_1
2
1
PR79
PR443
2
1
PR78
2
1 PC82_C1P0_2
2
1
PR80
2
1 PC84_1
2
1 PC80
2
1
PR77
PC85
2
1 PC103
2
1
PC101
2
1
PC95_1
2
1
PC88_2
4
32
1
PL11
2
1 PC190
2
1 PC79
PR442
2
1
PC83_2
1 2
1 4
32
1 4
32
PGND2
GL2
GL1
DNC
EN
PGND3
VOS
VIN2
PGND1
SW
LSET
IOUT
TOUT_FLT
PVCC
PHASE
VIN1
BOOT
AGND
VCC
REFIN
PWM
PGND2
GL2
GL1
DNC
EN
PGND3
VOS
VIN2
PGND1
SW
LSET
IOUT
TOUT_FLT
PVCC
PHASE
VIN1
BOOT
AGND
VCC
REFIN
PWM
2
1
1
SHEETDATE
23
7 3 2 16 5 4
E
A
B
C
E
D
C
B
A
7 6 5 4
D
DEPARTMENT
SIZE
PROJECT DOCUMENT NUMBER REV
REVIEWER
DESIGNER
BI
IN
OUT
BI
IN
BI
OUT
BI
OUT
IN
OUT
IN
C



PVDDCR_CPU1_P0_PHASE4
PVDDCR_CPU1_P0_PHASE3
11.0*7.5*12.5
PGL6303.151HLT
ISAT:70A@100C
DCR=1-4,0.105M OHM
DCR=2-3,0.27M OHM
2ND=CV+15^0TZ01
DCR=2-3,0.27M OHM
11.0*7.5*12.5
2ND=CV+15^0TZ01
DCR=1-4,0.105M OHM
ISAT:70A@100C
PGL6303.151HLT
Thu Aug 24 14:09:04 2023<NAME_2>
<NAME_1>
MB FABCGTI V02
202 OF 365
P V DDCR_CP U1_P 0_P V CC
P V DDCR_CP U1_P 0_P V CC
S W _P 12V _A UX _P V DDCR_CP U1_P 0_FLT
P V DDCR_CP U1_P 0
S W _P 12V _A UX _P V DDCR_CP U1_P 0_FLT
P V DDCR_CP U1_P 0
200
201
202
203
200
200201202203205206
200
201
202
203
200
200
200201202203205206
200
202
201 202
C0402
X 6S
0402LF
CHIP
5.6
C0402
10%
25V
1UF
X 6S
25V
X 7R
S W _P V DDCR_CP U1_P 0_B O O T3_RS W _P V DDCR_CP U1_P 0_B O O T3
0402LF
1/16W1%
5.6
S W _P V DDCR_CP U1_P 0_B O O T4_RS W _P V DDCR_CP U1_P 0_B O O T4
1%
0402LFCHIP
1/16W
0402
0.22UF
10%
16V
SMLF
IS L99390FRZ-TR5935
S W _P V DDCR_CP U1_P 0_B O O TR4
S W _P V DDCR_CP U1_P 0_S W 4
C0402
P V DDCR_CP U1_P 0_P W M4
P V DDCR_CP U1_P 0_TE MP 0
P V DDCR_CP U1_P 0_LS E T4
P V DDCR_CP U1_P 0_V CCS
P V DDCR_CP U1_P 0_V CC4
P V DDCR_CP U1_P 0_P W M3
P V DDCR_CP U1_P 0_TE MP 0
P V DDCR_CP U1_P 0_IMO N4
NC_P V DDCR_CP U1_P 0_DNC4
P V DDCR_CP U1_P 0_LS E T3
P V DDCR_CP U1_P 0_V CCS
P V DDCR_CP U1_P 0_IMO N3
P V DDCR_CP U1_P 0_V CC3
NC_P V DDCR_CP U1_P 0_DNC3 P V DDCR_CP U1_P 0_V O S 3
P V DDCR_CP U1_P 0_V O S 4
NC_P V DDCR_CP U1_P 0_G L2_4
NC_P V DDCR_CP U1_P 0_G L1_4
NC_P V DDCR_CP U1_P 0_G L1_3
NC_P V DDCR_CP U1_P 0_G L2_3
S W _P V DDCR_CP U1_P 0_S W 4_RC
IND_CP U1_P 0_CP L3
IND_CP U1_P 0_CP L2 IND_CP U1_P 0_CP L3
X 7R
10%
0.1UF
25V
0402
0402LF
8.87K
1%
E MP TY
1/16W
X 6S
10%
2.2UF
10V
C0402
X 7R
10%
0.1UF
25V
0402
0402LF
2.2
1%
CHIP
1/16W
X 6S
10%
2.2UF
10V
C0402
0402LF
8.87K
1%
E MP TY
1/16W
IC
SMLF
IC
IS L99390FRZ-TR5935
10%
0.1UF
0402
X 6S
10%
2.2UF
10V
0402LF
2.2
1%
CHIP
1/16W
X 6S
10%
2.2UF
10V
C0402
X 7R
10%
0.1UF
25V
1/8W
E MP TY
1%
1.5
0402LF
E MP TY
10%
560P F
50V
C0402
0402LF
0 5% CHIP
1/16W
X 7R
0402
10%
16V
0.22UF
SMLF
IND 150NH
20%
16V
22UF
C0805
X 6S
20%
16V
22UF
X 6S
C0805
20%
16V
22UF
C0805
X 6S
0402LF
0 5%
CHIP
1/16W
C0805
4V
22UF
20%
X 6S
C0805
4V
22UF
20%
X 6S
E MP TY
10%
560P F
50V
C0402
20%
16V
22UF
C0805
X 6S
0402
SMLF
IND 150NH
20%
16V
22UF
C0805
X 6S
20%
16V
22UF
C0805
X 6S
C0805
4V
22UF
20%
X 6S
C0805
4V
22UF
20%
X 6S
PVDDCR_CPU1_P0 VR PHASE 3&4
1.5
1%
1/8W
E MP TY
S W _P V DDCR_CP U1_P 0_S W 3
S W _P V DDCR_CP U1_P 0_B O O TR3 X 7R
S W _P V DDCR_CP U1_P 0_S W 3_RC
1UF
25V
10%
2
1
PC130_3
2
1
PC129_3
2
1
PC126_3
2
1
PC124_3
4
32
1
PL14
2
1 PC122
2
1
PC120_3
2
1
PC118_3
2
1 PC192
PR90
2
1
PC127_4
2
1
PC125_4
2
1
PC123_4
2
1
PR510
2
1
PC119_4
2
1
PC117_4
2
1 PC121
2
1
PR509
2
1 PC116_3
2
1 PC112_C1P0_3
2
1 PC110
2
1
PC115_4
1
30
25_29
3
36
10_19
39
34
4
32
40
7_9-20_24
5
37
38
41
6
35
31
33
2
PU15
1
30
25_29
3
36
10_19
39
34
4
32
40
7_9-20_24
5
37
38
41
6
35
31
33
2
PU14
2
1
PR86
2
1 PC111_C1P0_4
2
1
PR87
2
1 PC114_3
2
1 PC109
2
1
PR85
2
1
PC128_4
21
PR92
4
32
1
PL13
21 PR91
2
1 PC191
PR89
2
1
PR88
2
1 PC113_4
1 4
32
1 4
32
PGND2
GL2
GL1
DNC
EN
PGND3
VOS
VIN2
PGND1
SW
LSET
IOUT
TOUT_FLT
PVCC
PHASE
VIN1
BOOT
AGND
VCC
REFIN
PWM
PGND2
GL2
GL1
DNC
EN
PGND3
VOS
VIN2
PGND1
SW
LSET
IOUT
TOUT_FLT
PVCC
PHASE
VIN1
BOOT
AGND
VCC
REFIN
PWM
1
SHEETDATE
23
7 3 2 16 5 4
E
A
B
C
E
D
C
B
A
7 6 5 4
D
DEPARTMENT
SIZE
PROJECT DOCUMENT NUMBER REV
REVIEWER
DESIGNER
IN
OUT
BIBI
IN
BI
OUT
IN
OUT
IN
OUT
C



PVDDCR_CPU1_P0_PHASE6
DCR=1-4,0.105M OHM
DCR=2-3,0.27M OHM
2ND=CV+15^0TZ01
11.0*7.5*12.5
ISAT:70A@100C
PGL6303.151HLT
DCR=1-4,0.105M OHM
PGL6303.151HLT
ISAT:70A@100C
11.0*7.5*12.5
DCR=2-3,0.27M OHM
2ND=CV+15^0TZ01
PVDDCR_CPU1_P0_PHASE5
PGL6312.121AHLT
ISAT:60A@100C
6.5*6.5*10.0
DCR=0.17M OHM
2ND=CV+12^0EZ04
Thu Aug 24 14:09:05 2023<NAME_2>
<NAME_1>
MB FABCGTI V02
203 OF 365
P V DDCR_CP U1_P 0
S W _P 12V _A UX _P V DDCR_CP U1_P 0_FLT
P V DDCR_CP U1_P 0
S W _P 12V _A UX _P V DDCR_CP U1_P 0_FLT
P V DDCR_CP U1_P 0_P V CC
P V DDCR_CP U1_P 0_P V CC
203
203
200201202203205206
200
201
202
203
200
200201202203205206
200
201
202
203
200
200
200
201
0402
CHIP
1%
10%
PVDDCR_CPU1_P0 VR PHASE 5&6
IC
C0402
E MP TY
10%
50V
4V
22UF
20%
X 6S
C0805
4V
22UF
20%
X 6S
C0805
20%
16V
C0805
X 6S
22UF
20%
X 6S
22UF
IND 150NH
SMLF
X 7R
0402
0.22UF
16V
C0805
X 6S
22UF
16V
X 6S
10%
1UF
25V
X 7R
10%
0.1UF
25V
E MP TY
10%
560P F
50V
C0402
4V
22UF
20%
X 6S
C0805
4V
22UF
20%
X 6S
C0805
CHIP
1/16W
0402LF
0 5%
C0805
X 6S
22UF
16V
20%
C0805
X 6S
22UF
16V
1/8W
E MP TY
1%
1.5
0402LF
X 6S
C0805
22UF
16V
20%
X 6S
10%
1UF
25V
C0402
X 7R
10%
0.1UF
25V
IND 150NH
SMLF
0.22UF
16V
10%
X 7R
0402
0402LF
0 5% CHIP
1/16W
1%
1/8W
1.5
0402LF
E MP TY
X 6S
10%
2.2UF
10V
C04020402LF
2.2
1%
CHIP
1/16W
X 6S
10%
2.2UF
10V
C0402
SMLF
IC
X 6S
10%
10V
2.2UF
0402LF
8.87K
1%
E MP TY
1/16W
2.2
1%
CHIP
1/16W
X 6S
10%
2.2UF
10V
C0402
X 7R
10%
0.1UF
25V
0402
0402LF
8.87K
1%
E MP TY
1/16W
X 7R
10%
0.1UF
25V
0402
S W _P V DDCR_CP U1_P 0_S W 6
IND_CP U1_P 0_CP L6
S W _P V DDCR_CP U1_P 0_S W 5_RC
IND_CP U1_P 0_CP L6
P V DDCR_CP U1_P 0_V O S 5
P V DDCR_CP U1_P 0_V O S 6
S W _P V DDCR_CP U1_P 0_S W 6_RC
NC_P V DDCR_CP U1_P 0_G L2_6
NC_P V DDCR_CP U1_P 0_G L1_6
S W _P V DDCR_CP U1_P 0_B O O TR6
NC_P V DDCR_CP U1_P 0_G L1_5
S W _P V DDCR_CP U1_P 0_S W 5
NC_P V DDCR_CP U1_P 0_DNC5
P V DDCR_CP U1_P 0_V CC5
P V DDCR_CP U1_P 0_LS E T5
P V DDCR_CP U1_P 0_V CCS
P V DDCR_CP U1_P 0_IMO N5
P V DDCR_CP U1_P 0_V CC6
NC_P V DDCR_CP U1_P 0_DNC6
P V DDCR_CP U1_P 0_TE MP 0
P V DDCR_CP U1_P 0_LS E T6
P V DDCR_CP U1_P 0_V CCS
P V DDCR_CP U1_P 0_IMO N6
P V DDCR_CP U1_P 0_TE MP 0
P V DDCR_CP U1_P 0_P W M6
P V DDCR_CP U1_P 0_P W M5
NC_P V DDCR_CP U1_P 0_G L2_5
IND_CP U1_P 0_CP L5
16V
C0805
IS L99390FRZ-TR5935
20%
20%
0402
S MLF
IND
120NH/69A
560P F
IND_CP U1_P 0_CP L0
1%
0402LF
1/16W
CHIP
S W _P V DDCR_CP U1_P 0_B O O T6 S W _P V DDCR_CP U1_P 0_B O O T6_R
5.6
0402LF
1/16W
S W _P V DDCR_CP U1_P 0_B O O T5_R
0402LF C0402
IS L99390FRZ-TR5935
SMLF
C0402
5.6
S W _P V DDCR_CP U1_P 0_B O O TR5
S W _P V DDCR_CP U1_P 0_B O O T5
1
30
25_29
3
36
10_19
39
34
4
32
40
7_9-20_24
5
37
38
41
6
35
31
33
2
PU11
2
1 PC154
2
1
PC141_5
2
1
PC140_5
2
1
PC139_5
2
1
PC138_5
4
32
1
PL152
1 PC137
2
1
PC134_5
2
1 PC157
PR95
2
1
PC123_6
2
1
PC120_6
21 PR96
2
1
PC119_6
2
1
PC118_6
2
1
PR158
2
1
PC116_6
2
1
PC115_6
4
32
1
PL72
1 PC117
2 1
PL9
21 PR421
2
1
PR155
2
1
PR94
2
1 PC131
1
30
25_29
3
36
10_19
39
34
4
32
40
7_9-20_24
5
37
38
41
6
35
31
33
2
PU16
2
1 PC113_C1P0_6
2
1
PR93
2
1
PR416
2
1 PC112
2
1 PC132_5
2
1
PR7
2
1 PC111_6
2
1
PC136_5
2
1
PC135_5
2
1
PC114_6
PR420
2
1 PC133_C1P0_5
PGND2
GL2
GL1
DNC
EN
PGND3
VOS
VIN2
PGND1
SW
LSET
IOUT
TOUT_FLT
PVCC
PHASE
VIN1
BOOT
AGND
VCC
REFIN
PWM
1 4
32
1 4
3212
PGND2
GL2
GL1
DNC
EN
PGND3
VOS
VIN2
PGND1
SW
LSET
IOUT
TOUT_FLT
PVCC
PHASE
VIN1
BOOT
AGND
VCC
REFIN
PWM
1
SHEETDATE
23
7 3 2 16 5 4
E
A
B
C
E
D
C
B
A
7 6 5 4
D
DEPARTMENT
SIZE
PROJECT DOCUMENT NUMBER REV
REVIEWER
DESIGNER
OUT
IN
BIBI
OUT
BI
IN
OUT
IN
IN
OUT
C



Thu Aug 24 10:15:12 2023<NAME_2>
<NAME_1>
MB FABCGTI V02
204 OF 365Blank
1
SHEETDATE
23
7 3 2 16 5 4
E
A
B
C
E
D
C
B
A
7 6 5 4
D
DEPARTMENT
SIZE
PROJECT DOCUMENT NUMBER REV
REVIEWER
DESIGNER
C



PU17,PU18,PU19,PU20 = AL021590000/TDA21590
PR101,PR102,PR110,PR109 = CS00002JB13
PR103,PR104,PR111,PR112 = EMPTY
PU17,PU18,PU19,PU20=AL087000A03/MP87000GMJTH-C11D-Z
PC145_7,PC146_8,PC175_9,PC176_10=EMPTY
PC145_7,PC146_8,PC175_9,PC176_10 = EMPTY
PR101,PR102,PR109,PR110=CS00002JB13
PU17,PU18,PU19,PU20 =AL099390004/ISL99390FRZ-TR5935
PVDDIO_P0_PHASE1
MAIN SOURCE:RENESAS BOM
2ND SOURCE:INFENEON BOM
PR98,PR97,PR106,PR105 = CS00002JB13
PR103,PR104,PR111,PR112=EMPTY
3RD SOURCE:MPS BOM
2022/5/14 MODIFY 2ND=CV+15^0TZ01
DCR=2-3,0.27M OHM
DCR=1-4,0.105M OHM
11.0*7.5*12.5
ISAT:70A@100C
PGL6303.151HLT
2ND=CH747LM8822
7.3*4.3*1.9
ESR=4.5M OHM
6.3*8
2ND=CC72703MD39
IRIPPLE:5.08A
ESR=10M OHM
ISAT:70A@100C
2ND=CVA50^0MZ07
3RD=CVA50^0MZ08
11.0*7.5*12.5
ISAT:70A@100C
PGL6303.151HLT
DCR=1-4,0.105M OHM
DCR=2-3,0.27M OHM
2ND=CV+15^0TZ01
PVDDIO_P0_PHASE2
BOM NOTE
PG2292.500HLT
DCR=0.09M OHM
6.0*6.1*7.0
Thu Aug 24 14:09:26 2023<NAME_2>
<NAME_1>
MB FABCGTI V02
205 OF 365
2.2
P V DDIO _P 0
P 12V _A UXS W _P 12V _A UX _P V DDIO _P 0_FLT
P V DDIO _P 0
P V DDIO _P 0
S W _P 12V _A UX _P V DDIO _P 0_FLT
P V DDCR_CP U1_P 0_P V CC
P V DDCR_CP U1_P 0_P V CC
PVDDIO_P0_VR PHASE 1&2
P V DDIO _P 0_V CC2
0402LF
205
205206
200
205
206
200
200201202203205206
200
205
206
200
200
200201202203205206
200
270UF
0.1UF
22UF
16V
20%
X 6S
C0805
16V
16V
O S CO N
THLF
20%
20%
X 6S
22UF
C0805
16V
20%
C0402
20%
X 6S
22UF
10%
X 7R
S W _P V DDIO _P 0_B O O T1
SMLF
IC
IS L99390FRZ-TR5935
0402
25V
0.1UF
10%
X 7R X 6S
10%
1UF
25V
C0805
X 6S
16V
0402LF
1K
1%
CHIP
1/16W
4V
22UF
20%
X 6S
C0805
4V
22UF
20%
X 6S
C0805
X 7R
10%
25V
0402
0.1UF
X 7R
25V
0402
10%
50NH/86A
S MLF
IND
SMLF
IND 150NH
10%
X 7R
16V
0402
560P F
50V
E MP TY
10%
1%
1/8W
E MP TY
1.5
0402LF
S P CA P
20%
470UF
2.5V
S MLFS MLF
2.5V
470UF
20%
S P CA P
S MLF
E MP TY
20%
470UF
2.5V
4V
22UF
20%
X 6S
C0805
4V
22UF
20%
X 6S
C0805
1/16W
0 5%
CHIP
0402LF
C0805
X 6S
22UF
16V
20%
C0805
X 6S
22UF
16V
20%
22UF
16V
20%
X 6S
C0805
X 6S
10%
1UF
25V
C0402
0402
X 7R
10%
0.22UF
16V
SMLF
IND 150NH
0402LF
0 5%
CHIP
1/16W
E MP TY
10%
560P F
50V
C0402
1.5
0402LF
1%
1/8W
E MP TY
X 6S
2.2UF
10V
C0402
10%
0402LF
2.2
1%
CHIP
1/16W
X 6S
10%
2.2UF
10V
C0402
1%
1/16W
0402LF
8.87K
E MP TY
10%
0.1UF
25V
0402
25V
0402
IC
SMLF10V
X 6S
10%
C0402
2.2UF
1%
CHIP
1/16W
X 6S
10%
2.2UF
10V
C0402
8.87K
1%
E MP TY
1/16W
25V
IND_P V DDIO _P 0_CP L2
S W _P V DDIO _P 0_S W 1_RC
IND_P V DDIO _P 0_CP L2IND_P V DDIO _P 0_CP L3
S W _P V DDIO _P 0_S W 2_RC
S W _P V DDIO _P 0_B O O TR1
S W _P V DDIO _P 0_S W 2
S W _P V DDIO _P 0_B O O TR2
S W _P V DDIO _P 0_S W 1
NC_P V DDIO _P 0_G L1_1
NC_P V DDIO _P 0_G L2_1
P V DDIO _P 0_V O S 1NC_P V DDIO _P 0_DNC1
P V DDIO _P 0_IMO N1
P V DDIO _P 0_TE MP 1
P V DDCR_CP U1_P 0_V CCS
P V DDIO _P 0_LS E T1
P V DDIO _P 0_P W M1
P V DDIO _P 0_V CC1
NC_P V DDIO _P 0_G L1_2
NC_P V DDIO _P 0_G L2_2
P V DDIO _P 0_V O S 2
P V DDIO _P 0_TE MP 1
P V DDIO _P 0_IMO N2
P V DDCR_CP U1_P 0_V CCS
P V DDIO _P 0_LS E T2
P V DDIO _P 0_P W M2
X 7R
C0402
0.1UF
IS L99390FRZ-TR5935
NC_P V DDIO _P 0_DNC2
0402LF
0.1UF
0402
X 7R
10%
1%
CHIP
1/16W
0402LF
S W _P V DDIO _P 0_B O O T2 S W _P V DDIO _P 0_B O O T2_R
5.6
1/16W
CHIP
1%
0402LF
S W _P V DDIO _P 0_B O O T1_R
5.6
0.22UF
C0805
22UF
PC7000
1
30
25_29
3
36
10_19
39
34
4
32
40
7_9-20_24
5
37
38
41
6
35
31
33
2
PU17
2
1
PC148_1
2
1
PC150_1
2
1
PC152_1
2
1
PC154_1
PR410
2
1
PC169_1
2
1
PC166_1
2
1
PC107
PC148
21
PL19
2
1
PC164
2
1 PC158_1
4
32
1
PL17
2
1 PC155
2
1 PC158
2
1
PR221
2
1
PC165
2
1
PC162
2
1
PC160
2
1
PC170_2
2
1
PC168_2
PR103
2
1
PC159_2
2
1
PC157_2
2
1
PC153_2
2
1
PC151_2
2
1 PC156
4
32
1
PL18
PR104
2
1 PC159
2
1
PR223
21
PR101
2
1 PC147_IOP0_1
2
1
PR100
2
1 PC143
2
1
PR98
2
1 PC145_7
2
1
PC149_2
PR102
1
30
25_29
3
36
10_19
39
34
4
32
40
7_9-20_24
5
37
38
41
6
35
31
33
2
PU182
1 PC144_IOP0_2
2
1
PR99
2
1 PC142
2
1
PR97
2
1 PC146_8
PGND2
GL2
GL1
DNC
EN
PGND3
VOS
VIN2
PGND1
SW
LSET
IOUT
TOUT_FLT
PVCC
PHASE
VIN1
BOOT
AGND
VCC
REFIN
PWM
1 2
1 4
32
1 4
32
PGND2
GL2
GL1
DNC
EN
PGND3
VOS
VIN2
PGND1
SW
LSET
IOUT
TOUT_FLT
PVCC
PHASE
VIN1
BOOT
AGND
VCC
REFIN
PWM
2
1
2
1
1
SHEETDATE
23
7 3 2 16 5 4
E
A
B
C
E
D
C
B
A
7 6 5 4
D
DEPARTMENT
SIZE
PROJECT DOCUMENT NUMBER REV
REVIEWER
DESIGNER
OUT
IN
BI
OUT
BI
IN
BI
OUT
IN
OUT
IN
C



PVDDIO_P0_PHASE4
HCME656510Q-221QL
ISAT:30A@100C
6.5*6.5*10.0
DCR=0.17M OHM
2ND=CV+22Y0EZ01
DCR=2-3,0.27M OHM
2ND=CV+15^0TZ01
PGL6303.151HLT
11.0*7.5*12.5
DCR=1-4,0.105M OHM
ISAT:70A@100C
2ND=CV+15^0TZ01
DCR=2-3,0.27M OHM
DCR=1-4,0.105M OHM
PGL6303.151HLT
11.0*7.5*12.5
ISAT:70A@100C
PVDDIO_P0_PHASE3
Thu Aug 24 14:09:05 2023<NAME_2>
<NAME_1>
MB FABCGTI V02
206 OF 365
P V DDIO _P 0
P V DDIO _P 0
S W _P 12V _A UX _P V DDIO _P 0_FLT
S W _P 12V _A UX _P V DDIO _P 0_FLT
P V DDCR_CP U1_P 0_P V CC
P V DDCR_CP U1_P 0_P V CC
205
206
200
205
206
200
200
200201202203205206
200
200
205
206
200
200201202203205206
206
5.6
S W _P V DDIO _P 0_B O O T3_R
S W _P V DDIO _P 0_B O O T3
CHIP
1/16W
1%
0402LF
5.6
S W _P V DDIO _P 0_B O O T4_RS W _P V DDIO _P 0_B O O T4
1/16W1%
0402LFCHIP
C0402
X 6S
10%
25V
S W _P V DDIO _P 0_B O O TR3
PVDDIO_P0_VR PHASE 3&4
SMLF
IC
IS L99390FRZ-TR5935
4V
22UF
20%
X 6S
C0805
4V
22UF
20%
X 6S
C0805
4V
22UF
20%
X 6S
C0805
16V
20%
C0805
X 6S
22UF
150NH
SMLF
IND
C0805
X 6S
22UF
16V
20%
16V
X 7R
0.22UF
0402
C0805
X 6S
22UF
16V
20%
50V
C0402
560P F
10%
E MP TY
1.5
1/8W
1%
4V
22UF
20%
X 6S
C0805
5%
0402LF
0 CHIP
1/16W
C0805
X 6S
22UF
16V
20%
C0805
X 6S
22UF
16V
20%
C0805
X 6S
22UF
16V
20%
X 6S
10%
1UF
25V
C0402
X 7R
10%
0.22UF
16V
0402
0.22UH/33A
S MLF
IND
IND 150NH
SMLF
0402LF
0 5% CHIP
1/16W
560P F
50V
10%
C0402
E MP TY
1/8W
E MP TY
1%
1.5
0402LF
1UF
X 7R
10%
0.1UF
0402
SMLF
IC
IS L99390FRZ-TR5935
X 6S
10%
2.2UF
10V
C04020402LF
2.2
1%
CHIP
1/16W
X 6S
10%
2.2UF
10V
C0402
8.87K
1%
1/16W
E MP TY
0402LF
X 7R
10%
0.1UF
25V
0402
X 7R
10%
0.1UF
25V
0402
X 6S
10%
2.2UF
10V
C04020402LF
2.2
1%
CHIP
1/16W
X 6S
10%
2.2UF
10V
C0402
0402LF
8.87K
1%
E MP TY
1/16W
X 7R
10%
25V
0402
0.1UF
S W _P V DDIO _P 0_B O O TR4
S W _P V DDIO _P 0_S W 4
IND_P V DDIO _P 0_CP L3
S W _P V DDIO _P 0_S W 3_RC
IND_P V DDIO _P 0_CP L4IND_P V DDIO _P 0_CP L0
S W _P V DDIO _P 0_S W 4_RC
S W _P V DDIO _P 0_S W 3
NC_P V DDIO _P 0_G L2_3
P V DDIO _P 0_V O S 3
P V DDIO _P 0_IMO N3
P V DDIO _P 0_TE MP 1
NC_P V DDIO _P 0_DNC3
P V DDIO _P 0_P W M3
P V DDIO _P 0_LS E T3
P V DDIO _P 0_V CC3
P V DDCR_CP U1_P 0_V CCS
P V DDIO _P 0_V O S 4
NC_P V DDIO _P 0_G L2_4
NC_P V DDIO _P 0_G L1_4
P V DDIO _P 0_IMO N4
P V DDIO _P 0_P W M4
NC_P V DDIO _P 0_DNC4
P V DDIO _P 0_LS E T4
P V DDIO _P 0_V CC4
P V DDIO _P 0_TE MP 1
P V DDCR_CP U1_P 0_V CCS
25V
0402LF
NC_P V DDIO _P 0_G L1_3 E MP TY
IND_P V DDIO _P 0_CP L4
10%
1
30
25_29
3
36
10_19
39
34
4
32
40
7_9-20_24
5
37
38
41
6
35
31
33
2
PU20
2
1
PC190_3
2
1 PC187_3
4
32
1
PL21
2
1
PC184_3
2
1
PC181_3
2
1 PC166
2
1
PC189_4
PR111
2
1 PC188_4
2
1
PC185_4
2
1
PC180_4
4
32
1
PL20
PR112
2
1 PC163
2
1
PR291
2
1
PC179_3
2
1
PC177_3
PR110
1
30
25_29
3
36
10_19
39
34
4
32
40
7_9-20_24
5
37
38
41
6
35
31
33
2
PU19
2
1 PC174_IOP0_3
2
1 PC172
2
1
PR106
2
1 PC175_9
2
1
PC178_4
PR109
2
1 PC173_IOP0_4
2
1
PR107
2
1 PC171
2
1
PR105
2
1 PC176_10
2
1
PC192_3
2
1
PC191_4
2
1 PC186
2
1
PR379
2
1
PC182_4
2
1 PC183
2
1
PR108
PL16
2 1
PGND2
GL2
GL1
DNC
EN
PGND3
VOS
VIN2
PGND1
SW
LSET
IOUT
TOUT_FLT
PVCC
PHASE
VIN1
BOOT
AGND
VCC
REFIN
PWM
1 4
32
12
1 4
32
PGND2
GL2
GL1
DNC
EN
PGND3
VOS
VIN2
PGND1
SW
LSET
IOUT
TOUT_FLT
PVCC
PHASE
VIN1
BOOT
AGND
VCC
REFIN
PWM
1
SHEETDATE
23
7 3 2 16 5 4
E
A
B
C
E
D
C
B
A
7 6 5 4
D
DEPARTMENT
SIZE
PROJECT DOCUMENT NUMBER REV
REVIEWER
DESIGNER
OUT
IN
BI
OUT
BI
BI
IN
OUT
IN
OUT
IN
C



PMBUS ADDRESS AND CONFIG
/21.5K0X49
CONFIG/R
/4.64K
0/3.09K
0X49
MPS
ADDRESS(7-BIT)
0X63
2022/5/14 MODIFY
IRM REV1.09
EFFICIENCY > 90% @TDC
WORK FREQUENCY=600KHZ
MAX LOAD RELEASE=35A
MAX LOAD STEP=25A
DC & AC=1.045-1.155V
OUTPUT VOLTAGE=1.1V
OCP=96A (EDC*1.2)
PVDD11_S3_P0 SPECFICATION
PU21 = TBD/RAA229621GNP#HA0
MAIN SOURCE:RENESAS BOM
BOM NOTE
PR3 = CS21002FB06
PR113 = CS25362FB02
PC198 = CH11006JB00
PC199 = CH5103KEB01
3RD SOURCE:MPS BOM
PR126 = CS22672FB03
PR419,PR36,PR412 = EMPTY
PR121 = CS01002FB07
PC194 = CH12206KB14
PC193 = CH3104J1B00
POP R8458
20220422:
DE-POP R8458
20220413:
DIFFERENTIAL PAIR
EDC=80A
TDC=65A
RENESAS
INFINEON
TRACE WIDTH = 10MIL
PU21 = TBD/XDPE19283B
PR37,PR33,PR34,PR35 = EMPTY
PC199=CH5103KEB01
PC5 = CH21006JB10
PC198 = CH31004KB17
PR601 = CS24992FB07
PR125 = CS37502FB05
PR126 = CS33402FB06
PC194,PR113,PC193 = EMPTY
PR37,PR33,PR34,PR35,PR419,PR36 = EMPTY
PR3 = CS00002JB13
PU21 = TBD/MP2856GUT-0021-ZTRACE SPACING = 5MIL
2ND SOURCE:INFENEON BOM
20220413:
VR
PR121 IS CHANGED FROM 10 TO 0 OHM
Thu Aug 24 14:09:05 2023<NAME_2>
<NAME_1>
MB FABCGTI V02
207 OF 365
P 12V _A UX
P 3V 3_A UX
P V DD18_S 5_P 0
P 3V 3_A UX
P V DD18_S 5_P 0
P 3V 3_A UX
P 5V _A UX
P V DD11_S 3_P 0
PVDD11_S3_P0 VR CONTROLLER
0.1UF
1/16W
1%
1/16W
3.09K
P V DD11_S 3_P 0_A DDR_CFG
NC_P V DD11_S 3_P 0_IMO N5
NC_P V DD11_S 3_P 0_P W M5
0402LF
NC_P V DD11_S 3_P 0_IMO N8
NC_P V DD11_S 3_P 0_P W M8
P V DD11_S 3_P 0_TE MP 1
P V DD11_S 3_P 0_O CP _N_R
NC_P V DD11_S 3_P 0_IMO N6
NC_P V DD11_S 3_P 0_P W M6
P V DD11_S 3_P 0_P W M1
NC_P V DD11_S 3_P 0_IMO N7
P V DD11_S 3_P 0_V DDIO
P V DD11_S 3_P 0_V INS E N
P V DD11_S 3_P 0_V MO N
P V DD11_S 3_P 0_P W M2
P W RG D_P V DD11_S 3_P 0_R
NC_P V DD11_S 3_P 0_P W M7
V S E NS E _P V DD11_S 3_P 0_R
NC_P V DD11_S 3_P 0_P W M3
NC_P V DD11_S 3_P 0_P W M4
P V DD11_S 3_P 0_P MS DA _R
P V DD11_S 3_P 0_E N_R
P V DD11_S 3_P 0_P MA LE RT_R
NC_P V DD11_S 3_P 0_P G 1
NC_P V DD11_S 3_P 0_IMO N4
NC_P V DD11_S 3_P 0_IMO N3
P V DD11_S 3_P 0_RE S E T_N_R
NC_P V DD11_S 3_P 0_S V TO
P V DD11_S 3_P 0_IMO N2
P V DD11_S 3_P 0_P MS CL_R
P V DD11_S 3_P 0_IMO N1
IC
RA A 229621G NP #HA 0
SMLF
P V DD11_S 3_P 0_O CP _N
40.2K
CHIP
1/16W
5%
0402LF
5%0
5%
1/16W
P V DD11_S 3_P 0_E N
CHIP
P V DD11_S 3_P 0_P MA LE RT
S MB _S CM_2_R6_S DA
S MB _S CM_2_R6_S CL
1/16W
0402LF
5%
0402LF
0
1/16W
P V DD11_S 3_P 0_TE MP 0
0402
1000P F
50V
E MP TY
0402
0402LF
CHIP
E MP TY
0
1K
1/16W
0402LF
0402LF
1/16W
5%
E MP TY
5%
CHIP
P V DD11_S 3_P 0_V CCS
0
P W RG D_P V DD11_S 3_P 0
1/16W
X 7R
1/16W 0
5%
CHIP
0402LF
1%1
C0402
X 6S
10%
1UF
16V
C0402
6.3V
10UF
X 6S
0402
X 7R
10%
0.1UF
25V
X 7R
10%
0.1UF
25V
0402
0402LF0 5%CHIP 1/16W
0402LF
1%
E MP TY 1/16W
0402LF
5%
1/16W
0 5%CHIP 1/16W
0402LF0 5%CHIP 1/16W
0 5%CHIP 1/16W 0402LF
0402LF0 5%CHIP 1/16W
0402LF
0
5%
E MP TY
1/16W
0402LF5%CHIP
0402LF0 5%CHIP 1/16W
X 7R
10%
470P F
50V
0402
50V
CHIP
0
0402LF
CHIP
1%1K
CHIP
1%
0402LF
CHIP
3300P F
0402
50V
10%
1/16W
0402LF
E MP TY
1%
CHIP
0402LF
X 7R
10%
0.1UF
25V
04020402LF
4.99K
1%
E MP TY
1/16W
0402LF
0 5%
CHIP
1/16W
1%
49.9
1/16W
0
0402LF
10K
CHIP
0402
X 7R
10%
0402LF
1%
1/16W
P V DD11_S 3_P 0_V CC
P V DD11_S 3_P 0_RE S E T_N
V S E NS E _P V DD11_S 3_P 0_DP
1000P F
0
1K
1%
X 7R
0402LF
49.9
1000P F
X 7R
1/16W
0402LF
1/16W
5%
0402
1/16W
0402LF
5%
5%
50V
CHIP
V S E NS E _V S S _S E NS E _C_P 0
33
1/16W
5%0
E MP TY
CHIP
208
208
208
208
82
82
82 83
151
151
208
208
81
81
27
200 27
20%
25V
C5009
21
PR130
2
1 PC199
2
1 PC4
21
PR37
21
PR33
21
PR34
21
PR35
21
PR419
2
1
PR127
21
PR36
21
PR412
2
1 PC198
21
C197
21
R122
21 R123
21
R118
21
R119
21
R120
21
R117
2
1
PR114
2
1
PC194
21
PR121
2
1
R124
32
21
37
38
15
40
39
T H
35
36
19
20
17
18
31
22
14
8
7
6
5
4
3
2
1
9
10
16
12
33
11
34
13
23
24
25
26
27
28
29
30
PU21
2
1 PR126
2
1 PC5PR601
21
PR125
2
1
PR115
21
R8458
2
1
PR3
2
1 PC193
21
PR113
2
1 PC200
2
1 PC9
21
PR128
21
PR129
21
C196
21
R8116
CS0
PWM0
TEMP1
EN1||ADDR_CFG
TH_GND
OCP_L
CS2
PWM2
CS3
PWM3
PWM7
CS1
RGND1
VSEN1
VDDIO
TEMP0
VINSEN
VMON||IINSEN
VCCS
PWM6
PG0
PWM1
VSEN0
PWM5
PWM4
PMSDA
RGND0
EN0
nPMALERT
SVD
PG1
CS4
CS5
RESET_L
SVTO
CS6
SVC
PMSCL
SVTI
VCC
CS7
2
1
1
SHEETDATE
23
7 3 2 16 5 4
E
A
B
C
E
D
C
B
A
7 6 5 4
D
DEPARTMENT
SIZE
PROJECT DOCUMENT NUMBER REV
REVIEWER
DESIGNER
OUT
OUT
IN
IN
OUT
IN
IN
OUT
OUT
OUT
OUT
OUT
IN
IN
I N
C



PU22,PU23 = AL087000A03/MP87000GMJTH-C11D-Z
2022/5/14 MODIFY
MAIN SOURCE:RENESAS BOM
2ND SOURCE:INFENEON BOM
PR133,PR134,PR135,PR136 = CS00002JB13
PR413,PR135,PR136=CS00002JB13
3RD SOURCE:MPS BOM
PC201_1,PC202_2 = EMPTY
PU22,PU23 = AL021590000/TDA21590
PVDD11_S3_P0_PHASE2
2ND=CC72703MD39
6.3*8
PG2289.101HLT
3RD=CV+10G0MZ08
ESR=10M OHM
BOM NOTE
PR411,PR137,PR138 = EMPTY
PC201_1,PC202_2 = EMPTY
PU22,PU23 = AL099390004/ISL99390FRZ-TR5935
PR137,PR138 = EMPTY
PG2323.900HLT
ESR=10M OHM
5.0*5.8
2ND=CC7390JMZ117.3*4.3*1.9
ESR=9M OHM
2ND=CVA90^0KZ04
2ND=CVA90^0KZ04
3RD=CVA90^0KZ08
PG2323.900HLT
ISAT:132A@100C
10.0*7.7*12.0
DCR=0.103M OHM
2ND=CV+10G0MZ04
PVDD11_S3_P0_PHASE1
DCR:0.105M OHM
4.5*4.7*4.5
ISAT:13A@100C
2ND=CH747LM8822
ISAT:132A@100C
10.0*7.7*12.0
DCR=0.103M OHM
3RD=CVA90^0KZ08
IRIPPLE:5.08A
Thu Aug 24 14:09:05 2023<NAME_2>
<NAME_1>
MB FABCGTI V02
208 OF 365
S W _P 12V _A UX _P V DD11_S 3_P 0_FLT
P 12V _A UX
P 5V _A UX
P V DD11_S 3_P 0_P V CC
P 3V 3_A UX P V DD11_S 3_P 0_P V CC
P V DD11_S 3_P 0
P V DD11_S 3_P 0
P V DD11_S 3_P 0
P V DD11_S 3_P 0
S W _P 12V _A UX _P V DD11_S 3_P 0_FLT
PVDD11_S3_P0 VR PHASE 1&2
1/16W
P V DD11_S 3_P 0_V CCS
NC_P V DD11_S 3_P 0_G L1_1
S W _P V DD11_S 3_P 0_S W 1
S W _P V DD11_S 3_P 0_P H1
207208
207
208
207
207
207
208
207
207
207208
S MLF
100NH/16A
22UF 270UF
IND
C0805
20%
22UF
16V
20%
C0805
X 6S
0402
0402
20%
22UF
X 6S
0.1UF
IS L99390FRZ-TR5935
X 6S
0402
X 6S
20%
560P F
22UF22UF
25V
X 7R
25V
0.1UF
E MP TY
C0805
50V
10%
S W _P V DD11_S 3_P 0_S W 1_RC
16V
0
CHIP
P V DD11_S 3_P 0_P W M2
NC_P V DD11_S 3_P 0_DNC2
P V DD11_S 3_P 0_LS E T2
P V DD11_S 3_P 0_TE MP 0
P V DD11_S 3_P 0_IMO N2
P V DD11_S 3_P 0_V CC2
P V DD11_S 3_P 0_P W M1
P V DD11_S 3_P 0_TE MP 0
NC_P V DD11_S 3_P 0_G L2_2
NC_P V DD11_S 3_P 0_G L1_2
S W _P V DD11_S 3_P 0_S W 2
S W _P V DD11_S 3_P 0_S W 2_RC
P V DD11_S 3_P 0_IMO N1
P V DD11_S 3_P 0_V CCS
P V DD11_S 3_P 0_V CC1
NC_P V DD11_S 3_P 0_DNC1
P V DD11_S 3_P 0_LS E T1
P V DD11_S 3_P 0_V O S 2
S W _P V DD11_S 3_P 0_P H2
X 7R
10%
0.1UF
25V
0402
X 6S
10%
2.2UF
10V
C0402
4.87K 1%
E MP TY
0402LF
IC
0402LF
2.2
CHIP
1/16W
1%
X 6S
10%
2.2UF
10V
C0402
1/8W
1%
1.5
0402LF
E MP TY
560P F
C0402
E MP TY
10%
50V
C0402 C0805
E MP TY
1%
1.5
1/8W
X 7R
10%
0.1UF
25V
0402
X 6S
10%
10V
C0402
2.2UF
1/16WE MP TY
1%4.87K
0402LF
0402LF
2.2
1%
CHIP
1/16W
X 6S
10%
2.2UF
10V
C0402
X 6S
C0402
C0402
C0805
20%
X 7R
10%
0.22UF
16V
0402
90NH/155A
S MLF
IND
1/16W
5%
S P CA P
20%
2.5V
S MLF
S P CA P
470UF
S MLF
20%
2.5V
4V
22UF
20%
X 6S
C0805
390UF
20%
S MLF
2.5V
A LUM
S MLF
390UF
20%
A LUM
2.5V 2.5V
390UF
20%
A LUM
S MLF S MLF
2.5V
390UF
20%
A LUM
0.22UF
0402
90NH/155A
IND
25V
X 7R
10%
0.1UF
0402
0.1UF
X 7R
10%
25V
4V
22UF
20%
X 6S
C0805
4V
22UF
20%
X 6S
C0805
0402LF
1K
1%
CHIP
1/16W
0402LF
0
5%
CHIP
1/16W
0402LF
5%
E MP TY
1/16W
0
S MLF
2.5V
470UF
20%
S P CA P
4V
22UF
20%
X 6S
C0805
0 5%
CHIP
1/16W
0402LF
SMLF
IC
X 7R
10%
25V
10%
25V
0402LF
10%
X 7R
1UF
C0805
P V DD11_S 3_P 0_V O S 1
NC_P V DD11_S 3_P 0_G L2_1
1UF
10% 10%
16V 16V
22UF
470UF
16V
20%
C0805 C0805
22UF
X 6S
20%
0402LF
S MLF
16V
20%
16V
22UF
X 6SX 6SX 6S
CHIP
1/16W
0402LF
1%S W _P V DD11_S 3_P 0_B O O T2 S W _P V DD11_S 3_P 0_B O O T2_RC5.6
1/16W
1%
0402LF
S W _P V DD11_S 3_P 0_B O O T1_RC5.6S W _P V DD11_S 3_P 0_B O O T1
CHIP
IS L99390FRZ-TR5935
SMLF
20%
THLF
16V
O S CO N
16V
X 6S
20%
C0805
22UF
X 6S
C0805
22UF
X 6S
20%
22UF
C0805
X 6S
20%
16V16V16V16V
PC8005
PC8004
1
30
25_29
3
36
10_19
39
34
4
32
40
7_9-20_24
5
37
38
41
6
35
31
33
2
PU22
21
PR138
2
1 PC221_2
2
1 PC800
2
1 PC219_1
2
1 PC215_1
PR413PR411
PR414
2
1 PC227_1
21
PL24
2
1 PC222
2
1 PC220
21
PL23
2
1
PC217
2
1 PC228
2
1 PC225_2
2
1 PC226
2
1 PC223
21
PR137
2
1 PC218_2
2
1
PC218
2
1 PC216_2
2
1 PC213_1
2
1 PC207_1
21
PR135
2
1 PC169
2
1 PC205_11P0_1
2
1
PR131
2
1 PC203
2
1
PR482
2
1 PC214_2
2
1 PC212_2
2
1 PC206_11P0_2
2
1
PR132
1
30
25_29
3
36
10_19
39
34
4
32
40
7_9-20_24
5
37
38
41
6
35
31
33
2
PU23
21
PR134
2
1 PC204
2
1 PC202_2
2
1 PC224_1
PC6003
2
1 PC801
2
1 PC230
2
1 PC229
21
PL22
2
1 PC211_1
2
1 PC209_1
21
PR133
2
1 PC201_1
2
1 PC208_2
2
1 PC210_2
2
1 PC168
21
PR136
2
1
PR389
PGND2
GL2
GL1
DNC
EN
PGND3
VOS
VIN2
PGND1
SW
LSET
IOUT
TOUT_FLT
PVCC
PHASE
VIN1
BOOT
AGND
VCC
REFIN
PWM
1 2
1 2
1 2
PGND2
GL2
GL1
DNC
EN
PGND3
VOS
VIN2
PGND1
SW
LSET
IOUT
TOUT_FLT
PVCC
PHASE
VIN1
BOOT
AGND
VCC
REFIN
PWM
2
1 PC7002
2
1
2
1
2
1
1
SHEETDATE
23
7 3 2 16 5 4
E
A
B
C
E
D
C
B
A
7 6 5 4
D
DEPARTMENT
SIZE
PROJECT DOCUMENT NUMBER REV
REVIEWER
DESIGNER
OUT
IN
OUT
IN
OUT
IN
OUT
IN
C



MAX LOAD STEP=2.5A
WORK FREQUENCY=600KHZ
IRM REV1.09
EFFICIENCY > 85% @TDC
MAX LOAD RELEASE=2.5A
AC =+/-30MV
EDC=12A
OUTPUT VOLTAGE=1.8V
OCP=15A (EDC*1.2)
RB
FCCM
FSW=600KHZ
PVDD18_S5_P0
VOUT=0.6(1+RA/RB)=1.8V DIFFERENTIAL PAIR
TRACE WIDTH = 10MIL
5.0*5.8
2ND=CC7390JMZ11
E S R=10M O HM
DC =1.76-1.84V
TDC=10A
PVDD18_S5_P0 SPECFICATION
TRACE SPACING = 5MIL
RA
NEAR CPU SIDE
DCR=5M OHM
1ST
BOM NOTE
3RD AL000548007/TPS548B28RWWR/TI
2ND AL053319002/RS53319LR/REEDSEMI
1ST AL008633005/MPQ8633BGLE-C838-Z/MPS
2022/5/14 MODIFY
3RD PC212 CHANGE TO CH5222KEB01
PC259 CHANGE TO CH13306JB14
BOM CHANGE R&C TABLE
2ND NA
3RD=CX000220000
2ND=CX220Z06Z00
IRATED=5A@125C
10*10*4
DCR=3.3M OHM
ISAT:25A@100C
PCMC104T-1R0MN
2ND=CV-10I0MZ00
Thu Aug 24 14:09:27 2023<NAME_2>
<NAME_1>
MB FABCGTI V02
209 OF 365
P 3V 3_A UX
P 12V _A UX
P 3V 3_A UX
P V DD18_S 5_P 0
27
81
27
81
3310%
25V
1UF
C0402
X 6S
10%
16V
0.22UF
X 7R
0402
25V
0.1UF
0402
10%
E MP TY
X 6S
1UF
C0402
25V
10%
5%
X7R
50V
1.0UH/18A
S MLF
P W RG D_P V DD18_S 5_P 0
CHIP
0402LF
2.2
1000PF
IND
CHIP
SW_PVDD18_S5_P0_BST_RS W _P V DD18_S 5_P 0_B S T
1%
0402LF
S W _P V DD18_S 5_P 0_S W
25V
0.1UF
P V DD18_S 5_P 0_RG ND
P V DD18_S 5_P 0_FB
X 6S
20%
22UF
16V 16V
20% 20%
C0805
S W _P 12V _A UX _P V DD18_S 5_P 0_FLT
20%
16V
PVDD18_S5_P0
22UF
C0805
20%
4V
0402LF
1K
1%
CHIP
1/16W
X 7R
10%
0.1UF
25V
0402
S MLF
2.5V
390UF
20%
A LUM
4V
22UF
20%
E MP TY
C0805
CHIP
1/16W
1%
49.9
0402LF
E MP TY
C0805
20%
4V
22UF
C0805
4V
22UF
4V
22UF
20%
C0805
X 6S
20K CHIP
C0402 10%
E MP TY
0402
X 7R
220P F 50V
10%
1/16W
CHIP
0402LF
49.9
1%
5%
10K
1/16W
0402LF
1/16W
1%
CHIP
10K
X 7R
10% 0402
10%
25V
0402
X 7R
SMLF
0402LF
8.66K
1%
CHIP
1/16W
0 5%
CHIP 1/16W
0402LF
0402LF
0
5%
CHIP
1/16W
IND
X 6S
25V
0.1UF
10%
C0402
P V DD18_S 5_P 0_FB _RC
V S E NS E _P V DD18_S 5_P 0_DN
P V DD18_S 5_P 0_MO DE
P V DD18_S 5_P 0_CS
0402
FM_P W RG D_P V DD18_S 5_P 0
20%
X 6SX 6S
CHIP
V S E NS E _P V DD18_S 5_P 0_DP
5%
0402LF
P V DD18_S 5_P 0_RE F
0.022UF
25V
0
0.01UF 1/16W
0402LF
CHIP
1%
10
1/16W
0402LF
P V DD18_S 5_P 0_V CC
MP Q 8633B G LE -C838-Z
IC
S MLF
B LM18S N220TN1D/8000MA
P V DD18_S 5_P 0_E N
16V
22UF
X 6S
C0805
X 6S
22UF
C0805
X 6S
C0805
22UF
20%
16V
X 6S
C0805
22UF
PR8001
PC8002
2
1 PC285
21 R177
2
1
PR439
2
1 PC215
2
1 PC115
2
1 PC261
21
PR438
2
1 PC260
2
1 PC288
2
1 PC114
21
PR434
PR435
21
PL78
21
PR471
PC6005
21
PC259
PR418
2
1
R8465
2
1 PC237
2
1 PC81
2
1 PC254
2
1 PC227
2
1
PC209
2
1
PR470
PC113
2
1 PC258
21
10
19
5
20
6
9
11_18
4
7
8
3
1
2
PU57
2
1
PR448
21
PR417
2
1
PR477
2
1
PC212
2
1 PC111
21
PL77
PC6001
2
1C674
2
1
21
2
1
C5001
1 2
1 2
VIN2
CS
MODE
TRK_REF
SW
RGND
VCC
AGND
FB
BST
EN
PGND
PGOODVIN1
21
2
1
2
1
2
1
2
1
1
SHEETDATE
23
7 3 2 16 5 4
E
A
B
C
E
D
C
B
A
7 6 5 4
D
DEPARTMENT
SIZE
PROJECT DOCUMENT NUMBER REV
REVIEWER
DESIGNER
OUT
IN
IN
IN
C



IRM REV1.09
SVI3 ADDRESS=PORT0 (0X2)
EFFICIENCY > 90% @TDC
WORK FREQUENCY=600KHZ
MAX LOAD RELEASE=95A
MAX LOAD STEP=45A
OCP=156A (EDC*1.2)
PVDDCR_SOC_P1 SPECFICATION
DEFAULT POWER-ON VID=0.9V
IRM REV1.09
SVI3 ADDRESS=PORT0 (0X1)
EFFICIENCY > 90% @TDC
WORK FREQUENCY=600KHZ
VID=0.75-1.2V
MAX LOAD RELEASE=200A
LOAD-LINE=0.4MOHM
20220413:
2ND SOURCE:INFENEON BOM
PR159 = CS21472FB02
PR530,PR436,PR437 = EMPTY
PR4 = CS21002FB06
PR157 = CS25362FB02
PU25 = TBD/XDPE192C3B
RENESAS
INFINEON
/52.3K
20220413:
OCP=276A (EDC*1.2)
EDC=230A
TDC=175A
MAX LOAD STEP=200A
TRACE WIDTH = 10MIL
DIFFERENTIAL PAIR
PVDDCR_CPU0_P1 SPECFICATION
DC=+/-20MV
VID=0.55-1.5V
DEFAULT POWER-ON VID=0.9V
MAX AC=VID+200MV
MIN AC=VID-EDC*LL-110MV
MIN AC=VID-150MV
MAX AC=VID+150MV
TDC=105A
EDC=130A
DC=+/-20MV
TRACE SPACING = 5MIL
VR
MPS
TRACE SPACING = 5MIL
0/5.23K
/1.47K
PC243 = CH3104J1B00
PC251 = CH5103KEB01
PR173,PR174 = CS01002FB07
3RD SOURCE:MPS BOM
PC6 = CH21006JB10
PR4 = CS00002JB13
PC251=CH5103KEB01
PC250,PC253 = CH31004KB17
PR602 = CS24992FB07
PR181 = CS37502FB05
PR159 = CS35232FB02
PR530,PR436,PR437=EMPTY
PC244,PC245,PR157,PC243 = EMPTY
PU25 = TBD/MP2857GQKT-001C-Z
PC244,PC245 = CH12206KB14
PC253,PC250 = CH11006JB00
TRACE WIDTH = 10MIL
DIFFERENTIAL PAIR
PU25 = TBD/RAA229620GNP#HA0
MAIN SOURCE:RENESAS BOM
BOM NOTE
2022/5/14 MODIFYPR173 IS CHANGED FROM 10 TO 0 OHM
0X4D
0X4D
0X72
ADDRESS(7-BIT) CONFIG/R
PMBUS ADDRESS AND CONFIG
PR150 IS CHANGED FROM 1K TO 0 OHM
PR174 IS CHANGED FROM 10 TO 0 OHM
Thu Aug 24 14:09:06 2023<NAME_2>
<NAME_1>
MB FABCGTI V02
210 OF 365
I16
P V DD18_S 5_P 1
P V DD18_S 5_P 1
P 12V _A UX
P 3V 3_A UX
P 3V 3_A UX
P 3V 3_A UX
P V DD18_S 5_P 1
P V DDCR_S O C_P 1
P 5V _A UX
P V DDCR_CP U0_P 1
P 3V 3_A UX
1K
0402LF
49.9 1% 0402LF1/16W
P V DDCR_CP U0_P 1_RE S E T_N
CHIP
PVDDCR_CPU0_P1/PVDDCR_SOC_P1 VR CONTROLLER
X 7R
5%
P V DDCR_S O C_P 1_E N_G D
P V DDCR_CP U0_P 1_V CC
16V
1/16W
0402LF
5%
0402
CHIP
P V DDCR_CP U0_P 1_P MA LE RT
S MB _V R_3V 3S TB Y _S DA
CHIP
1/16W
50V
10%
P V DDCR_CP U0_P 1_TE MP 0
5%
1000P F
50V1000P F
V S E NS E _V S S _S E NS E _A _P 1
50V
0402LF
1/16W 0 5%
1K
0402LF
1%
1UF
CHIP
CHIP
P W RG D_P V DDCR_S O C_P 1_R
0402LF
5%
0402LF
0402
0402LF
E MP TY
V S E NS E _P V DDCR_S O C_P 1_DP
P V DDCR_CP U0_P 1_O CP _N_R
P V DDCR_CP U0_P 1_V CCS
E MP TY
1K
1%
1K
1/16W
CHIP
1/16W
CHIP
1%
1K
0402LF
IC
0.1UF
25V
10%
0402
1%
49.9
1%
CHIP
0402LF
49.9
CHIP 1/16W1K
1/16W
CHIP
49.9
1/16W
5%0
0402LF
1/16W
E MP TY
1%
4.99K
0402LF 0402
25V
0.1UF
10%
X 7R
50V1000P F
1/16WCHIP
10%
3300P F
50V
X 7R
0402
0402
10%
3300P F
50V
X 7R
50V
5%
10P F
0402
50V
5%
10P F
0402
50V
5%
E MP TY
10P F
1%
1K 1K
1%
0402LF
1K
CHIP
1%
0402LF
1/16W
1/16W
1%
0402
5%
0402
0402
470P F
X 7R
0402
50V
470P F
10%
X 7R
1/16WCHIP 5%0
1/16WCHIP 0
01/16WCHIP
25V
0.1UF
10%
X 7R
0.1UF
0402
25V
10%
X 7R
X 6S
20%
10UF
6.3V
C0402
X 6S
C0402
1UF
10%
CHIP
1%1
0402LF
10%X 7R
6.3V
0402
1%
0
1/16W
1%
0402LF
1/16W
E MP TY E MP TY
1/16W
E MP TY
0402LF
P V DDCR_CP U0_P 1_O CP _N
CHIP
1/16W
B S S 138K
0402LF
1/16W
EMPTY
1%
1/16W
0402LF
0402
E MP TY
CHIP
1/16W
1%
10K
5% 0402
1000P F
1%
1000P F
X 7R
5%
50V
49.9
0402X 7R
5% 50V
1000P F
5%
1/16W
5%
0
0402
0402LF
1/16W
CHIP
0402LF
0402LF
1%
1/16W
CHIP 0402LF
0
CHIP
1/16W
5%0
V S E NS E _P V DDCR_CP U0_P 1_DP 5%
1%
0402LF
1%
1/16W
0402
50V
33
CHIP
1/16W
0402LF
P W RG D_P V DDCR_S O C_P 1
5%
0402LF
5%33
CHIP
CHIP
33
0S MB _V R_3V 3S TB Y _S CL
10K
5%
0
CHIP
P V DDCR_S O C_P 1_E N
1K
5.23K
1%
1/16W
CHIP
0402LF
X 7R
1000P F
5%
CHIP
X 7R
0402LF
40.2K
5%
E MP TY
0402LF
1/16W
IC
P V DDCR_S O C_P 1_E N_RC
50V
P JA 3415A E
0402LF
V S E NS E _V S S _S E NS E _A _P 1
0402LF
CHIP
5%
1/16W
0402LF
5%
1/16W
0402LF
5%
1/16W
0402LF
0S V ID_P V DDCR_CP U0_P 1_S V TI
CHIP
0
E MP TY
X 7R
0
S V ID_P V DDCR_CP U0_P 1_S V C_R
CHIP
1/16W
0402LF
0402LF
0402LF
CHIP
P V DDCR_CP U0_P 1_E N
P W RG D_P V DDCR_CP U0_P 1
1/16W
0402LF
5%
S V ID_P V DDCR_CP U0_P 1_S V D_R
0402LF
5%
CHIP
1/16W
0
1/16W
0402LF
1/16W
CHIP
S V ID_P V DDCR_CP U0_P 1_S V TO 49.9 1%
RA A 229620G NP #HA 0
SMLF
IC
P V DDCR_CP U0_P 1_IMO N1
S V ID_P V DDCR_CP U0_P 1_S V TI_R
P V DDCR_CP U0_P 1_P MS CL_R
SVID _PVD D C R _C PU 0_P1_SVC _R 1
P V DDCR_CP U0_P 1_IMO N6
S V ID_P V DDCR_CP U0_P 1_S V TO _R
P V DDCR_CP U0_P 1_RE S E T_N_R
NC_P V DDCR_CP U0_P 1_IMO N7
NC_P V DDCR_CP U0_P 1_IMO N8
SVID _PVD D C R _C PU 0_P1_SVD _R 1
P V DDCR_CP U0_P 1_P MA LE RT_R
P V DDCR_CP U0_P 1_E N_R
P V DDCR_CP U0_P 1_P MS DA _R
NC_P V DDCR_CP U0_P 1_P W M8
NC_P V DDCR_CP U0_P 1_P W M7
V S E NS E _P V DDCR_CP U0_P 1_V S E N0
P V DDCR_S O C_P 1_P W M2
P W RG D_P V DDCR_CP U0_P 1_R
P V DDCR_CP U0_P 1_P W M6
P V DDCR_CP U0_P 1_V MO N
P V DDCR_CP U0_P 1_V INS E N
V S E NS E _P V DDCR_S O C_P 1_V S E N1
P V DDCR_S O C_P 1_IMO N2
P V DDCR_CP U0_P 1_P W M1
NC_P V DDCR_CP U0_P 1_P W M9
NC_P V DDCR_CP U0_P 1_IMO N9
P V DDCR_S O C_P 1_P W M3
P V DDCR_S O C_P 1_IMO N3
P V DDCR_S O C_P 1_E N//A DDR_CFG
P V DDCR_S O C_P 1_TE MP 1
P V DDCR_S O C_P 1_P W M1
P V DDCR_S O C_P 1_IMO N1
P V DDCR_CP U0_P 1_P W M5
P V DDCR_CP U0_P 1_IMO N5
P V DDCR_CP U0_P 1_P W M4
P V DDCR_CP U0_P 1_IMO N4
P V DDCR_CP U0_P 1_P W M3
P V DDCR_CP U0_P 1_IMO N3
P V DDCR_CP U0_P 1_P W M2
78
82 83
151
213
212
211
210 54
54
216215213
82
54
80
151
80
210 54
54
81
81
54
54
211
213
215
213
215
211
216
216
216215
215
215
213
213
212
212
212
212
211
1/16W
E MP TY
P V DDCR_CP U0_P 1_IMO N2
211
212211
R6087
PR8010
PR8009
PR159
21C5003
C5012
21C5019
40
25
45
46
19
48
47
T H
43
44
23
24
21
22
39
26
18
12
11
10
9
8
7
6
5
4
3
2
1
13
14
20
16
41
15
42
17
27
28
29
30
31
32
33
34
35
36
37
38
PU25
21
PC247
21
PR183
2
1 PC252
2
1 PC251
2
1 PC10
21
PR530
21
PR436
PR437
2
1 PC253
2
1 PC250
21
R8178
21 R8179
21
R8171
21
R8176
21
R8177
21
R8167
2
1
PR161
2
1
R8160
2
1 C297
2
1 C296
2
1
PC244
21
PR173
21
R8180
21
C8246
2
1 PC6PR602
2
1
PR162
21R8184
2
1
PR163
21
R8165
21
R8166
2
1 PC243
2
1
PR4
G
PQ11
2
1 PR152
G
PQ15
21
PR157
2
1
PR151
2
1
R8153
21
R149
2
1 PC11
21
C248
21
C249
21
PR172
21
R175
2
1
R8156
2
1
R154
2
1 C295
2
1
PC245
21
PR174
21
PR181
21
R8168
21
R8182
2
1
PR164
2
1 C242
2
1
PR150
SD
S D
S
G
D
G
CS10
PWM10
CS9
PWM9
CS8
PWM8
CS7
PWM7
CS0
PWM0
TEMP1
EN1||ADDR_CFG
TH_GND
OCP_L
CS2
PWM2
CS3
PWM3
PWM11
CS1
RGND1
VSEN1
VDDIO
TEMP0
VINSEN
VMON||IINSEN
VCCS
PWM6
PG0
PWM1
VSEN0
PWM5
PWM4
PMSDA
RGND0
EN0
nPMALERT
SVD
PG1
CS4
CS5
RESET_L
SVTO
CS6
SVC
PMSCL
SVTI
VCC
CS11
SD
21
21
2
1
2
1
2
1
1
SHEETDATE
23
7 3 2 16 5 4
E
A
B
C
E
D
C
B
A
7 6 5 4
D
DEPARTMENT
SIZE
PROJECT DOCUMENT NUMBER REV
REVIEWER
DESIGNER
OUT
IN
IN
OUT
IN
IN
IN
IN
IN
OUT
IN
OUT
BI
OUT
OUT
IN
IN
IN
IN
IN
OUT
OUT
OUT
IN
OUT
IN
IN
OUT
OUT
IN
IN
OUT
OUT
IN
OUT
IN
IN
C



PR189,PR190,PR197,PR198,PR203,PR424 = CS00002JB13
PU4,PU26,PU27,PU28,PU29,PU24 = AL087000A03/MP87000GMJTH-C11D-Z
PR336,PR189,PR190,PR197,PR198,PR203,PR424=CS00002JB13
3RD SOURCE:MPS BOM
PC254_1,PC255_2,PC284_3,PC285_4,PC306_5,PC124_6 = EMPTY
PR191,PR192,PR199,PR200,PR204,PR425 = EMPTY
PR187,PR188,PR195,PR196,PR202,PR423 = CS00002JB13
PU4,PU26,PU27,PU28,PU29,PU24 = AL021590000/TDA21590
2ND SOURCE:INFENEON BOM
PU4,PU26,PU27,PU28,PU29,PU24 = AL099390004/ISL99390FRZ-TR5935
PC254_1,PC255_2,PC284_3,PC285_4,PC306_5,PC124_6=EMPTY
PR335,PR191,PR192,PR199,PR200,PR204,PR425=EMPTY
PVDDCR_CPU0_P1_PHASE2
PVDDCR_CPU0_P1_PHASE1
PG2292.500HLT
DCR=0.09M OHM
2ND=CVA50^0MZ07
3RD=CVA50^0MZ08
2ND=CV+15^0TZ01
11.0*7.5*12.5
6.3*8
DCR=1-4,0.105M OHM
DCR=2-3,0.27M OHM
ESR=9M OHM
7.3*4.3*1.9
MAIN=CH122KM8801
PGL6303.151HLT
11.0*7.5*12.5
2ND=CV+15^0TZ01
ISAT:70A@100C
ISAT:70A@100C
6.0*6.1*7.0
DCR=2-3,0.27M OHM
DCR=1-4,0.105M OHM
ISAT:70A@100C
PGL6303.151HLT
2ND=CC72703MD39
IRIPPLE:5.08A
ESR=10M OHM
BOM NOTE
2022/5/14 MODIFY
MAIN SOURCE:RENESAS BOM
Thu Aug 24 14:09:06 2023<NAME_2>
<NAME_1>
MB FABCGTI V02
211 OF 365
S W _P 12V _A UX _P V DDCR_CP U0_P 1_FLT
S W _P 12V _A UX _P V DDCR_CP U0_P 1_FLT
P V DDCR_CP U0_P 1
P 12V _A UX
P V DDCR_CP U0_P 1
P V DDCR_CP U0_P 1
P V DDCR_CP U0_P 1_P V CCP 3V 3_A UX
P V DDCR_CP U0_P 1_P V CC
P 5V _A UX
PVDDCR_CPU0_P1 VR PHASE 1&2
210
211
210
211
212211
213
210211212213215216
210
211
212213210
210
212213210
210211212213215216
25V
C0402
CHIP
5.6
CHIP
S W _P V DDCR_CP U0_P 1_B O O T1
5.6 S W _P V DDCR_CP U0_P 1_B O O T2_RCS W _P V DDCR_CP U0_P 1_B O O T2
0402LF
1%
1/16W
S W _P V DDCR_CP U0_P 1_B O O T1_RC
1/16W
0402LF
1%
C0402
0.1UFIS L99390FRZ-TR5935
IC
IND
150NH
0402
X 7R
10%
SMLF
IS L99390FRZ-TR5935
IC
0402
25V
0.1UF
10%
X 7R
S MLF
S P CA P
220UF
20%
4V
0402LF
8.87K 1%
E MP TY 1/16W
1/16W
CHIP
1%
1K
0402LF
C0805
4V
22UF
X 6S
20%20%
C0805
X 6S
22UF
4V
10%
X 7R
0.1UF
25V
S MLF
IND
50NH/86A
O S CO N
16V
THLF
20%
270UF270UF
20%
THLF
16V
O S CO N
S P CA P
S MLF
4V
20%
220UF
C0805
X 6S
20%
22UF
4V
C0805
X 6S
20%
22UF
4V
20%
220UF
S MLF
S P CA P
4V
S P CA P
S MLF
4V
20%
220UF
20%
S MLF
S P CA P
4V
220UF
150NH
IND
SMLF
16V
10%
X 7R
0402
0.22UF
16V
20%
X 6S
20%
16V
22UF
X 6S
C0805
20%
16V
22UF
X 6S
560P F
50V
E MP TY
10%
C0402
X 6S
25V
C0402
10%
1UF
25V
10%
0.1UF
0402
C0402
10V
2.2UF
X 6S
10%1/16W
CHIP
1%
2.2
0402LF
1/16W
E MP TY
0402LF
0
5%
8.87K
E MP TY 1/16W
1%
0402LF
C0402
10V
2.2UF
10%
X 6S
0402LFCHIP
5%0
1/16W
1.5
1%
1/8W
0402LF
E MP TY
20%
22UF
X 6S
16V
20%
C0805
X 6S
16V
22UF
16V
22UF
C0805
X 6S
20%
25V
1UF
10%
X 6S
10%
X 7R
0402
C0402
50V
560P F
10%
E MP TY
1/16W
CHIP
5%0
0402LF
0402LF
1.5
1%
E MP TY
1/8W
0402
25V
0.1UF
10%
X 7R
10%
C0402
10V
2.2UF
X 6S
1/16W
CHIP
1%
0402LF
10V
2.2UF
10%
X 6S
0.1UF
0402
25V
10%
X 7R
1/16W
0
0402LF
5%
CHIP
S W _P V DDCR_CP U0_P 1_S W 2
S W _P V DDCR_CP U0_P 1_S W 1
S W _P V DDCR_CP U0_P 1_P H2
P V DDCR_CP U0_P 1_IMO N1
S W _P V DDCR_CP U0_P 1_P H1
P V DDCR_CP U0_P 1_V CC2
IND_CP U0_P 1_CP L1
IND_CP U0_P 1_CP L2IND_CP U0_P 1_CP L1
IND_CP U0_P 1_CP L5
NC_P V DDCR_CP U0_P 1_G L1_1
NC_P V DDCR_CP U0_P 1_G L2_1
P V DDCR_CP U0_P 1_LS E T1
P V DDCR_CP U0_P 1_V CCS
P V DDCR_CP U0_P 1_V O S 2
NC_P V DDCR_CP U0_P 1_G L2_2
NC_P V DDCR_CP U0_P 1_G L1_2
P V DDCR_CP U0_P 1_P W M1
P V DDCR_CP U0_P 1_TE MP 0
NC_P V DDCR_CP U0_P 1_DNC2
P V DDCR_CP U0_P 1_LS E T2
P V DDCR_CP U0_P 1_IMO N2
P V DDCR_CP U0_P 1_TE MP 0
P V DDCR_CP U0_P 1_P W M2
P V DDCR_CP U0_P 1_V CCS
SMLF2.2
22UF
P V DDCR_CP U0_P 1_V O S 1
0402
P V DDCR_CP U0_P 1_V CC1
C0805
S W _P V DDCR_CP U0_P 1_S W 2_RC
NC_P V DDCR_CP U0_P 1_DNC1
S W _P V DDCR_CP U0_P 1_S W 1_RC
C0805C0805
SMLF
16V
0.22UF
X 7R
1
30
25_29
3
36
10_19
39
34
4
32
40
7_9-20_24
5
37
38
41
6
35
31
33
2
PU26
4
32
1
PL28
2
1
PC270
1
30
25_29
3
36
10_19
39
34
4
32
40
7_9-20_24
5
37
38
41
6
35
31
33
2
PU4
2
1 PC278
2
1 PC105
21
PR190
21
PR188
PR337
2
1 PC283_1
2
1 PC281_1
PC6004
21
PL30
2
1 PC272
2
1 PC280_2
2
1 PC277
2
1 PC276
2
1 PC275
4
32
1
PL29
2
1
PC271
2
1 PC268_1
2
1 PC266_1
2
1 PC264_1
21
PR189
2
1 PC262_1
2
1 PC258_C0P1_1
2
1
PR185
PR336
21
PR187
2
1 PC256
2
1
PR485
2
1 PC267_2
2
1 PC265_2
2
1 PC261_2
21
PR192
2
1
PR486
2
1 PC257
2
1 PC255_2
2
1 PC273
2
1 PC279
2
1 PC282_2
2
1 PC170
2
1 PC260_1
21
PR191
2
1 PC269_2
2
1 PC263_2
2
1 PC173
2
1 PC254_1
2
1 PC259_C0P1_2
2
1
PR186
PR335
PGND2
GL2
GL1
DNC
EN
PGND3
VOS
VIN2
PGND1
SW
LSET
IOUT
TOUT_FLT
PVCC
PHASE
VIN1
BOOT
AGND
VCC
REFIN
PWM
1 4
32
PGND2
GL2
GL1
DNC
EN
PGND3
VOS
VIN2
PGND1
SW
LSET
IOUT
TOUT_FLT
PVCC
PHASE
VIN1
BOOT
AGND
VCC
REFIN
PWM
1 2
1 4
32
2
1
1
SHEETDATE
23
7 3 2 16 5 4
E
A
B
C
E
D
C
B
A
7 6 5 4
D
DEPARTMENT
SIZE
PROJECT DOCUMENT NUMBER REV
REVIEWER
DESIGNER
OUT
BI
IN
OUT
BIBI
BI
OUT
IN
OUT
IN
IN
C



PVDDCR_CPU0_P1_PHASE3
11.0*7.5*12.5
2ND=CV+15^0TZ01
DCR=2-3,0.27M OHM
DCR=1-4,0.105M OHM
ISAT:70A@100C
PGL6303.151HLT
PGL6303.151HLT
11.0*7.5*12.5
DCR=2-3,0.27M OHM
DCR=1-4,0.105M OHM
ISAT:70A@100C
2ND=CV+15^0TZ01
PVDDCR_CPU0_P1_PHASE4
Thu Aug 24 14:09:27 2023<NAME_2>
<NAME_1>
MB FABCGTI V02
212 OF 365
P V DDCR_CP U0_P 1
S W _P 12V _A UX _P V DDCR_CP U0_P 1_FLT
P V DDCR_CP U0_P 1
S W _P 12V _A UX _P V DDCR_CP U0_P 1_FLT
P V DDCR_CP U0_P 1_P V CC
P V DDCR_CP U0_P 1_P V CC
212211
212
210
210
210211212213215216
211
212213210
210
210
210211212213215216
211212
213210
C0402
X 6S
0402LF
1/16W
S W _P V DDCR_CP U0_P 1_B O O T3
S W _P V DDCR_CP U0_P 1_P H3
5.6P V DDCR_CP U0_P 1_V CC3
C0402
S W _P V DDCR_CP U0_P 1_B O O T3_RC1%
CHIP
5.6 S W _P V DDCR_CP U0_P 1_B O O T4_RCS W _P V DDCR_CP U0_P 1_B O O T4
1/16W
CHIP 0402LF
1%
1UF
20%
C0805
PVDDCR_CPU0_P1 VR PHASE 3&4
4V
22UF
20%
X 6S
C0805
4V
22UF
20%
X 6S
C0805
IND
150NH
SMLF
C0805
X 6S
22UF
16V
20%
0.22UF
16V
10%
X 7R
0402
4V
22UF
20%
X 6S
C0805
4V
22UF
20%
X 6S
C0805
X 6S
22UF
16V
20%
SMLF
IND
150NH
X 7R
10%
0.22UF
16V
0402
C0805
X 6S
16V
20%
X 6S
22UF
16V
20%
C0402
X 6S
10%
1UF
25V
E MP TY
10%
560P F
50V
C0402
1/8W
E MP TY
1%
1.5
0402LF
X 7R
10%
0.1UF
25V
0402
2.2UF
C0402
10V
X 6S
10%
SMLF
IC
IS L99390FRZ-TR5935
2.2
1/16W
0402LF
1%
CHIP
X 6S
10%
2.2UF
10V
8.87K 1%
1/16W
0402LF
0402
X 7R
10%
0.1UF
25V
0402LF
0 5%
CHIP
1/16W
C0805
22UF
16V16V
X 6SX 7R
10%
E MP TY
10%
560P F
50V
C0402
1/8W
E MP TY
1%
1.5
0402LF
0402LF
0 5%
CHIP
1/16W
10%
X 6S
2.2UF
10V
C0402
1/16W
CHIP
1%
2.2
0402LF
8.87K 1%
1/16WE MP TY
0402LF
SMLF
IS L99390FRZ-TR5935
X 6S
10%
2.2UF
10V
C0402
X 7R
10%
0.1UF
25V
0402
IND_CP U0_P 1_CP L3IND_CP U0_P 1_CP L2
IND_CP U0_P 1_CP L3
S W _P V DDCR_CP U0_P 1_P H4
S W _P V DDCR_CP U0_P 1_S W 3_RC
NC_P V DDCR_CP U0_P 1_G L1_3
NC_P V DDCR_CP U0_P 1_G L2_3
P V DDCR_CP U0_P 1_IMO N3
P V DDCR_CP U0_P 1_P W M3
NC_P V DDCR_CP U0_P 1_DNC3
P V DDCR_CP U0_P 1_LS E T3
P V DDCR_CP U0_P 1_V CCS
P V DDCR_CP U0_P 1_V O S 3
S W _P V DDCR_CP U0_P 1_S W 4_RC
P V DDCR_CP U0_P 1_V O S 4
NC_P V DDCR_CP U0_P 1_G L2_4
S W _P V DDCR_CP U0_P 1_S W 4
NC_P V DDCR_CP U0_P 1_G L1_4
P V DDCR_CP U0_P 1_V CC4
P V DDCR_CP U0_P 1_TE MP 0
P V DDCR_CP U0_P 1_LS E T4
NC_P V DDCR_CP U0_P 1_DNC4
P V DDCR_CP U0_P 1_IMO N4
P V DDCR_CP U0_P 1_P W M4
P V DDCR_CP U0_P 1_V CCS
22UF
S W _P V DDCR_CP U0_P 1_S W 3
C0805
20%
22UF0.1UF
25V25V
IC
C0805
X 6S
10%
0402
E MP TY
P V DDCR_CP U0_P 1_TE MP 0
2
1 PC304_3
2
1 PC302_3
4
32
1
PL31
2
1 PC298_3
2
1
PC300
2
1 PC305_4
2
1 PC303_4
2
1 PC299_4
4
32
1
PL32
2
1
PC301
2
1 PC296_3
2
1 PC294_3
2
1 PC292_3
21
PR197
2
1 PC316
2
1
PR522
2
1 PC290_3
2
1 PC288_C0P1_3
1
30
25_29
3
36
10_19
39
34
4
32
40
7_9-20_24
5
37
38
41
6
35
31
33
2
PU27
2
1
PR193
2
1 PC286
21
PR195
2
1 PC284_3
21
PR199
2
1 PC297_4
2
1 PC295_4
2
1 PC291_4
2
1 PC293_4
21
PR198
2
1 PC317
2
1
PR523
21
PR200
2
1 PC289_C0P1_4
2
1
PR194
21
PR196 1
30
25_29
3
36
10_19
39
34
4
32
40
7_9-20_24
5
37
38
41
6
35
31
33
2
PU28
2
1 PC287
2
1 PC285_4
PGND2
GL2
GL1
DNC
EN
PGND3
VOS
VIN2
PGND1
SW
LSET
IOUT
TOUT_FLT
PVCC
PHASE
VIN1
BOOT
AGND
VCC
REFIN
PWM
1 4
32
1 4
32
PGND2
GL2
GL1
DNC
EN
PGND3
VOS
VIN2
PGND1
SW
LSET
IOUT
TOUT_FLT
PVCC
PHASE
VIN1
BOOT
AGND
VCC
REFIN
PWM
1
SHEETDATE
23
7 3 2 16 5 4
E
A
B
C
E
D
C
B
A
7 6 5 4
D
DEPARTMENT
SIZE
PROJECT DOCUMENT NUMBER REV
REVIEWER
DESIGNER
IN
OUT
BIBI
BI
OUT
OUT
IN
IN
OUT
IN
C



6.5*6.5*10.0
2ND=CV+12^0EZ04
ISAT:60A@100C
DCR=0.17M OHM
PGL6312.121AHLT
PVDDCR_CPU0_P1_PHASE6
DCR=1-4,0.105M OHM
11.0*7.5*12.5
ISAT:70A@100C
PGL6303.151HLT
2ND=CV+15^0TZ01
DCR=2-3,0.27M OHM
ISAT:70A@100C
PGL6303.151HLT
11.0*7.5*12.5
2ND=CV+15^0TZ01
DCR=1-4,0.105M OHM
DCR=2-3,0.27M OHM
PVDDCR_CPU0_P1_PHASE5
Thu Aug 24 14:09:27 2023<NAME_2>
<NAME_1>
MB FABCGTI V02
213 OF 365
P V DDCR_CP U0_P 1_P V CC
P V DDCR_CP U0_P 1_P V CC
S W _P 12V _A UX _P V DDCR_CP U0_P 1_FLT
P V DDCR_CP U0_P 1
S W _P 12V _A UX _P V DDCR_CP U0_P 1_FLT
P V DDCR_CP U0_P 1
210211212213215216
210
210
211
212213210
210
210
210211212213215216
211
212213210
213
213 211
X 6S
C0805
P V DDCR_CP U0_P 1_V O S 5
NC_P V DDCR_CP U0_P 1_G L2_5
P V DDCR_CP U0_P 1_LS E T58.87K
0.1UF
S W _P V DDCR_CP U0_P 1_S W 5
S W _P V DDCR_CP U0_P 1_S W 5_RC
1/16W
P V DDCR_CP U0_P 1_V CCS
P V DDCR_CP U0_P 1_IMO N6
P V DDCR_CP U0_P 1_P W M6
P V DDCR_CP U0_P 1_TE MP 0
NC_P V DDCR_CP U0_P 1_DNC6
P V DDCR_CP U0_P 1_LS E T6
P V DDCR_CP U0_P 1_V CC6
P V DDCR_CP U0_P 1_P W M5
NC_P V DDCR_CP U0_P 1_G L2_6
NC_P V DDCR_CP U0_P 1_G L1_6
S W _P V DDCR_CP U0_P 1_S W 6
P V DDCR_CP U0_P 1_V O S 6
S W _P V DDCR_CP U0_P 1_S W 6_RC
P V DDCR_CP U0_P 1_IMO N5
P V DDCR_CP U0_P 1_V CCS
P V DDCR_CP U0_P 1_TE MP 0
NC_P V DDCR_CP U0_P 1_DNC5
P V DDCR_CP U0_P 1_V CC5
NC_P V DDCR_CP U0_P 1_G L1_5
S W _P V DDCR_CP U0_P 1_P H5
S W _P V DDCR_CP U0_P 1_P H6
IND_CP U0_P 1_CP L6
IND_CP U0_P 1_CP L6 IND_CP U0_P 1_CP L5
0402
25V
0.1UF
10%
X 7R
0402LF
8.87K 1%
E MP TY 1/16W
C0402
10V
2.2UF
10%
X 6S
CHIP
1/16W
1%
2.2
0402LF
X 6S
10%
10V
C0402
2.2UF
IS L99390FRZ-TR5935
IC
SMLF
1%
0402LF
1.5
E MP TY
1/8W
5%
1/16W
CHIP
0
0402LF
C0402
10%
560P F
0.1UF
10%
X 7R
20%
16V
22UF
X 6S
20%
16V
22UF
X 6S
C0805
0402LF
1.5
1%
E MP TY
1/8W
5%
1/16W
0402LFCHIP
0
25V
10%
X 7R
0402
1%
E MP TY
C0402
10V
2.2UF
10%
X 6S
1/16W
CHIP
1%
2.2
0402LF C0402
10V
2.2UF
10%
X 6S
0402
25V
0.1UF
10%
X 7R
C0402
560P F
50V
10%
E MP TY
25V
1UF
10%
X 6S
20%
16V
22UF
C0805
20%
16V
22UF
X 6S
0402
16V
0.22UF
10%
X 7R
150NH
IND
SMLF
20%
16V
22UF
X 6S
C0805
C0805
X 6S
20%
22UF
4V
22UF
C0805
X 6S
20%
4V
X 7R
10%
16V
0.22UF
0402
IND
150NH
SMLF
20%
16V
22UF
C0805
X 6S
20%
22UF
4V
C0805
X 6S
20%
22UF
4V
IS L99390FRZ-TR5935
IC
SMLF
PVDDCR_CPU0_P1 VR PHASE 5&6
C0805
C0805
25V
IND
S MLF
120NH/69A
50V
E MP TY
IND_CP U0_P 1_CP L0
CHIP
1%
0402LF
1/16W
S W _P V DDCR_CP U0_P 1_B O O T6 S W _P V DDCR_CP U0_P 1_B O O T6_RC5.6
CHIP
1%
1/16W
0402LF
S W _P V DDCR_CP U0_P 1_B O O T5 S W _P V DDCR_CP U0_P 1_B O O T5_RC5.6
0402LF
C0402
X 6S
1UF
25V
10%
X 6S
C04020402
1
30
25_29
3
36
10_19
39
34
4
32
40
7_9-20_24
5
37
38
41
6
35
31
33
2
PU24
2
1 PC316_5
2
1 PC315_5
2
1 PC313_5
4
32
1
PL33
2
1
PC314
2
1 PC135_6
2
1 PC134_6
2
1 PC132_6
4
32
1
PL8
2
1
PC133
21
PL27
2
1 PC312_5
2
1 PC311_5
2
1 PC310_5
21
PR203
2
1 PC318
2
1 PC309_5
2
1 PC308_C0P1_5
2
1
PR201
2
1 PC307
21
PR202
2
1 PC306_5
21
PR204
2
1
PR46
2
1 PC130_6
2
1 PC129_6
21
PR424
2
1 PC128_6
2
1 PC127_6
2
1 PC321
21
PR425
2
1
PR524
1
30
25_29
3
36
10_19
39
34
4
32
40
7_9-20_24
5
37
38
41
6
35
31
33
2
PU29
2
1 PC126_C0P1_6
2
1
PR422
2
1 PC125
21
PR423
2
1 PC124_6
PGND2
GL2
GL1
DNC
EN
PGND3
VOS
VIN2
PGND1
SW
LSET
IOUT
TOUT_FLT
PVCC
PHASE
VIN1
BOOT
AGND
VCC
REFIN
PWM
1 4
32
1 4
321 2
PGND2
GL2
GL1
DNC
EN
PGND3
VOS
VIN2
PGND1
SW
LSET
IOUT
TOUT_FLT
PVCC
PHASE
VIN1
BOOT
AGND
VCC
REFIN
PWM
1
SHEETDATE
23
7 3 2 16 5 4
E
A
B
C
E
D
C
B
A
7 6 5 4
D
DEPARTMENT
SIZE
PROJECT DOCUMENT NUMBER REV
REVIEWER
DESIGNER
IN
BIBI
OUT
BI
OUT
OUT
IN
IN
OUT
IN
C



Thu Aug 24 10:15:19 2023<NAME_2>
<NAME_1>
MB FABCGTI V02
214 OF 365Blank
1
SHEETDATE
23
7 3 2 16 5 4
E
A
B
C
E
D
C
B
A
7 6 5 4
D
DEPARTMENT
SIZE
PROJECT DOCUMENT NUMBER REV
REVIEWER
DESIGNER
C



PU30,PU31,PU32 = AL087000A03/MP87000GMJTH-C11D-Z
3RD SOURCE:MPS BOM
PR207,PR208,PR214 = CS00002JB13
PR209,PR210,PR215 = CS00002JB13
PU30,PU31,PU32 = AL021590000/TDA21590
PR209,PR210,PR215=CS00002JB13
PC317_7,PC318_8,PC345_9 = EMPTY
2ND SOURCE:INFENEON BOM
PU30,PU31,PU32 = AL099390004/ISL99390FRZ-TR5935
2022/5/14 MODIFY
BOM NOTE
PR211,PR212,PR216 = EMPTY
PR211,PR212,PR216=EMPTY
PC317_7,PC318_8,PC345_9=EMPTY
MAIN SOURCE:RENESAS BOM
PVDDCR_SOC_P1_PHASE1
ESR=4.5M OHM
2ND=CH747LM8822
7.3*4.3*1.9
DCR=2-3,0.27M OHM
DCR=1-4,0.105M OHM
PGL6303.151HLT
ISAT:70A@100C
11.0*7.5*12.5
2ND=CV+15^0TZ01
DCR=2-3,0.27M OHM
2ND=CV+15^0TZ01
DCR=1-4,0.105M OHM
11.0*7.5*12.5
ISAT:70A@100C
ESR=10M OHM
3RD=CVA50^0MZ08
PGL6303.151HLT
PG2292.500HLT
6.0*6.1*7.0
ISAT:70A@100C
DCR=0.09M OHM
2ND=CVA50^0MZ07
2ND=CC72703MD39
6.3*8
IRIPPLE:5.08A
PVDDCR_SOC_P1_PHASE2
Thu Aug 24 14:09:06 2023<NAME_2>
<NAME_1>
MB FABCGTI V02
215 OF 365
S W _P 12V _A UX _P V DDCR_S O C_P 1_FLT
S W _P 12V _A UX _P V DDCR_S O C_P 1_FLT P 12V _A UX
P V DDCR_S O C_P 1
P V DDCR_S O C_P 1
P V DDCR_S O C_P 1
P V DDCR_CP U0_P 1_P V CC
P V DDCR_CP U0_P 1_P V CC
210
NC_P V DDCR_S O C_P 1_DNC2
IC
IS L99390FRZ-TR5935
210211212213215216
215216
210
215
216210
210211212213215216
215
216210
210
215
210
X 7R
0402LF
E MP TY
S W _P V DDCR_S O C_P 1_S W 1_RC
560P F
5.6 S W _P V DDCR_S O C_P 1_B O O T1_RCS W _P V DDCR_S O C_P 1_B O O T1 1%
CHIP 0402LF
1/16W
5.6 S W _P V DDCR_S O C_P 1_B O O T2_RCS W _P V DDCR_S O C_P 1_B O O T2 1%
CHIP 0402LF
1/16W
22UF
20%
16V
X 6S
C0805
22UF
C0805
X 6S
C0805C0805
20%
16V
CHIP
150NH
SMLF
0.22UF
16V
10%
C0805
THLF
C0805
X 6S
20%
16V 16V
S MLF
X 6SX 6S O S CO N
IND
22UF
X 6S
C0805
16V
20%20%
X 6S
25V
1UF
25V 16V 20%
16V
50NH/86A
22UF
4V
10%
22UF
0.1UF
1/16W20%
C0805
X 6S
20%
4V
1K
X 6S
10%
0402
22UF
16V
P V DDCR_S O C_P 1_V O S 1
NC_P V DDCR_S O C_P 1_G L1_1
10%
25V
IS L99390FRZ-TR5935
IC
0.1UF
25V
10%
22UF
X 6S
20%
PVDDCR_SOC_P1 VR PHASE 1&2
SMLF
0402LF
5%
1/16W
CHIP
0
1%
CHIP
0402LF
22UF
X 6S
C0805
X 7R
10%
25V
0402
10%
0402
0.1UF
X 7R
IND
X 7R
0402
S MLF
S P CA P
2.5V
20%
470UF
E MP TY
20%
470UF
2.5V
S MLF
4V
22UF
20%
X 6S
C0805
4V
22UF
20%
X 6S
C0805
S MLF
S P CA P
20%
470UF
2.5V
X 6S
22UF
16V
20%
X 7R
16V
0402
150NH
SMLF
IND
C0805C0805
10%
50V
C0402
X 6S
C04020402
X 6S
2.2UF
C04020402LF
1%
2.2
CHIP
1/16W
X 6S
10%
2.2UF
C0402
10V
E MP TY
1%8.87K
0402LF
1/16W
X 7R
10%
0.1UF
25V
0402
0402LF
5%
1/16W
0
1.5
1/8W
1%
16V
C0805
20%
X 6S
1UF
C0402
1/8W
E MP TY
1%
1.5
0402LF
E MP TY
10%
560P F
50V
C0402
SMLF
X 6S
10%
2.2UF
10V
C0402
2.2
1%
CHIP
1/16W
0402LF
10%
10V
C0402
2.2UF
E MP TY
1%8.87K
1/16W
0402LF
X 7R
10%
0.1UF
25V
0402
P V DDCR_CP U0_P 1_V CCS
P V DDCR_S O C_P 1_P W M2
P V DDCR_S O C_P 1_V O S 2 IND_S O C_P 1_CP L2IND_S O C_P 1_CP L3
S W _P V DDCR_S O C_P 1_P H2
NC_P V DDCR_S O C_P 1_G L2_1
S W _P V DDCR_S O C_P 1_S W 1
P V DDCR_S O C_P 1_P W M1
P V DDCR_S O C_P 1_TE MP 1
P V DDCR_S O C_P 1_LS E T1
NC_P V DDCR_S O C_P 1_DNC1
P V DDCR_CP U0_P 1_V CCS
S W _P V DDCR_S O C_P 1_S W 2_RC
NC_P V DDCR_S O C_P 1_G L1_2
NC_P V DDCR_S O C_P 1_G L2_2
S W _P V DDCR_S O C_P 1_S W 2
P V DDCR_S O C_P 1_V CC2
P V DDCR_S O C_P 1_LS E T2
P V DDCR_S O C_P 1_TE MP 1
P V DDCR_S O C_P 1_IMO N2
10V
10%
0.22UF
E MP TY
IND_S O C_P 1_CP L2
P V DDCR_S O C_P 1_V CC1
P V DDCR_S O C_P 1_IMO N1
S W _P V DDCR_S O C_P 1_P H1
10%
X 6S
25V
0.1UF
X 7R
22UF
20%
270UF22UF22UF
16V
20%
PC8012
PC8011
1
30
25_29
3
36
10_19
39
34
4
32
40
7_9-20_24
5
37
38
41
6
35
31
33
2
PU31
21
PR212
2
1 PC341_1
PC6007
21
PL37
2
1 PC336PC334_1
2
1 PC342_2
2
1 PC339_2
2
1 PC337
PC335_2
2
1 PC332_2
2
1
PC334
2
1 PC331_1
2
1 PC329_1
21
PR209
2
1 PC141
2
1 PC321_SOP1_1
2
1 PC319
21
PR207
2
1 PC317_7
21
PR211
2
1 PC330_2
2
1
PR526
2
1 PC149
1
30
25_29
3
36
10_19
39
34
4
32
40
7_9-20_24
5
37
38
41
6
35
31
33
2
PU30
2
1 PC322_SOP1_2
2
1
PR206
2
1 PC320
21
PR208
PR339
2
1 PC344_1
2
1
PC338
4
32
1
PL35
2
1
PC333
2
1 PC343
2
1 PC340
4
32
1
PL36
2
1 PC327_1
2
1 PC323_1
2
1 PC325_1
2
1
PR205
2
1
PR525
2
1 PC328_2
2
1 PC324_2
21
PR210
2
1 PC326_2
2
1 PC318_8
PGND2
GL2
GL1
DNC
EN
PGND3
VOS
VIN2
PGND1
SW
LSET
IOUT
TOUT_FLT
PVCC
PHASE
VIN1
BOOT
AGND
VCC
REFIN
PWM
1 2
1 4
32
1 4
32
PGND2
GL2
GL1
DNC
EN
PGND3
VOS
VIN2
PGND1
SW
LSET
IOUT
TOUT_FLT
PVCC
PHASE
VIN1
BOOT
AGND
VCC
REFIN
PWM
2
1
2
1
2
1
1
SHEETDATE
23
7 3 2 16 5 4
E
A
B
C
E
D
C
B
A
7 6 5 4
D
DEPARTMENT
SIZE
PROJECT DOCUMENT NUMBER REV
REVIEWER
DESIGNER
OUT
IN
OUT
BIBI
BI
OUT
OUT
IN
IN
IN
C



PGL6303.151HLT
ISAT:70A@100C
DCR=1-4,0.105M OHM
DCR=2-3,0.27M OHM
11.0*7.5*12.5
2ND=CV+15^0TZ01
2ND=CV+22Y0EZ01
6.5*6.5*10.0
ISAT:30A@100C
HCME656510Q-221QL
DCR=0.17M OHM
PVDDCR_SOC_P1_PHASE3
Thu Aug 24 14:09:06 2023<NAME_2>
<NAME_1>
MB FABCGTI V02
216 OF 365
P V DDCR_CP U0_P 1_P V CC
S W _P 12V _A UX _P V DDCR_S O C_P 1_FLT
P V DDCR_S O C_P 1
210211212213215
215
210
210
210
215
0402
S W _P V DDCR_S O C_P 1_B O O T3
S W _P V DDCR_S O C_P 1_P H3
S W _P V DDCR_S O C_P 1_S W 3
P V DDCR_S O C_P 1_V O S 3
5.6 S W _P V DDCR_S O C_P 1_B O O T3_RC
CHIP
1/16W
1%
0402LF
10%
NC_P V DDCR_S O C_P 1_G L2_3
NC_P V DDCR_S O C_P 1_G L1_3
P V DDCR_CP U0_P 1_V CCS
P V DDCR_S O C_P 1_TE MP 1
P V DDCR_S O C_P 1_LS E T3
P V DDCR_S O C_P 1_P W M3
NC_P V DDCR_S O C_P 1_DNC3
P V DDCR_S O C_P 1_V CC3
P V DDCR_S O C_P 1_IMO N3
IND_S O C_P 1_CP L0 IND_S O C_P 1_CP L3
S W _P V DDCR_S O C_P 1_S W 3_RC0402
25V
0.1UF
10%
X 7R
1/16W
0402LF
8.87K 1%
E MP TY
1.5
0402LF
1%
1/8W
E MP TY
C0402
50V
560P F
E MP TY
10%
C0402
10V
2.2UF
X 6S
CHIP
0402LF
2.2
1%
1/16W
C0402
10V
2.2UF
10%
X 6S
25V
10%
0.1UF
X 7R
25V
10%
C0402
1UF
X 6S
20%
16V
22UF
X 6S
C0805
1/16W
5%0
0402LFCHIP
0.22UH/33A
IND
SMLF
150NH
IND
SMLF
C0805
X 6S
20%
22UF
4V
C0805
X 6S
20%
22UF
4V
20%
16V
X 6S
22UF
C0805
20%
16V
22UF
X 6S
C0805
0402
16V
0.22UF
10%
X 7R
16V
22UF
C0805
20%
X 6S
IC
IS L99390FRZ-TR5935
SMLF
PVDDCR_SOC_P1 VR PHASE 3
2
1
PC353
2
1 PC355_3
2
1 PC354_3
21
PR216
2
1 PC348_3
2
1
PR213
2
1 PC346
2
1 PC195
2
1
PR511
2
1 PC345_9
1
30
25_29
3
36
10_19
39
34
4
32
40
7_9-20_24
5
37
38
41
6
35
31
33
2
PU32
PC353_3
2
1 PC352_3
2
1 PC351_3
4
32
1
PL38
2
1 PC350_3
21
PR215
2
1 PC349_3
2
1 PC347_SOP1_3
21
PR214
PL34
21
PGND2
GL2
GL1
DNC
EN
PGND3
VOS
VIN2
PGND1
SW
LSET
IOUT
TOUT_FLT
PVCC
PHASE
VIN1
BOOT
AGND
VCC
REFIN
PWM
1 4
321 2
1
SHEETDATE
23
7 3 2 16 5 4
E
A
B
C
E
D
C
B
A
7 6 5 4
D
DEPARTMENT
SIZE
PROJECT DOCUMENT NUMBER REV
REVIEWER
DESIGNER
OUT
IN
BI
OUT
IN
C



IRM REV1.09
DEFAULT POWER-ON VID=1.1V
DC & AC=+/-80MV
OCP=168A (EDC*1.2)
MAX LOAD STEP=44A
MAX LOAD RELEASE=37A
IRM REV1.09
SVI3 ADDRESS=PORT1 (0X2)
EFFICIENCY > 90% @TDC
WORK FREQUENCY=600KHZ
EDC=140A
SVI3 ADDRESS=PORT1 (0X1)
PVDDIO_P1 SPECFICATION
VID=0.9-1.2V
NOTE: 0 OHM CHECK
PR12,PR533 = EMPTY
PR231 = CS21002FB06
PR230 = CS25362FB02
PU34 = TBD/XDPE192C3B
2ND SOURCE:INFENEON BOM
PR245,PR246 = CS01002FB07
PU34 = TBD/RAA229620GNP#HA0
MAIN SOURCE:RENESAS BOM
2022/5/14 MODIFY
BOM NOTE
INFINEON 0X4C /2K
TRACE SPACING = 5MIL
TRACE WIDTH = 10MIL
DIFFERENTIAL PAIR
MPS
VR
RENESAS 0X74
DIFFERENTIAL PAIR
TRACE WIDTH = 10MIL
TRACE SPACING = 5MIL
TDC=120A
LOAD-LINE=0.4MOHM
EDC=230A
OCP=276A (EDC*1.2)
MAX LOAD STEP=200A
TDC=175A
MAX AC=VID+200MV
DC=+/-20MV
VID=0.55-1.5V
EFFICIENCY > 90% @TDC
WORK FREQUENCY=600KHZ
MIN AC=VID-EDC*LL-110MV
MAX LOAD RELEASE=200A
DEFAULT POWER-ON VID=0.9V
PVDDCR_CPU1_P1 SPECFICATION
20220413:
PC367,PC368 = CH11006JB00
PR533,PR12=EMPTY
PR231 = CS00002JB13
PR244 = CS34222FB06
PR251 = CS37502FB05
PR603 = CS24992FB07
PC367,PC368 = CH31004KB17
PC364 = CH21006JB10
PC358,PC361,PR230,PC357=EMPTY
PU34 = TBD/MP2857GQKT-001B-Z
3RD SOURCE:MPS BOM
PC357 = CH3104J1B00
PC358,PC361 = CH12206KB14
PC366 = CH5103KEB01
PR244 = CS22002FB07
PC366=CH5103KEB01
PR245 IS CHANGED FROM 10 TO 0 OHM
PR246 IS CHANGED FROM 10 TO 0 OHM
0X4C /42.2K
1/9.53K
CONFIGADDRESS(7-BIT)
PMBUS ADDRESS AND CONFIG
Thu Aug 24 14:09:27 2023<NAME_2>
<NAME_1>
MB FABCGTI V02
217 OF 365
I6
P V DDIO _P 1
P 3V 3_A UX
P V DD18_S 5_P 1
P 5V _A UX
P 3V 3_A UX
P V DD18_S 5_P 1
P 12V _A UX
P 3V 3_A UX
P 3V 3_A UX
P V DD18_S 5_P 1
P V DDCR_CP U1_P 1
219P V DDCR_CP U1_P 1_P W M4
82
81
81
54
54224
54
54
222 223
218 219 220 222 223
218 219 220
81
82
78
151
151
8382
54
54
54
218
220
222
220
222
218
223
223
223
223
222
222
220
220
219
219
219
218
218
1/16WCHIP
CHIP
5%
1/16W
0402LF
1/16W
1K
0402LF
1000P F
CHIP
X 7R
0402
0402LF
50V
33
1/16W
1/16W
5%
0402LF5%
5%
0
FM_P V DDCR_CP U1_P 1_E N
P W RG D_P V DDCR_CP U1_P 1
10P F
1%
1/16W
1K0
E MP TY E MP TY
CHIP 1/16W
0402LF5%0
1/16W
1K
E MP TY
5%
1%
1000P F
1%
10P F
10P F
50V
E MP TY
5%
E MP TYCHIP
1/16W
0402LF
1/16W
3300P F
1/16W 5% 0402LF
33 0402LF
CHIP
CHIP 1/16W
5% 0402LF33
0402LF
50V
1/16W
0402LF
0 5% 1/16W
0 5%
CHIP
X 7R
1/16W
50V
CHIP
1000P F
5%
X 7R
1000P F
50V
0402LF
0402
P W RG D_P V DDIO _P 1
5%
0
X 7R
X 7R5%
0402
0402X 7R50V
1/16W
1UF
P V DDCR_CP U1_P 1_RE S E T_N_R
0402LF
1000P F
1/16WCHIP
0402LF CHIP
1%
1K
V S E NS E _V S S _S E NS E _B _P 1
V S E NS E _V S S _S E NS E _C_P 1
V S E NS E _P V DDIO _P 1_DP
P V DDIO _P 1_E N_G
V S E NS E _P V DDCR_CP U1_P 1_DP
P V DDCR_CP U1_P 1_V INS E N
P V DDIO _P 1_TE MP 1
P V DDCR_CP U1_P 1_V CCS
P V DDCR_CP U1_P 1_TE MP 0
IC
B S S 138K
CHIP
1/16W
1%
0402LF
10K
1%
CHIP
1%
9.53K
1/16W
0402LF
IC
P JA 3415A E
0402LF
1K
1%
CHIP
1/16W
49.9
1% 0402LF
CHIP
1/16W
1% 0402LF
49.9
1%
CHIP
49.9 1/16W
5%
0402
5%
0402
50V
5%
50V
1%
49.9
CHIP
E MP TY
0402LF
1%
0402LF
E MP TY
1/16W
0402LF
1%
1/16W
25V
10%
X 7R
0402
0.1UF
0 5% 0402LF
CHIP
1/16W
1% 0402LF1K E MP TY50V
0402
0402LF
4.99K
1%
E MP TY
1/16W
X 7R
10%
0.1UF
25V
0402
X 7R6.3V
5%CHIP 1/16W 0
1/16W0402LF CHIP1K
X 7R
10%
0402
3300P F
50V
0402LF
1%
50V
X 7R
10%
470P F
0402
X 7R
10%
470P F
50V
0CHIP 5%
0402LF
E MP TY1000P F 50V
0402
X 7R
10%
0.1UF
25V
0402
10%
0.1UF
25V
X 7R
0402
X 6S
10%
16V
C0402
1UF 0402LF
1 1% CHIP
1/16W
CHIP 1/16W
1K
0
0 5%
0402
CHIP 1/16W
0402LF5%
1/16W
1%
EMPTY
P V DDIO _P 1_E N_R
10K
P V DDIO _P 1_E N
5% 0402LF
5%
0402LF
0 5%
1/16W
CHIP
CHIP
0402
1000P F
0402LF
10%
0 5%
1/16W
0402
CHIP
1K
0
V S E NS E _P V DDCR_CP U1_P 1_V S E N0
0402
V S E NS E _P V DDIO _P 1_V S E N1
1/16W
10%
5%
0402
0402LF
0402LF
C0402
X 6S
20%
6.3V
10UF
CHIP
0402LF
P V DDCR_CP U1_P 1_O CP _N
40.2K
50V
PVDDCR_CPU1_P1/PVDDIO_P1 VR CONTROLLER
CHIP 1/16W
P V DDCR_CP U1_P 1_RE S E T_N
0402LF1%100
1%
0402LF
CHIP
S MB _S CM_2_R1_S CL
CHIP
S MB _S CM_2_R1_S DA
P V DDCR_CP U1_P 1_S MB _A LE RT
E MP TY
1/16W
1K
S V ID_P V DDCR_CP U1_P 1_S V TI
1%49.9
1/16WCHIP
0402LF
S V ID_P V DDCR_CP U1_P 1_S V C_R
S V ID_P V DDCR_CP U1_P 1_S V D_R
S V ID_P V DDCR_CP U1_P 1_S V TO
RA A 229620G NP #HA 0IC
SMLF
P V DDCR_CP U1_P 1_IMO N1
P V DDCR_CP U1_P 1_V CC
S V ID_P V DDCR_CP U1_P 1_S V TI_R
S MB _CLK _P V DDCR_CP U1_P 1_R
SVID _PVD D C R _C PU 1_P1_SVC _R 1
P V DDCR_CP U1_P 1_IMO N6
S V ID_P V DDCR_CP U1_P 1_S V TO _R
NC_P V DDCR_CP U1_P 1_IMO N7
NC_P V DDCR_CP U1_P 1_IMO N8
P W RG D_P V DDIO _P 1_R
SVID _PVD D C R _C PU 1_P1_SVD _R 1
P V DDCR_CP U1_P 1_S MB _A LE RT_R
P V DDCR_CP U1_P 1_E N_R
S MB _DIO _P V DDCR_CP U1_P 1_R
NC_P V DDCR_CP U1_P 1_P W M8
NC_P V DDCR_CP U1_P 1_P W M7
P V DDIO _P 1_P W M2
P W RG D_P V DDCR_CP U1_P 1_R
P V DDCR_CP U1_P 1_P W M6
P V DDCR_CP U1_P 1_V MO N
P V DDIO _P 1_IMO N2
P V DDCR_CP U1_P 1_P W M1
P V DDIO _P 1_P W M4
P V DDIO _P 1_IMO N4
P V DDIO _P 1_P W M3
P V DDIO _P 1_IMO N3
P V DDCR_CP U1_P 1_O CP _N_R
P V DDCR_CP U1_P 1_E N1_A DDR_CFG
P V DDIO _P 1_P W M1
P V DDIO _P 1_IMO N1
P V DDCR_CP U1_P 1_P W M5
P V DDCR_CP U1_P 1_IMO N5
P V DDCR_CP U1_P 1_IMO N4
P V DDCR_CP U1_P 1_P W M3
P V DDCR_CP U1_P 1_IMO N3
P V DDCR_CP U1_P 1_P W M2
P V DDCR_CP U1_P 1_IMO N2
R6088
PR8012
PR8011
21C5006
21
C5020
21
C5022
21
PR12
21PR253
2
1
PC365
2
1
PC366
2
1 PC29
2
1 PC93
21C836021R8233
21R8234
21R8235
21C8359
21R8248
21
PR239
21
R8238
21R8249
21R8250
2
1
PC358
21
PR245
PR533
2
1 PC367
2
1 PC368
21
R8252
21
PR246
2
1
PC361
21R8247
21
R240
21
R8241
21
PC363
2
1
PC364
PR603
21C836221R8242
21R8243
21
PR251
2
1 PC357
2
1
R8225
2
1
R8222
2
1
R8220
2
1
PR218
21
PR228
2
1 C310
2
1 C309
2
1 C308
2
1
R8219
2
1
PR217
21
PR226
21
PR227
21
PR460
2
1
PR232
G
PQ12
2
1 PR244
21PR230
2
1
PR231
G
PQ16
2
1 C8356
21
R8224
SD
S D
40
25
45
46
19
48
47
TH
43
44
23
24
21
22
39
26
18
12
11
10
9
8
7
6
5
4
3
2
1
13
14
20
16
41
15
42
17
27
28
29
30
31
32
33
34
35
36
37
38
PU34
S
G
D
G
CS10
PWM10
CS9
PWM9
CS8
PWM8
CS7
PWM7
CS0
PWM0
TEMP1
EN1||ADDR_CFG
TH_GND
OCP_L
CS2
PWM2
CS3
PWM3
PWM11
CS1
RGND1
VSEN1
VDDIO
TEMP0
VINSEN
VMON||IINSEN
VCCS
PWM6
PG0
PWM1
VSEN0
PWM5
PWM4
PMSDA
RGND0
EN0
nPMALERT
SVD
PG1
CS4
CS5
RESET_L
SVTO
CS6
SVC
PMSCL
SVTI
VCC
CS11
SD
21
21
2
1
1
SHEETDATE
23
7 3 2 16 5 4
E
A
B
C
E
D
C
B
A
7 6 5 4
D
DEPARTMENT
SIZE
PROJECT DOCUMENT NUMBER REV
REVIEWER
DESIGNER
OUT
IN
OUT
IN
BI
OUT
IN
IN
IN
OUT
IN
OUT
IN
IN
IN IN
OUT
OUT
IN
OUT
IN
OUT
IN
OUT
IN
OUT
IN
OUT
IN
OUT
OUT
IN
OUT
IN
IN
OUT
IN
IN
IN
C



MAIN SOURCE:RENESAS BOM
PR272,PR266,PR267,PR259,PR258,PR428 = CS00002JB13
PC374_1,PC373_2,PC404_3,PC403_4,PC422_5,PC136_6 = EMPTY
3RD SOURCE:MPS BOM
PR341,PR258,PR259,PR266,PR267,PR272,PR428 = CS00002JB13
PU35,PU5,PU37,PU36,PU38,PU33 = AL087000A03/MP87000GMJTH-C11D-Z
PR340,PR260,PR261,PR268,PR269,PR273,PR429 = EMPTY
PC374_1,PC373_2,PC404_3,PC403_4,PC422_5,PC136_6 = EMPTY
PR273,PR268,PR269,PR260,PR261,PR429 = EMPTY
PR255,PR254,PR263,PR262,PR270,PR426 = CS00002JB13
PU35,PU5,PU37,PU36,PU38,PU33 = AL021590000/TDA21590
PU35,PU5,PU37,PU36,PU38,PU33 = AL099390004/ISL99390FRZ-TR5935
2022/5/14 MODIFY
ESR=10M OHM
IRIPPLE:5.08A
6.3*8
PVDDCR_CPU1_P1_PHASE2
PVDDCR_CPU1_P1_PHASE1
BOM NOTE
2ND SOURCE:INFENEON BOM
2ND=CC72703MD39
DCR=1-4,0.105M OHM
DCR=2-3,0.27M OHM
2ND=CV+15^0TZ01
11.0*7.5*12.5
PGL6303.151HLT
ISAT:70A@100C
7.3*4.3*1.9
ESR=4.5M OHM
MAIN=CH122KM8801
ISAT:70A@100C
PG2292.500HLT
3RD=CVA50^0MZ08
2ND=CVA50^0MZ07
DCR=0.09M OHM
6.0*6.1*7.0
PGL6303.151HLT
ISAT:70A@100C
11.0*7.5*12.5
DCR=1-4,0.105M OHM
DCR=2-3,0.27M OHM
2ND=CV+15^0TZ01
Thu Aug 24 14:09:07 2023<NAME_2>
<NAME_1>
MB FABCGTI V02
218 OF 365
S W _P 12V _A UX _P V DDCR_CP U1_P 1_FLT
P V DDCR_CP U1_P 1_P V CC
P 5V _A UX P 3V 3_A UX P V DDCR_CP U1_P 1_P V CC
P V DDCR_CP U1_P 1
P V DDCR_CP U1_P 1
P V DDCR_CP U1_P 1
S W _P 12V _A UX _P V DDCR_CP U1_P 1_FLT
P 12V _A UX
PVDDCR_CPU1_P1 VR PHASE 1&2
NC_P V DDCR_CP U1_P 1_G L2_2
NC_P V DDCR_CP U1_P 1_DNC2
S W _P V DDCR_CP U1_P 1_B O O T2_R
20%
0
217
217218219220222223
218219
220217
217
217218219220222223
218219
220217
217
217
220
218 219
218
270UF
20%
O S CO N
S MLF
16V
IND
50NH/86A
X 6S
O S CO N
S MLF
16V
20%
270UF
S W _P V DDCR_CP U1_P 1_B O O TR1
P V DDCR_CP U1_P 1_V CC1
0.22UF
16V
10%
S W _P V DDCR_CP U1_P 1_S W 1_RC
C0805
16V
22UF1UF
P V DDCR_CP U1_P 1_IMO N1
P V DDCR_CP U1_P 1_V CCS
P V DDCR_CP U1_P 1_TE MP 0
P V DDCR_CP U1_P 1_P W M1
P V DDCR_CP U1_P 1_V CCS
P V DDCR_CP U1_P 1_LS E T2
P V DDCR_CP U1_P 1_TE MP 0
P V DDCR_CP U1_P 1_P W M2
P V DDCR_CP U1_P 1_IMO N2
P V DDCR_CP U1_P 1_V CC2
S W _P V DDCR_CP U1_P 1_B O O TR2
P V DDCR_CP U1_P 1_V O S 2
NC_P V DDCR_CP U1_P 1_G L1_2
S W _P V DDCR_CP U1_P 1_S W 2_RC
NC_P V DDCR_CP U1_P 1_DNC1
S W _P V DDCR_CP U1_P 1_S W 1
NC_P V DDCR_CP U1_P 1_G L1_1
NC_P V DDCR_CP U1_P 1_G L2_1
P V DDCR_CP U1_P 1_V O S 1 IND_CP U1_P 1_CP L5
IND_CP U1_P 1_CP L1 IND_CP U1_P 1_CP L2
IND_CP U1_P 1_CP L1
S W _P V DDCR_CP U1_P 1_S W 2
0402
X 7R
0402LF
1%
25V
0.1UF
0402
10%
X 7R
C0402
10V
2.2UF
10%
X 6S
0402LF
1/16W
CHIP
1%
2.2
C0402
10V
2.2UF
10%
X 6S
8.87K
0402LF
1%
E MP TY
1/16W
C0402
10V
2.2UF
10%
X 6S
0402LF
1/16W
1%
2.2
C0402
10V
2.2UF
10%
X 6S
IC
25V
0.1UF
10%
0402LF
1.5
E MP TY
1/8W
1%
C0402
50V
560P F
E MP TY
10%
1/16W
CHIP5%0
0402LF
0.22UF
16V
10%
X 7R
0402
C0402
25V
10%
X 6S
20%
X 6S
C0805
0402LF
1.5
1%
E MP TY
1/8W
20%
16V
22UF
X 6S
20%
X 6S
C0805
16V
22UF
25V
0.1UF
10%
C0402
50V
560P F
10%
E MP TY
C0402
25V
1UF
X 6S
20%
16V
22UF
X 6S
C0805
0402
X 7R
16V
22UF
C0805
16V
X 6S
150NHIND
SMLF
1/16W
CHIP
5%
0402LF
0
S MLF
S P CA P
20%
220UF
4V
S P CA P
4V
20%
220UF
S MLF
S P CA P
4V
S MLF
20%
220UF
C0805
X 6S
20%
22UF
4V
C0805
X 6S
20%
22UF
4V
4V
S P CA P
20%
220UF
S MLF S MLF
4V
20%
220UF
S P CA P
150NH
0402
25V
0.1UF
10%
X 7R
25V
0402
X 7R
10%
C0805
X 6S
22UF
4V
C0805
X 6S
20%
22UF
4V
1/16W
CHIP
1%
1K
0402LF
1/16W
CHIP
5%
0402LF
0
1/16W
E MP TY
0402LF
5%
SMLF
P V DDCR_CP U1_P 1_LS E T1
IND
C0805
20%20%10%
CHIP
SMLF
SMLF
IS L99390FRZ-TR5935
25V
10%
E MP TY
0.1UF
8.87K
1/16W
1%
CHIP
1/16W
0402LF
5.6
CHIP
1%
S W _P V DDCR_CP U1_P 1_B O O T15.6
X 7R
0402
IS L99390FRZ-TR5935
S W _P V DDCR_CP U1_P 1_B O O T1_R
IC
1/16W
0402LF
S W _P V DDCR_CP U1_P 1_B O O T2
0402
X 7R
0.1UF
22UF
S MLF
PC390 PC393
1
30
25_29
3
36
10_19
39
34
4
32
40
7_9-20_24
5
37
38
41
6
35
31
33
2
PU35
PR341PR340
2
1
PC398_1
2
1
PC395_1
PC375
2
1
PC392
21
PL42
4
32
1
PL40
2
1 PC389
2
1
PC397_2
2
1
PC394_2
21 PR261
4
32
1
PL41
2
1
PC384_1
2
1
PC381_1
2
1 PC383
2
1
PC379_1
2
1
PC377_1
2
1 PC201
PR258
2
1
PC375_1
2
1
PC385_2
2
1
PR512
2
1
PC380_2
2
1
PC378_2
2
1 PC386
21 PR260
2
1 PC202
2
1
PR513
2
1
PC376_2
1
30
25_29
3
36
10_19
39
34
4
32
40
7_9-20_24
5
37
38
41
6
35
31
33
2
PU5
2
1 PC371_C1P1_1
2
1
PR256
2
1
PR255
2
1 PC372_C1P1_2
2
1 PC370
2
1 PC374_1
2
1
PR254
PR342
2
1 PC391
2
1 PC388
2
1 PC387
2
1 PC106
2
1
PC382_2
PR259
2
1 PC369
2
1
PR257
2
1 PC373_2
PGND2
GL2
GL1
DNC
EN
PGND3
VOS
VIN2
PGND1
SW
LSET
IOUT
TOUT_FLT
PVCC
PHASE
VIN1
BOOT
AGND
VCC
REFIN
PWM
1 2
1 4
32
1 4
32
PGND2
GL2
GL1
DNC
EN
PGND3
VOS
VIN2
PGND1
SW
LSET
IOUT
TOUT_FLT
PVCC
PHASE
VIN1
BOOT
AGND
VCC
REFIN
PWM
2
1
2
1
2
1
1
SHEETDATE
23
7 3 2 16 5 4
E
A
B
C
E
D
C
B
A
7 6 5 4
D
DEPARTMENT
SIZE
PROJECT DOCUMENT NUMBER REV
REVIEWER
DESIGNER
BI
OUT
IN
BI
OUT
BI
IN
BI
OUT
IN
OUT
IN
C



PVDDCR_CPU1_P1_PHASE4
PVDDCR_CPU1_P1_PHASE3
DCR=1-4,0.105M OHM
DCR=2-3,0.27M OHM
DCR=1-4,0.105M OHM
11.0*7.5*12.5
ISAT:70A@100C
PGL6303.151HLT
ISAT:70A@100C
PGL6303.151HLT
DCR=2-3,0.27M OHM
11.0*7.5*12.5
Thu Aug 24 14:09:07 2023<NAME_2>
<NAME_1>
MB FABCGTI V02
219 OF 365
P V DDCR_CP U1_P 1_P V CC
P V DDCR_CP U1_P 1_P V CC
S W _P 12V _A UX _P V DDCR_CP U1_P 1_FLT
S W _P 12V _A UX _P V DDCR_CP U1_P 1_FLT
P V DDCR_CP U1_P 1
P V DDCR_CP U1_P 1
217
218
219
220
217
217
217
218
219
220
217
217218219220222223
217
217218219220222223
219
218 219
0402
CHIP
5.6
C0805
0402LF
C0402
5.6
S W _P V DDCR_CP U1_P 1_B O O T4_RS W _P V DDCR_CP U1_P 1_B O O T4
CHIP
1%
0402LF
1/16W
S W _P V DDCR_CP U1_P 1_B O O T3_RS W _P V DDCR_CP U1_P 1_B O O T3
1% 1/16W
X 6S
C0402
0402LF
E MP TY
S W _P V DDCR_CP U1_P 1_S W 3_RC
C0402
E MP TY
10%
50V
560P F
S W _P V DDCR_CP U1_P 1_B O O TR3
S W _P V DDCR_CP U1_P 1_S W 3
P V DDCR_CP U1_P 1_V O S 3
NC_P V DDCR_CP U1_P 1_G L1_3
NC_P V DDCR_CP U1_P 1_G L2_3
PVDDCR_CPU1_P1 VR PHASE 3&4
10V
P V DDCR_CP U1_P 1_P W M3
10%
25V
1UF
10%
X 6S
25V
0.1UF
S W _P V DDCR_CP U1_P 1_B O O TR4
S W _P V DDCR_CP U1_P 1_S W 4
P V DDCR_CP U1_P 1_V O S 4
NC_P V DDCR_CP U1_P 1_G L1_4
NC_P V DDCR_CP U1_P 1_G L2_4
0402
0402LF
1/16W
P V DDCR_CP U1_P 1_TE MP 0
P V DDCR_CP U1_P 1_IMO N4
P V DDCR_CP U1_P 1_P W M4
P V DDCR_CP U1_P 1_TE MP 0
P V DDCR_CP U1_P 1_LS E T4
P V DDCR_CP U1_P 1_V CCS
P V DDCR_CP U1_P 1_V CC4
NC_P V DDCR_CP U1_P 1_DNC4
P V DDCR_CP U1_P 1_IMO N3
P V DDCR_CP U1_P 1_V CCS
P V DDCR_CP U1_P 1_LS E T3
NC_P V DDCR_CP U1_P 1_DNC3
P V DDCR_CP U1_P 1_V CC3
S W _P V DDCR_CP U1_P 1_S W 4_RC
IND_CP U1_P 1_CP L3
IND_CP U1_P 1_CP L2 IND_CP U1_P 1_CP L3
0402
25V
0.1UF
10%
X 7R
1/16W
E MP TY
1%
8.87K
0402LF
C0402
10V
2.2UF
10%
X 6S
0402
25V
0.1UF
10%
X 7R
1/16W
CHIP
1%
2.2
0402LF
X 6S
C0402
2.2UF
10%
8.87K
1%
E MP TY
IS L99390FRZ-TR5935
IC
SMLF
25V
10%
X 7R
10V
2.2UF
10%
X 6S
0402LF
CHIP
1/16W
1%
2.2
C0402
10V
2.2UF
10%
X 6S
0.1UF
E MP TY
0402LF
1.5
1%
1/8W
C0402
50V
560P F
10%
E MP TY
1/16W
CHIP5%0
0402LF
16V
0402
10%
X 7R
0.22UF
25V
1UF
10% 20%
16V
22UF
X 6S
C0805
1.5
1%
1/8W
20%
16V
22UF
C0805
X 6S
20%
16V
22UF
X 6S
C0805
5%0
1/16W
CHIP
0402LF
150NHIND
SMLF
C0402
22UF
16V
X 6S
20%
10%
0.22UF
X 7R
16V
22UF
X 6S
C0805
20%
16V
22UF
C0805
16V
20%
X 6S
IND 150NH
SMLF
C0805
X 6S
20%
22UF
4V
C0805
X 6S
20%
22UF
4V
C0805
X 6S
20%
22UF
4V
C0805
X 6S
20%
22UF
4V
IS L99390FRZ-TR5935
IC
SMLF
X 7R
0402
1
30
25_29
3
36
10_19
39
34
4
32
40
7_9-20_24
5
37
38
41
6
35
31
33
2
PU37
2
1
PC419_3
2
1
PC420_4
2
1
PC418_4
2
1
PC417_3
4
32
1
PL44
2
1
PC416_3
2
1
PC412_3
2
1 PC414
2
1
PC406_3
2
1 PC206
PR267
21 PR269
2
1
PC415_4
2
1
PC411_4
2
1
PR516
2
1
PC407_4
PR266
2
1
PR515
2
1 PC408_3
2
1 PC402_C1P1_3
2
1
PR265
2
1 PC400
2
1 PC405_4
1
30
25_29
3
36
10_19
39
34
4
32
40
7_9-20_24
5
37
38
41
6
35
31
33
2
PU36
2
1
PR263
2
1 PC401_C1P1_4
2
1
PR264
2
1 PC404_3
2
1 PC399
2
1
PR262
2
1
PC410_3
4
32
1
PL43
2
1
PC409_4
2
1 PC413
21 PR268
2
1 PC205
2
1 PC403_4
PGND2
GL2
GL1
DNC
EN
PGND3
VOS
VIN2
PGND1
SW
LSET
IOUT
TOUT_FLT
PVCC
PHASE
VIN1
BOOT
AGND
VCC
REFIN
PWM
1 4
32
1 4
32
PGND2
GL2
GL1
DNC
EN
PGND3
VOS
VIN2
PGND1
SW
LSET
IOUT
TOUT_FLT
PVCC
PHASE
VIN1
BOOT
AGND
VCC
REFIN
PWM
1
SHEETDATE
23
7 3 2 16 5 4
E
A
B
C
E
D
C
B
A
7 6 5 4
D
DEPARTMENT
SIZE
PROJECT DOCUMENT NUMBER REV
REVIEWER
DESIGNER
IN
OUT
BIBI
IN
BI
OUT
IN
OUT
IN
OUT
C



PVDDCR_CPU1_P1_PHASE5
2ND=CV+15^0TZ01
DCR=1-4,0.105M OHM
11.0*7.5*12.5
ISAT:70A@100C
PGL6303.151HLT
DCR=2-3,0.27M OHM
2ND=CV+15^0TZ01
11.0*7.5*12.5
ISAT:70A@100C
PGL6303.151HLT
DCR=2-3,0.27M OHM
DCR=1-4,0.105M OHM
PVDDCR_CPU1_P1_PHASE6
2ND=CV+12^0EZ04
DCR=0.17M OHM
6.5*6.5*10.0
ISAT:60A@100C
PGL6312.121AHLT
Thu Aug 24 14:09:07 2023<NAME_2>
<NAME_1>
MB FABCGTI V02
220 OF 365
P V DDCR_CP U1_P 1_P V CC
P V DDCR_CP U1_P 1_P V CC
S W _P 12V _A UX _P V DDCR_CP U1_P 1_FLT
S W _P 12V _A UX _P V DDCR_CP U1_P 1_FLT
P V DDCR_CP U1_P 1
P V DDCR_CP U1_P 1
217218219220222223
218
219
220
217
218
219
220
217
217
217
217
217
217218219220222223
220
220 218
S W _P V DDCR_CP U1_P 1_B O O T6
S W _P V DDCR_CP U1_P 1_B O O TR6
S W _P V DDCR_CP U1_P 1_S W 6
NC_P V DDCR_CP U1_P 1_G L1_6
NC_P V DDCR_CP U1_P 1_G L2_6
5.6
S W _P V DDCR_CP U1_P 1_B O O T5_R
C0402
SMLF
5.6S W _P V DDCR_CP U1_P 1_B O O T5
0402LF
CHIP
1%
1/16W
S W _P V DDCR_CP U1_P 1_B O O T6_R
CHIP
0402LF
1/16W
1%
IND_CP U1_P 1_CP L0
SMLF
560P F
120NH/69A
IND
S MLF
0402
0402
X 7R
0.1UF
10%
C0805
X 6S
20%
16V
22UF
S W _P V DDCR_CP U1_P 1_B O O TR5
S W _P V DDCR_CP U1_P 1_S W 5
NC_P V DDCR_CP U1_P 1_G L2_5
P V DDCR_CP U1_P 1_V CCS
P V DDCR_CP U1_P 1_TE MP 0
P V DDCR_CP U1_P 1_TE MP 0
P V DDCR_CP U1_P 1_P W M5
P V DDCR_CP U1_P 1_IMO N6
P V DDCR_CP U1_P 1_LS E T6
P V DDCR_CP U1_P 1_P W M6
NC_P V DDCR_CP U1_P 1_DNC6
P V DDCR_CP U1_P 1_V CC6
P V DDCR_CP U1_P 1_IMO N5
P V DDCR_CP U1_P 1_V CCS
P V DDCR_CP U1_P 1_LS E T5
P V DDCR_CP U1_P 1_V CC5
NC_P V DDCR_CP U1_P 1_DNC5
NC_P V DDCR_CP U1_P 1_G L1_5
S W _P V DDCR_CP U1_P 1_S W 6_RC
P V DDCR_CP U1_P 1_V O S 6 IND_CP U1_P 1_CP L6
S W _P V DDCR_CP U1_P 1_S W 5_RC
IND_CP U1_P 1_CP L6 IND_CP U1_P 1_CP L5
0402
25V
0.1UF
10%
X 7R
0402LF
8.87K
1%
E MP TY
1/16W
0402
25V
0.1UF
10%
X 7R
C0402
10V
2.2UF
10%
X 6S
1/16W
CHIP
1%
2.2
0402LF
0402LF
8.87K
1%
E MP TY
1/16W
IC
SMLF
C0402
10V
2.2UF
10%
X 6S
C0402
10V
2.2UF
10%
X 6S
1/16W
CHIP
1%
2.2
0402LF C0402
10V
2.2UF
10%
X 6S
1.5
1%
1/8W
E MP TY
0402LF
E MP TY
10%
50V
C0402
1/16W
CHIP5%
0402LF
0
25V
C0402
25V
10%
X 6S
1UF
20%
16V
22UF
X 6S
C0805
0402LF
1.5
1%
E MP TY
1/8W
20%
16V
22UF
X 6S
C0805
0402
16V
0.22UF
10%
X 7R
20%
16V
22UF
X 6S
C0805
1/16W
CHIP0
0402LF
5%
150NHIND
C0402
10%
X 6S
20%
16V
X 6S
C0805
0.22UF
10%
X 7R
0402
22UF
20%
16V
22UF
X 6S
C0805
150NHIND
SMLF
C0805
X 6S
20%
22UF
4V
C0805
X 6S
20%
22UF
4V
C0805
4V
22UF
20%
X 6S
C0805
X 6S
20%
22UF
4V
IS L99390FRZ-TR5935
PVDDCR_CPU1_P1 VR PHASE 5&6
IS L99390FRZ-TR5935
X 7R
25V25V
10%
IC
0.1UF 1UF
10%
P V DDCR_CP U1_P 1_V O S 5
E MP TY
50V
560P F
16V
1
30
25_29
3
36
10_19
39
34
4
32
40
7_9-20_24
5
37
38
41
6
35
31
33
2
PU38
2
1
PC431_5
2
1
PC430_5
2
1
PC149_6
2
1
PC148_6
4
32
1
PL45
2
1
PC429_5
2
1 PC428
2
1
PC426_5
2
1
PC424_5
2
1
PC425_5
2
1 PC207
PR272
4
32
1
PL69
21 PR273
2
1
PC147_6
2
1 PC146
2
1
PC145_6
2
1
PR517
2
1
PC144_6
2
1
PC141_6
2 1
PL39
21 PR429
2
1 PC208
2
1
PR518
2
1
PR271
2
1 PC421
2
1 PC139_C1P1_6
1
30
25_29
3
36
10_19
39
34
4
32
40
7_9-20_24
5
37
38
41
6
35
31
33
2
PU33
2
1
PR270
2
1
PR427
2
1 PC138
2
1 PC422_5
2
1
PR426
2
1 PC136_6
2
1
PC427_5
2
1
PC140_6
PR428
2
1 PC423_C1P1_5
PGND2
GL2
GL1
DNC
EN
PGND3
VOS
VIN2
PGND1
SW
LSET
IOUT
TOUT_FLT
PVCC
PHASE
VIN1
BOOT
AGND
VCC
REFIN
PWM
1 4
32
1 4
3212
PGND2
GL2
GL1
DNC
EN
PGND3
VOS
VIN2
PGND1
SW
LSET
IOUT
TOUT_FLT
PVCC
PHASE
VIN1
BOOT
AGND
VCC
REFIN
PWM
1
SHEETDATE
23
7 3 2 16 5 4
E
A
B
C
E
D
C
B
A
7 6 5 4
D
DEPARTMENT
SIZE
PROJECT DOCUMENT NUMBER REV
REVIEWER
DESIGNER
IN
OUT
BI
IN
BI
BI
OUT
OUT
IN
IN
OUT
C



Thu Aug 24 10:15:24 2023<NAME_2>
<NAME_1>
MB FABCGTI V02
221 OF 365Blank
1
SHEETDATE
23
7 3 2 16 5 4
E
A
B
C
E
D
C
B
A
7 6 5 4
D
DEPARTMENT
SIZE
PROJECT DOCUMENT NUMBER REV
REVIEWER
DESIGNER
C



PU39,PU40,PU52,PU53=AL087000A03/MP87000GMJTH-C11D-Z
BOM NOTE
MAIN SOURCE:RENESAS BOM
PU39,PU40,PU52,PU53 = AL099390004/ISL99390FRZ-TR5935
2ND SOURCE:INFENEON BOM
PU39,PU40,PU52,PU53 = AL021590000/TDA21590
PR372,PR373,PR278,PR279 = CS00002JB13
PR275,PR274,PR369,PR368 = CS00002JB13
PR280,PR281,PR374,PR375 = EMPTY
PC435_7,PC436_8,PC620_9,PC621_10 = EMPTY
PR278,PR279,PR372,PR373=CS00002JB13
PC435_7,PC436_8,PC620_9,PC621_10=EMPTY
DCR=1-4,0.105M OHM
DCR=1-4,0.105M OHM
PGL6303.151HLT
DCR=2-3,0.27M OHM
2ND=CV+15^0TZ01
ISAT:70A@100C
11.0*7.5*12.5
6.3*8
IRIPPLE:5.08A
7.3*4.3*1.9
ESR=4.5M OHM
2ND=CH747LM8822
11.0*7.5*12.5
ISAT:70A@100C
PGL6303.151HLT
DCR=2-3,0.27M OHM
2ND=CV+15^0TZ01
PVDDIO_P1_PHASE2
3RD SOURCE:MPS BOM
PR280,PR281,PR374,PR375=EMPTY
2022/5/14 MODIFY
PVDDIO_P1_PHASE1
2ND=CC72703MD39
ESR=10M OHM
3RD=CVA50^0MZ08
2ND=CVA50^0MZ07
DCR=0.09M OHM
ISAT:70A@100C
PG2292.500HLT
6.0*6.1*7.0
Thu Aug 24 14:09:28 2023<NAME_2>
<NAME_1>
MB FABCGTI V02
222 OF 365
S W _P 12V _A UX _P V DDIO _P 1_FLT
P 12V _A UX
P V DDIO _P 1
P V DDIO _P 1
P V DDIO _P 1
S W _P 12V _A UX _P V DDIO _P 1_FLT
P V DDCR_CP U1_P 1_P V CC
P V DDCR_CP U1_P 1_P V CC
PVDDIO_P1 VR PHASE 1&2
222
222223
222
223
217
217
217
217218219220222223
217
217218219220222223
222
223
217
217
X 6S
C0402 C0805 C0805
X 6S X 6S
20%
16V
22UF
20%
20%
16V
22UF
C0805
270UF
IND
20%
22UF
16V
X 6S
22UF
C0805
20%
16V
X 6S
10%
25V
1UF
10%
X 7R
0.1UF
25V
0402
16V
S MLF
O S CO N
10%
0.22UF
10%
0402
S W _P V DDIO _P 1_B O O T1
SMLF
IC
SMLF
IND 150NH
0402LF
1K
1%
CHIP
1/16W
4V
22UF
20%
X 6S
C0805
X 6S
20%
22UF
4V
C0805
X 7R
10%
100NF
50V
C0402
0.1UF
25V
X 7R
0402
50NH/86A
S MLF
IND
SMLF
150NH
X 7R
16V
0402
E MP TY
20%
470UF
2.5V
S MLF
S P CA P
20%
470UF
S MLF
2.5V
S P CA P
20%
470UF
2.5V
S MLF
4V
22UF
20%
X 6S
C0805
4V
22UF
20%
X 6S
C0805
X 6S
20%
16V
22UF
C0805
0402LF
CHIP
1/16W
0 5%
20%
16V
22UF
C0805
X 6S
20%
16V
22UF
C0805
X 6S
X 7R
10%
0.22UF
16V
0402
0402LF
0 5%
CHIP
1/16W
E MP TY
SMLF
IC
X 6S
10%
2.2UF
10V
C04020402LF
2.2
1%
CHIP
1/16W
X 6S
10%
2.2UF
10V
C0402
0402LF
1/16W
E MP TY
1%
8.87K
1%
X 6S
10%
1UF
25V
C0402X 7R
10%
0.1UF
25V
C0402
E MP TY
10%
560P F
50V
1%
1.5
1/8W
E MP TY
0402LF
X 6S
10%
2.2UF
10V
C04020402LF
2.2
1%
CHIP
1/16W
X 6S
C0402
10V
2.2UF
1/16W
E MP TY
1%
8.87K
0402LF
10%
X 7R
0.1UF
25V
0402
25V
10%
X 7R
0402
S W _P V DDIO _P 1_B O O TR2
S W _P V DDIO _P 1_S W 2
IND_P V DDIO _P 1_CP L2
IND_P V DDIO _P 1_CP L2IND_P V DDIO _P 1_CP L3
P V DDIO _P 1_V O S 1
NC_P V DDIO _P 1_G L1_1
NC_P V DDIO _P 1_DNC1
P V DDIO _P 1_V CC1
NC_P V DDIO _P 1_G L1_2
NC_P V DDIO _P 1_G L2_2
P V DDIO _P 1_V O S 2
P V DDIO _P 1_TE MP 1
P V DDIO _P 1_LS E T2
P V DDIO _P 1_IMO N2
P V DDIO _P 1_P W M2
P V DDCR_CP U1_P 1_V CCS
P V DDIO _P 1_IMO N1
P V DDCR_CP U1_P 1_V CCS
P V DDIO _P 1_TE MP 1
P V DDIO _P 1_P W M1
S W _P V DDIO _P 1_S W 1
S W _P V DDIO _P 1_B O O TR1
IS L99390FRZ-TR5935
P V DDIO _P 1_LS E T1
NC_P V DDIO _P 1_G L2_1
IS L99390FRZ-TR5935
560P F
50V
10%
C0402
S W _P V DDIO _P 1_S W 1_RC
1.5
1/8W
E MP TY
0402LF
NC_P V DDIO _P 1_DNC2
P V DDIO _P 1_V CC210%
S W _P V DDIO _P 1_S W 2_RC
0.1UF
0402LF1%
CHIP
1/16WS W _P V DDIO _P 1_B O O T2
S W _P V DDIO _P 1_B O O T2_R5.6
0402LF1%
CHIP
1/16W S W _P V DDIO _P 1_B O O T1_R5.6
PC7001 PC454
1
30
25_29
3
36
10_19
39
34
4
32
40
7_9-20_24
5
37
38
41
6
35
31
33
2
PU40
4
32
1
PL48
PR378
2
1
PC459_1
2
1
PC456_1
2
1
PC451
PC438
21
PL49
4
32
1
PL47
2
1 PC448_1
2
1
PC444_1
2
1 PC447
2
1
PC455
2
1
PC452
2
1
PC450
2
1
PC460_2
2
1
PC458_2
2
1
PC449_2
PR280
2
1
PC446_2
2
1
PC443_2
2
1 PC445
PR281
2
1
PC442_1
21
PR279
2
1
PC440_1
2
1
PC438_1
2
1 PC174
1
30
25_29
3
36
10_19
39
34
4
32
40
7_9-20_24
5
37
38
41
6
35
31
33
2
PU39
2
1 PC437_IOP1_1
2
1
PR277
2
1 PC433
2
1
PR275
2
1
PR488
2
1
PC441_2
PR278
2
1 PC439_2
2
1 PC175
2
1
PR489
2
1 PC434_IOP1_2
2
1
PR276
2
1 PC432
2
1
PR274
2
1 PC435_7
2
1 PC436_8
PGND2
GL2
GL1
DNC
EN
PGND3
VOS
VIN2
PGND1
SW
LSET
IOUT
TOUT_FLT
PVCC
PHASE
VIN1
BOOT
AGND
VCC
REFIN
PWM
1 4
32
1 2
1 4
32
PGND2
GL2
GL1
DNC
EN
PGND3
VOS
VIN2
PGND1
SW
LSET
IOUT
TOUT_FLT
PVCC
PHASE
VIN1
BOOT
AGND
VCC
REFIN
PWM
2
1
2
1
2
1
1
SHEETDATE
23
7 3 2 16 5 4
E
A
B
C
E
D
C
B
A
7 6 5 4
D
DEPARTMENT
SIZE
PROJECT DOCUMENT NUMBER REV
REVIEWER
DESIGNER
IN
OUT
IN
BI
BIBI
IN
OUT
OUT
IN
OUT
C



PVDDIO_P1_PHASE4
DCR=2-3,0.27M OHM
PGL6303.151HLT
11.0*7.5*12.5
ISAT:70A@100C
DCR=1-4,0.105M OHM
2ND=CV+15^0TZ01
PGL6303.151HLT
DCR=1-4,0.105M OHM
DCR=2-3,0.27M OHM
2ND=CV+15^0TZ01
11.0*7.5*12.5
ISAT:70A@100C
HCME656510Q-221QL
ISAT:30A@100C
2ND=CV+22Y0EZ01
DCR=0.17M OHM
6.5*6.5*10.0
PVDDIO_P1_PHASE3
Thu Aug 24 14:09:07 2023<NAME_2>
<NAME_1>
MB FABCGTI V02
223 OF 365
P V DDIO _P 1
S W _P 12V _A UX _P V DDIO _P 1_FLT
P V DDIO _P 1
S W _P 12V _A UX _P V DDIO _P 1_FLT
P V DDCR_CP U1_P 1_P V CC
P V DDCR_CP U1_P 1_P V CC
222223
223
217218219220222223
217
222
223
217
217
217218219220222223
217
222
223
217
217
25V
1UF
1%
5.6
C0402
S W _P V DDIO _P 1_S W 3_RC
S W _P V DDIO _P 1_B O O T3_R
S W _P V DDIO _P 1_B O O T3
0402LF
CHIP
1/16W
5.6 S W _P V DDIO _P 1_B O O T4_RS W _P V DDIO _P 1_B O O T4 1/16W
0402LF1%
CHIP
0402
PVDDIO_P1 VR PHASE 3&4
SMLF
IC
IS L99390FRZ-TR5935
C0805
X 6S
22UF
16V
20%
4V
22UF
20%
X 6S
C0805
4V
22UF
20%
X 6S
C0805
C0805
X 6S
22UF
16V
20%
X 7R
10%
16V
0402
SMLF
150NHIND
C0805
X 6S
22UF
16V
20%
C0805
X 6S
22UF
16V
20%
E MP TY
10%
560P F
50V
0402LF
1.5
1%
E MP TY
1/8W
CHIP
0402LF
0
5%
1/16W
4V
22UF
20%
X 6S
C0805
4V
22UF
20%
X 6S
C0805
C0805
X 6S
22UF
16V
20%
C0805
X 6S
22UF
16V
20%
X 6S
10%
C0402
10%
0.22UF
X 7R
16V
0402
IND
0.22UH/33ASMLF
SMLF
IND 150NH
0402LF
0
5% CHIP
1/16W
1/8W
E MP TY
1%
1.5
0402LF
10%
560P F
C0402
50V
E MP TY
X 6S
10%
1UF
25V
C0402X 7R
10%
0.1UF
25V
X 6S
10%
2.2UF
10V
C04020402LF
2.2
1%
CHIP
1/16W
X 6S
10%
2.2UF
10V
C0402
1/16W
E MP TY
1%
8.87K
0402LF
X 7R
10%
0.1UF
25V
0402
X 7R
10%
0.1UF
25V
0402
SMLF
IC
IS L99390FRZ-TR5935
X 6S
10%
2.2UF
10V
C04020402LF
2.2
1%
CHIP
1/16W
X 6S
10%
2.2UF
10V
C0402
1/16W
E MP TY
1%
8.87K
0402LF
X 7R
10%
0.1UF
25V
0402
IND_P V DDIO _P 1_CP L3IND_P V DDIO _P 1_CP L4
IND_P V DDIO _P 1_CP L4IND_P V DDIO _P 1_CP L0
S W _P V DDIO _P 1_S W 4_RC
S W _P V DDIO _P 1_B O O TR3
S W _P V DDIO _P 1_S W 4
S W _P V DDIO _P 1_S W 3
S W _P V DDIO _P 1_B O O TR4
NC_P V DDIO _P 1_G L1_3
NC_P V DDIO _P 1_G L2_3
P V DDIO _P 1_V O S 3
P V DDIO _P 1_V CC3
NC_P V DDIO _P 1_DNC3
P V DDCR_CP U1_P 1_V CCS
P V DDIO _P 1_LS E T3
P V DDIO _P 1_P W M3
P V DDIO _P 1_TE MP 1
P V DDIO _P 1_IMO N3
P V DDIO _P 1_V O S 4
NC_P V DDIO _P 1_G L2_4
NC_P V DDIO _P 1_G L1_4P V DDIO _P 1_LS E T4
P V DDIO _P 1_V CC4
NC_P V DDIO _P 1_DNC4
P V DDCR_CP U1_P 1_V CCS
P V DDIO _P 1_P W M4
P V DDIO _P 1_TE MP 1
P V DDIO _P 1_IMO N4
0.22UF
PL46
1
30
25_29
3
36
10_19
39
34
4
32
40
7_9-20_24
5
37
38
41
6
35
31
33
2
PU52
2
1
PC627_4
2
1
PC637_3
2
1 PC631
4
32
1
PL68
2
1
PC628_3
2
1
PC626_3
2
1 PC177
2
1
PC636_4
2
1 PC633_4
2
1
PC625_4
4
32
1
PL67
PR375
2
1
PR491
2
1 PC176
2
1
PC624_3
2
1 PC622_3
PR373
2
1 PC619_IOP1_3
2
1
PR371
2
1
PR369
2
1 PC620_9
2
1 PC623_4
PR372
2
1 PC618_IOP1_4
2
1
PR370
2
1 PC616
2
1
PR368
2
1
PC635_3
2
1 PC632_3
2
1
PR492
PR374
2
1
PC634_4
2
1
PC629_4
2
1 PC630
2
1 PC617
1
30
25_29
3
36
10_19
39
34
4
32
40
7_9-20_24
5
37
38
41
6
35
31
33
2
PU53
2
1 PC621_10
2 1
PGND2
GL2
GL1
DNC
EN
PGND3
VOS
VIN2
PGND1
SW
LSET
IOUT
TOUT_FLT
PVCC
PHASE
VIN1
BOOT
AGND
VCC
REFIN
PWM
1 4
32
12
1 4
32
PGND2
GL2
GL1
DNC
EN
PGND3
VOS
VIN2
PGND1
SW
LSET
IOUT
TOUT_FLT
PVCC
PHASE
VIN1
BOOT
AGND
VCC
REFIN
PWM
1
SHEETDATE
23
7 3 2 16 5 4
E
A
B
C
E
D
C
B
A
7 6 5 4
D
DEPARTMENT
SIZE
PROJECT DOCUMENT NUMBER REV
REVIEWER
DESIGNER
OUT
IN
BI
OUT
BI
BI
IN
OUT
IN
OUT
IN
C



WORK FREQUENCY=600KHZ
IRM REV1.09
MAX LOAD STEP=25A
MAX LOAD RELEASE=35A
EFFICIENCY > 90% @TDC
2022/5/14 MODIFY
PR6 = CS00002JB13
PR464 = CS32702FB03
PC643 = CH31004KB17
PC644=CH5103KEB01
PC8 = CH21006JB10
PR604 = CS24992FB07
PR388 = CS37502FB05
PR13,PR14,PR406,PR407,PR408,PR409 = EMPTY
PC639,PR376,PC638=EMPTY
PU54 = TBD/MP2856GUT-0021-Z
PR384 = CS01002FB07
PR408,PR409,PR415 = EMPTY
PR14,PR13,PR406,PR407 = EMPTY
PR6 = CS21002FB06
PR376 = CS25362FB02
PU54 = TBD/XDPE19283B
2ND SOURCE:INFENEON BOM
MAIN SOURCE:RENESAS BOM
PU54 = TBD/RAA229621GNP#HA0
BOM NOTE
PR464=CS23572FB05
PC644 = CH5103KEB01
PC643 = CH11006JB00
3RD SOURCE:MPS BOM
PC638 = CH3104J1B00
PC639 = CH12206KB14
20220413:
DIFFERENTIAL PAIR
EDC=80A
TDC=65A
DC & AC=1.045-1.155V
PVDD11_S3_P1 SPECFICATION
OUTPUT VOLTAGE=1.1V
OCP=96A (EDC*1.2)
VR
RENESAS
INFINEON
MPS
TRACE SPACING = 5MIL
20220422:
POP R8146
TRACE WIDTH = 10MIL
DE-POP R8146
20220413:
PR384 IS CHANGED FROM 10 TO 0 OHM
CONFIG/R
0/13.7K
0X4A /27K
/3.57K0X4A
0X75
ADDRESS(7-BIT)
PMBUS ADDRESS AND CONFIG
Thu Aug 24 14:09:28 2023<NAME_2>
<NAME_1>
MB FABCGTI V02
224 OF 365
P V DD18_S 5_P 1
P 3V 3_A UX
P 12V _A UX
P 5V _A UX
P 3V 3_A UX
P V DD18_S 5_P 1
P 3V 3_A UX
P V DD11_S 3_P 1
151
225
225
225
225
82
81
54
54217
225
81
225
81
8382
151
NC_P V DD11_S 3_P 1_IMO N8
NC_P V DD11_S 3_P 1_P W M8
P V DD11_S 3_P 1_TE MP 1
P V DD11_S 3_P 1_A DDR_CFG
P V DD11_S 3_P 1_O CP _N_R
NC_P V DD11_S 3_P 1_IMO N6
NC_P V DD11_S 3_P 1_P W M6
NC_P V DD11_S 3_P 1_IMO N5
NC_P V DD11_S 3_P 1_P W M5
P V DD11_S 3_P 1_P W M1
NC_P V DD11_S 3_P 1_IMO N7
P V DD11_S 3_P 1_V DDIO
P V DD11_S 3_P 1_V INS E N
P V DD11_S 3_P 1_V MO N
P V DD11_S 3_P 1_P W M2
P W RG D_P V DD11_S 3_P 1_R
NC_P V DD11_S 3_P 1_P W M7
V S E NS E _P V DD11_S 3_P 1_R
NC_P V DD11_S 3_P 1_P W M3
NC_P V DD11_S 3_P 1_P W M4
P V DD11_S 3_P 1_P MS DA _R
P V DD11_S 3_P 1_E N_R
P V DD11_S 3_P 1_P MA LE RT_R
NC_P V DD11_S 3_P 1_P G 1
NC_P V DD11_S 3_P 1_IMO N4
NC_P V DD11_S 3_P 1_IMO N3
P V DD11_S 3_P 1_RE S E T_N_R
NC_P V DD11_S 3_P 1_S V TO
P V DD11_S 3_P 1_IMO N2
P V DD11_S 3_P 1_P MS CL_R
P V DD11_S 3_P 1_IMO N1
SMLF
IC
RA A 229621G NP #HA 0
E MP TY 0402LF
0402LF
5%
1%
1K
P V DD11_S 3_P 1_O CP _N
PVDD11_S3_P1 VR CONTROLLER
0402LF
1/16W
1%
0.1UF
5%
1/16W
P W RG D_P V DD11_S 3_P 1
0402LF
10%
V S E NS E _P V DD11_S 3_P 1_DP
V S E NS E _V S S _S E NS E _C_P 1
P V DD11_S 3_P 1_TE MP 0
P V DD11_S 3_P 1_RE S E T_N
P V DD11_S 3_P 1_V CCS
P V DD11_S 3_P 1_V CC
0402LF
40.2K
X 7R
25V
0402
10%
0402LF
10K
1%
CHIP
1/16W
0402LF
1/16W
49.9
1%
CHIP
0402LF
E MP TY
1/16W
4.99K
1%
0402LF
0
CHIP
1/16W
X 7R
10%
0.1UF
25V
0402
E MP TY
1/16W
50V
3300P F
X 7R
0402
CHIP
1/16W
1%
0402LF
1%
1/16W
CHIP
1K
0402LF
0402LF
5%
1/16W
0
0402LF
1/16W
0 5%
CHIP
0
0
1/16W
5%
0402
5%X 7R
50V
5%
1000P F
0402
50V
E MP TY
X 7R
10%
470P F
50V
0402
0 5%1/16WCHIP 0402LF
CHIP 0 5%1/16W 0402LF
0402LF
0
5%
1/16W
E MP TY
0402LF0 5%CHIP 1/16W
0 5%CHIP 1/16W
0402LF0 5%1/16WCHIP
5% 0402LFCHIP 1/16W 0
0402LF
0 5%
E MP TY
1/16W
1K 1%
E MP TY 1/16W
0402LF
0402LF5%1/16WCHIP
X 7R
10%
0.1UF
25V
0402
X 7R
10%
0.1UF
25V
0402
6.3V
10UF
20%
X 6S
X 6S
10%
1UF
16V
C0402
0402LF
1 1%
1/16W
CHIP
CHIP
P V DD11_S 3_P 1_E N 5%
0402LF
CHIP
X 7R
04021000P F
P V DD11_S 3_P 1_P MA LE RT
0
5%
49.9
50V
0402LF
1/16W
CHIP
5%0
33
CHIP
1/16W
0402LF
5%
1/16W
0
0402LFE MP TY
1/16W
5%
CHIP
1000P F
0402LF
S MB _S CM_2_R2_S CL
0
S MB _S CM_2_R2_S DA
CHIP
C0402
CHIP
1%
1/16W
13.7K
C5010
32
21
37
38
15
40
39
T H
35
36
19
20
17
18
31
22
14
8
7
6
5
4
3
2
1
9
10
16
12
33
11
34
13
23
24
25
26
27
28
29
30
PU54
21
PR393
2
1 PC645
2
1 PC644
2
1 PC95
2
1 PC96
21
PR406
21
PR391
21
PR392
21
PR407
21
PR13
21
PR14
21
PR408
2
1
PR390
21
PR409
21
PR415
2
1 PC643
21
C8641
21
C642
21
R8385
21 R8386
21
R8381
21
R8382
21
R8383
21
R8380
2
1
PR229
2
1
PC639
21
PR384
2
1
R8011
2
1 PC8
21
PR388
PR604
2
1
PR288
21
R8010
21
R8146
2
1
PR6
2
1 PC638
21
PR376
PR464
CS0
PWM0
TEMP1
EN1||ADDR_CFG
TH_GND
OCP_L
CS2
PWM2
CS3
PWM3
PWM7
CS1
RGND1
VSEN1
VDDIO
TEMP0
VINSEN
VMON||IINSEN
VCCS
PWM6
PG0
PWM1
VSEN0
PWM5
PWM4
PMSDA
RGND0
EN0
nPMALERT
SVD
PG1
CS4
CS5
RESET_L
SVTO
CS6
SVC
PMSCL
SVTI
VCC
CS7
21
2
1
1
SHEETDATE
23
7 3 2 16 5 4
E
A
B
C
E
D
C
B
A
7 6 5 4
D
DEPARTMENT
SIZE
PROJECT DOCUMENT NUMBER REV
REVIEWER
DESIGNER
OUT
OUT
IN
OUT
IN
IN
IN
OUT
OUT
OUT
OUT
OUT
IN
IN
I N
C



2022/5/14 MODIFY
MAIN SOURCE:RENESAS BOM
PU44,PU45 =AL099390004/ISL99390FRZ-TR5935
2ND SOURCE:INFENEON BOM
PU44,PU45 = AL021590000/TDA21590
PU44,PU45 =AL087000A03/MP87000GMJTH-C11D-Z
PR394,PR330,PR331=CS00002JB13
2ND=CV+10G0MZ04
DCR:0.105M OHM
4.5*4.7*4.5
ISAT:13A@100C
3RD=CV+10G0MZ08
PG2289.101HLT
6.3*8
2ND=CC72703MD39
IRIPPLE:5.08A
ESR=10M OHM
BOM NOTE
PR328,PR329 = CS00002JB13
3RD SOURCE:MPS BOM
PR387,PR332,PR333 = EMPTY
PC503_1,PC504_2 = EMPTY
PR330,PR331 = CS00002JB13
PC503_1,PC504_2 = EMPTY
PR332,PR333 = EMPTY
2ND=CH747LM8822
ISAT:132A@100C
10.0*7.7*12.0
PG2323.900HLT
5.0*5.8
2ND=CC7390JMZ11
ESR=10M OHM
7.3*4.3*1.9
DCR=0.103M OHM
2ND=CVA90^0KZ04
3RD=CVA90^0KZ08
PG2323.900HLT
3RD=CVA90^0KZ08
2ND=CVA90^0KZ04
DCR=0.103M OHM
10.0*7.7*12.0
ISAT:132A@100C
PVDD11_S3_P1_PHASE1
PVDD11_S3_P1_PHASE2
ESR=9M OHM
Thu Aug 24 14:09:03 2023<NAME_2>
<NAME_1>
MB FABCGTI V02
225 OF 365
P V DD11_S 3_P 1_P V CC
S W _P 12V _A UX _P V DD11_S 3_P 1_FLT
P V DD11_S 3_P 1
P V DD11_S 3_P 1
P V DD11_S 3_P 1
P V DD11_S 3_P 1_P V CCP 3V 3_A UXP 5V _A UX
P V DD11_S 3_P 1
S W _P 12V _A UX _P V DD11_S 3_P 1_FLT
P 12V _A UX
PVDD11_S3_P1 VR PHASE 1&2
P V DD11_S 3_P 1_P W M2
NC_P V DD11_S 3_P 1_DNC2
P V DD11_S 3_P 1_V CCS
1/16W
225
224
224
224225
224
224
224225
225
224
224
16V
20%
C0805
22UF
X 6S
100NH/16A
560P F
P V DD11_S 3_P 1_TE MP 0
IC
SMLF
X 6S
1/16W
CHIP
1%
1K
0402LFC0805
X 6S
20%
22UF
4V
C0805
X 6S
20%
22UF
4V
25V
0.1UF
X 7R
C0402
50V
100NF
10%
X 7R
90NH/155A
IND
S MLF
0.22UF
A LUM
20%
390UF
2.5V
S MLF
A LUM
20%
390UF
2.5V
S MLF
A LUM
20%
390UF
2.5V
S MLF
A LUM
20%
390UF
2.5V
S MLF
C0805
X 6S
20%
22UF
4V
S P CA P
20%
470UF
S MLF
2.5V2.5V
20%
S P CA P
S MLF
470UF
S MLF
2.5V
470UF
20%
0
C0805
X 6S
20%
22UF
4V
90NH/155A
IND
S MLF
0.22UF
0402
16V
10%
X 7R
1/16W
CHIP
5%0
0402LF
C0402
50V
10%
E MP TY
C0402
10V
2.2UF
10%
X 6S
1/16W
E MP TY
5%
0
0402LF
1/16W
CHIP
1%
2.2
0402LF
0402LF
4.87K 1%
E MP TY 1/16W
C0402
10V
2.2UF
10%
X 6S
0402
25V
0.1UF
10%
X 7R
0402LF
1.5
22UF22UF
C0402
50V
560P F
10%
E MP TY
0402LF
1.5
1%
E MP TY
1/8W
IS L99390FRZ-TR5935
IC
SMLF
C0402
10V
2.2UF
10%
X 6SCHIP
1%
2.2
0402LF
0402LF
4.87K 1%
E MP TY 1/16W
C0402
10V
2.2UF
10%
X 6S
0402
25V
0.1UF
10%
X 7R
1/16W
CHIP
5%
0
0402LF
P V DD11_S 3_P 1_V O S 1
S W _P V DD11_S 3_P 1_P H1
P V DD11_S 3_P 1_V O S 2
S W _P V DD11_S 3_P 1_S W 1
NC_P V DD11_S 3_P 1_G L1_1
NC_P V DD11_S 3_P 1_G L2_1
NC_P V DD11_S 3_P 1_DNC1
P V DD11_S 3_P 1_LS E T1
P V DD11_S 3_P 1_IMO N1
P V DD11_S 3_P 1_V CCS
S W _P V DD11_S 3_P 1_S W 2_RC
NC_P V DD11_S 3_P 1_G L2_2
NC_P V DD11_S 3_P 1_G L1_2
S W _P V DD11_S 3_P 1_S W 2
P V DD11_S 3_P 1_P W M1
P V DD11_S 3_P 1_V CC2
P V DD11_S 3_P 1_IMO N2
P V DD11_S 3_P 1_LS E T2
5%
1/16W
0402LF
E MP TY
S W _P V DD11_S 3_P 1_S W 1_RC
0402
X 7R
16V
S W _P V DD11_S 3_P 1_P H2
C0402
10%
25V
1/8W
1%
X 6S
C0805
IS L99390FRZ-TR5935
P V DD11_S 3_P 1_TE MP 0
IND
10%
S MLF
C0805
X 7R
10%
1UF 0.1UF
25V 16V
20%
16V
S P CA P
20%
0402
X 6S X 6S
C0805
X 6S
22UF
16V
20%
C0805
20%
16V
22UF
X 6S
C0805
16V
22UF
20%
1/16W
0402LF
1%
CHIP
S W _P V DD11_S 3_P 1_B O O T2 S W _P V DD11_S 3_P 1_B O O T2_RC5.6
1/16W
0402LFCHIP
1%S W _P V DD11_S 3_P 1_B O O T1 S W _P V DD11_S 3_P 1_B O O T1_RC5.6P V DD11_S 3_P 1_V CC1
0402
10%
THLF
CHIP
20%
270UF1UF
C0402
10%
X 6S
25V
X 7R
10%
0.1UF
0402
25V
X 6S
C0805
20%
22UF
16V
X 6S
C0805
22UF
20%
X 6S
22UF
20%
22UF
C0805
X 6S
20%
22UF
O S CO N
16V
16V16V16V
C0805 C0805
X 6S
20%
16V
PC7003
PC8007
PC8006
1
30
25_29
3
36
10_19
39
34
4
32
40
7_9-20_24
5
37
38
41
6
35
31
33
2
PU45
2
1 PC512_2
PR395
2
1 PC529_1
2
1 PC526_1
PC511
2
1 PC524
2
1 PC521_1
21
PL54
2
1
PC519
2
1 PC803
2
1 PC532
2
1 PC531
2
1 PC802
2
1 PC525
21
PR332
2
1 PC27
2
1 PC523_2
21
PL55
2
1
PC520
21
PR333
2
1 PC517_1
2
1 PC515_1
2
1 PC513_1
21
PR330
2
1 PC315
2
1 PC511_1
PR394
2
1
PR326
2
1 PC505
2
1
PR520
2
1 PC516_2
2
1 PC514_2
2
1 PC255
1
30
25_29
3
36
10_19
39
34
4
32
40
7_9-20_24
5
37
38
41
6
35
31
33
2
PU44
2
1 PC508_11P1_2
2
1
PR327
21
PR329
2
1 PC506
2
1 PC504_2
PR387
21
PL56
2
1 PC522
2
1 PC530
2
1 PC527_2
2
1 PC528
2
1 PC518_2
2
1 PC509_1
2
1 PC507_11P1_1
21
PR328
2
1 PC503_1
2
1 PC510_2
21
PR331
2
1
PR519PGND2
GL2
GL1
DNC
EN
PGND3
VOS
VIN2
PGND1
SW
LSET
IOUT
TOUT_FLT
PVCC
PHASE
VIN1
BOOT
AGND
VCC
REFIN
PWM
1 2
1 2
1 2
PGND2
GL2
GL1
DNC
EN
PGND3
VOS
VIN2
PGND1
SW
LSET
IOUT
TOUT_FLT
PVCC
PHASE
VIN1
BOOT
AGND
VCC
REFIN
PWM
2
1
2
1
2
1
2
1
1
SHEETDATE
23
7 3 2 16 5 4
E
A
B
C
E
D
C
B
A
7 6 5 4
D
DEPARTMENT
SIZE
PROJECT DOCUMENT NUMBER REV
REVIEWER
DESIGNER
OUT
IN
OUT
IN
OUT
IN
OUT
IN
C



MAX LOAD STEP=2.5A
WORK FREQUENCY=600KHZ
IRM REV1.09
EFFICIENCY > 85% @TDC
MAX LOAD RELEASE=2.5A
AC =+/-30MV
DC =1.76-1.84V
OUTPUT VOLTAGE=1.8V
OCP=15A (EDC*1.2)
BOM NOTE
2ND=CV-10I0MZ00
PCMC104T-1R0MN
ISAT:25A@100C
DCR=3.3M OHM
10*10*4
RA
DCR=5M OHM
FCCM
FSW=600KHZ
PVDD18_S5_P1
RB
NEAR CPU SIDE TRACE SPACING = 5MIL
TRACE WIDTH = 10MIL
DIFFERENTIAL PAIR
5.0*5.8
ESR= 10 MOHM
2ND=CC7390JMZ11
PVDD18_S5_P1 SPECFICATION
VOUT=0.6(1+RA/RB)=1.8V
EDC=12A
TDC=10A
1ST
2ND NA
PC64 CHANGE TO CH13306JB14
3RD PC20 CHANGE TO CH5222KEB01
BOM CHANGE R&C TABLE
3RD AL000548007/TPS548B28RWWR/TI
2ND AL053319002/RS53319LR/REEDSEMI
1ST AL008633005/MPQ8633BGLE-C838-Z/MPS
2022/5/14 MODIFY
3RD=CX000220000
2ND=CX220Z06Z00
IRATED=5A@125C
Thu Aug 24 14:09:02 2023<NAME_2>
<NAME_1>
MB FABCGTI V02
226 OF 365
P V DD18_S 5_P 1
P 3V 3_A UX
P 3V 3_A UX
P 12V _A UX
81
81
54
54
33
C0402
1UF
X 6S
10%
25V
X 7R
0402
0.1UF
25V
10%
16V
X 7R
0402
0.22UF
10%
X 6S
10%
1UF
25V
C0402
10%
0.1UF
E MP TY
25V
0402
P W RG D_P V DD18_S 5_R_P 1
50V
1000PF
CHIP
SW_PVDD18_S5_P1_BST_R
IND
S MLF
S W _P V DD18_S 5_P 1_B S T
0402LF
MP Q 8633B G LE -C838-Z
SMLF
P V DD18_S 5_P 1_FB
16V
P V DD18_S 5_P 1_E N
22UF
C0805
20%
X 6S
22UF
X 6S
16V
C0805
20%
20% 20%
S W _P 12V _A UX _P V DD18_S 5_P 1_FLT
C0805
X 6S
22UF
16V 16V
22UF
X 6S
C0805 C0805
X 6S
22UF
16V
20%
B LM18S N220TN1D/8000MA
0402LF
1/16W
49.9
E MP TY 0.01UF
1%
10
0402LF
CHIP
1/16W
1/16W0
0402LF
CHIP
V S E NS E _P V DD18_S 5_P 1_DN
10K
1/16W
C0402
0402
CHIP
1%
5%
5%
10K
CHIP
1/16W
P V DD18_S 5_P 1_CS
P V DD18_S 5_P 1_V CC
P V DD18_S 5_P 1_MO DE
P V DD18_S 5_P 1_RE F
P V DD18_S S _P 1_RG ND
P V DD18_S 5_P 1_FB _RC
V S E NS E _P V DD18_S 5_P 1_DP
IND
S MLF
8.66K
1%
CHIP
1/16W
0402LF
0
5%
CHIP
1/16W
0402LF
0 5%
0402LF
1/16WCHIP
IC
0402
25V
X 7R
10%
0.022UF
25V0.1UF
10%
X 7R
0402
0402LF
1%
CHIP
50V
X 7R
0402
10%
0402LF
CHIP
10%
25V
5%
22UF
C0805
4V
X 6S
C0805
4V
22UF
20%
49.9
CHIP1%
1/16W
0402LF
20%
C0805
X 6S
4V
22UF 22UF
C0805
E MP TY
20%
4V
22UF
20%
E MP TY
4V
C0805
A LUM
S MLF
2.5V
20%
390UF
25V
0.1UF
0402
X 7R
10%
0402LF
1K
1%
CHIP
1/16W
PVDD18_S5_P1
0402LF
P W RG D_P V DD18_S 5_P 1
S W _P V DD18_S 5_P 1_S W
2.2
20K
1.0UH/18A
220P F
1% X7R
20%
X 6S
PR8002
PC8003
2
1 PC60
2
1
PC21
2
1 PC87
2
1 PC84
21
PR400
21
PR401
PC6006
21
PR148
21
PC64
2
1 PR147
2
1
PR399
2
1
PC19
21
PR398
21
PL26
2
1
PC20
2
1
PR403
21 R259
2
1
PC89
2
1 PC88
2 1PR402
2
1 PC83
2
1 PC65
2
1
R8009
2
1 PC22
2
1 PC152
2
1 PC150
2
1 PC61
21
PC62
2
1
PC153
21
10
19
5
20
6
9
11_18
4
7
8
3
1
2
PU3
2
1
PR397
2
1
PR8
2
1C675
PC6002
PL57
C5016
21
1 2
1 2
VIN2
CS
MODE
TRK_REF
SW
RGND
VCC
AGND
FB
BST
EN
PGND
PGOODVIN1
21
2
1
2
1
2
1
2
1
1
SHEETDATE
23
7 3 2 16 5 4
E
A
B
C
E
D
C
B
A
7 6 5 4
D
DEPARTMENT
SIZE
PROJECT DOCUMENT NUMBER REV
REVIEWER
DESIGNER
OUT
IN
IN
IN
C



Thu Aug 24 10:15:28 2023<NAME_2>
<NAME_1>
MB FABCGTI V02
227 OF 365Blank
1
SHEETDATE
23
7 3 2 16 5 4
E
A
B
C
E
D
C
B
A
7 6 5 4
D
DEPARTMENT
SIZE
PROJECT DOCUMENT NUMBER REV
REVIEWER
DESIGNER
C



Thu Aug 24 10:15:29 2023<NAME_2>
<NAME_1>
MB FABCGTI V02
228 OF 365Blank
1
SHEETDATE
23
7 3 2 16 5 4
E
A
B
C
E
D
C
B
A
7 6 5 4
D
DEPARTMENT
SIZE
PROJECT DOCUMENT NUMBER REV
REVIEWER
DESIGNER
C



10 INCH5 INCH
Thu Aug 24 14:09:58 2023<NAME_2>
<NAME_1>
MB FABCGTI V02
229 OF 365
DELTA_L_GND_1
DELTA_L_GND_1
DELTA_L_GND_1
DELTA_L_GND_1
DELTA_L_GND_1
DELTA_L_GND_1
DELTA_L_GND_1
DELTA_L_GND_1DELTA_L_GND_1
DELTA_L_GND_1
DELTA_L_GND_1
DELTA_L_GND_1
DELTA_L_GND_1DELTA_L_GND_1
DELTA_L_GND_1
DELTA_L_GND_1
DELTA_L_GND_1
DELTA_L_GND_1
DELTA_L_GND_1
DELTA_L_GND_1
DELTA_L_GND_1DELTA_L_GND_1
DELTA_L_GND_1
DELTA_L_GND_1
DELTA_L_GND_1
DELTA_L_GND_1
DELTA_L_GND_1 DELTA_L_GND_1
DELTA_L_GND_1
DELTA_L_GND_1
DELTA_L_GND_1DELTA_L_GND_1
EMPTY
DELTA_L_85_10INCH_IN4_DN
DELTA_L_85_10INCH_IN5_DN
DELTA_L_85_10INCH_IN5_DP
DELTA_L_85_10INCH_IN4_DP
S M L F
SMLF
SMLF
DELTA_L_85_5INCH_IN3_DP
DELTA_L_85_5INCH_IN3_DN
DELTA-L 4.0
DELTA_L_85_10INCH_IN6_DN
DELTA_L_85_10INCH_IN6_DP
D E L T A - L4 . 0
E M P T Y
SMLF
DELTA-L 4.0
EMPTY
S M L FD E L T A - L4 . 0
E M P T Y
EMPTY
SMLF
E M P T Y
D E L T A - L4 . 0 S M L F
SMLF
DELTA-L 4.0
EMPTY
S M L FD E L T A - L4 . 0
E M P T Y
DELTA-L 4.0
SMLF
DELTA_L_85_10INCH_IN2_DN
DELTA_L_85_10INCH_IN2_DP
S M L FD E L T A - L4 . 0
E M P T Y
S M L F
EMPTY
DELTA-L 4.0
SMLF
DELTA_L_85_10INCH_IN1_DP
DELTA_L_85_10INCH_IN1_DN
S M L FD E L T A - L4 . 0
E M P T Y
EMPTY
DELTA-L 4.0
SMLF
DELTA_L_85_10INCH_TOP_DP
DELTA_L_85_10INCH_TOP_DN
EMPTY
DELTA_L_85_5INCH_IN6_DN
DELTA_L_85_5INCH_IN6_DP
D E L T A - L4 . 0
E M P T Y
S M L F
E M P T Y
SMLF
EMPTY
DELTA_L_85_5INCH_IN2_DP
DELTA_L_85_5INCH_IN2_DN
DELTA_L_85_5INCH_IN1_DP
DELTA_L_85_5INCH_IN1_DN
DELTA_L_85_5INCH_BOT_DP
DELTA_L_85_5INCH_BOT_DN
S M L F
E M P T Y
DELTA_L_85_5INCH_TOP_DP
DELTA-L
D E L T A - L4 . 0
SMLF
DELTA-L 4.0
EMPTY
EMPTY
SMLF
DELTA-L 4.0
S M L FD E L T A - L4 . 0
E M P T Y
DELTA-L 4.0
EMPTY
EMPTY
DELTA-L 4.0
SMLF
SMLF
DELTA-L 4.0
EMPTY
E M P T Y
S M L F
SMLF
DELTA-L 4.0
DELTA-L 4.0
DELTA_L_85_5INCH_IN4_DN
DELTA_L_85_5INCH_IN4_DP
DELTA_L_85_5INCH_IN5_DP
DELTA_L_85_5INCH_IN5_DN
D E L T A - L4 . 0
S M L F
D E L T A - L4 . 0
E M P T Y
D E L T A - L4 . 0
D E L T A - L4 . 0
E M P T Y
S M L F
DELTA_L_85_5INCH_TOP_DN
SMLF
DELTA-L 4.0
EMPTY
S M L FD E L T A - L4 . 0
E M P T Y
EMPTY
DELTA-L 4.0
SMLF
S M L FD E L T A - L4 . 0
E M P T Y
DELTA_L_85_10INCH_BOT_DP
DELTA_L_85_10INCH_BOT_DN
EMPTY
DELTA-L 4.0 S M L FD E L T A - L4 . 0
E M P T Y
DELTA_L_85_10INCH_IN3_DP
DELTA_L_85_10INCH_IN3_DN
32
13 2
1
32
13 2
1
32
13 2
1
32
13 2
1
32
13 2
1
32
13 2
1
32
13 2
1
32
13 2
1
32
13 2
1
32
13 2
1
32
13 2
1
32
13 2
1
32
13 2
1
32
13 2
1
32
13 2
1
32
13 2
1
J119
J118
J80
J79
J78
J77
J76
J75
J115
J114
J8068
J8067
J66
J65
J64
J63
1_P
3_G2_N1_P
3_G 2_N
1_P
3_G2_N1_P
3_G 2_N
1_P
3_G2_N1_P
3_G 2_N
1_P
3_G2_N1_P
3_G 2_N
1_P
3_G2_N1_P
3_G 2_N
1_P
3_G2_N1_P
3_G 2_N
1_P
3_G2_N1_P
3_G 2_N
1_P
3_G2_N1_P
3_G 2_N
1_P
3_G2_N1_P
3_G 2_N
1_P
3_G2_N1_P
3_G 2_N
1_P
3_G2_N1_P
3_G 2_N
1_P
3_G2_N1_P
3_G 2_N
1_P
3_G2_N1_P
3_G 2_N
1_P
3_G2_N1_P
3_G 2_N
1_P
3_G2_N1_P
3_G 2_N
1_P
3_G2_N1_P
3_G 2_N
J 1 2 1
J 1 2 0
J 8 6
J 8 5
J 8 4
J 8 3
J 8 2
J 8 1
J 1 1 7
J 1 1 6
J 7 4
J 7 3
J 7 2
J 7 1
J 7 0
J 8 0 6 9
1
SHEETDATE
23
7 3 2 16 5 4
E
A
B
C
E
D
C
B
A
7 6 5 4
D
DEPARTMENT
SIZE
PROJECT DOCUMENT NUMBER REV
REVIEWER
DESIGNER
C



HOLE300 (CPU HS HOLE)
HOLE_D10N
RT HS HOLE WILL DEFINE IN DXF/EMN
RETIMER HS HOLE
HOLE_C4-5D3-8B8I5-6_RO6-6_NPT_RB
HOLE1248 (M.2 LATCH HOLE)
HSC MODULE CONN HOLE
HOLE_OB6-4X8OBD3-2X4-8B6-4X8N_RO6X7-6_NPM
HOLE1187 (E1S SCREW HOLE)
VR HS HOLE
P3V3_AUX HS HOLE
20221013: ADD FOR RETIMER VR
GND_HOLE514(STD)
HOLE_R4-2X5D2B4_IX0-1T_NPM_RB
HOLE 596
HOLE372(GUIDE PIN)
HOLE_DUMMY50
TOOLING HOLE
HOLE1247(M.2)
HOLE_C10D5-6B10_NPB
GND_HOLE140 (HANDLE)
GND_C8D4B8
Thu Aug 24 14:09:29 2023<NAME_2>
<NAME_1>
MB FABCGTI V02
230 OF 365
EMPTY
TH
EMPTY
EMPTY
TH
TH
EMPTY
TH
TH
TH
TH
E MP TY
E MP TY
E MP TY
TH
E MP TY
TH
E MP TY
TH
E MP TY
TH
E MP TY
TH
TH TH
E MP TY
TH
E MP TY E MP TY
TH
E MP TY
TH
E MP TY
TH
E MP TY
TH
E MP TY
TH
E MP TY
E MP TY
TH
TH
TH TH
EMPTY
TH TH
TH
EMPTY
TH
EMPTY
TH
EMPTY
TH
EMPTY
TH
TH
EMPTY EMPTY
TH
EMPTY EMPTY
TH TH
EMPTYEMPTY
TH
IO
THLF
CONN1_10165288-101LF
IO
TH
EMPTY
TH
TH
EMPTYEMPTYEMPTY EMPTY
EMPTY
TH
EMPTY
TH
EMPTYEMPTY
TH TH
EMPTY
THTH
HOLE
EMPTY
TH TH
EMPTY
TH
EMPTY
EMPTY
TH
THTH TH
EMPTY
E MP TY
THTH
TH
EMPTY
EMPTY
TH
THLF
CONN1_10165288-101LF
EMPTY
EMPTY
TH
EMPTY
TH
E MP TY
THTH
E MP TY
TH
E MP TY
E MP TY
TH
E MP TY
TH
E MP TY
E MP TY
EMPTY
TH
EMPTYEMPTY
EMPTY
EMPTY
TH
EMPTY
TH
EMPTY
H3 H5 H12
H10
H8
H2
H6001
H6000
1
H11
1
H13
1
H54
1
H50
1
H49
1
H44
1
H43
1
H37
1
H33
1
H38
1
H34
1
H8028
1
H22
1
H8027
1
H21
1
H53
1 1 111
1
1
11
1
1
1
1
1
1
1
1
1
1
1
1
1
1
1
1
1
1
1
1
6
5 3
26
5 3
2
11
1
SCR_H1SCR_H1
1
11
11
1
1
6
5 3
26
5 3
26
5 3
2
11
9
8
7
4
9
8
7
4
9
8
7
4
9
8
7
4
9
8
7
4
H6002
H90H128
H106
H105
H104
H103
H102
H101
H100
H99
H98
H97
H96
H95
H94
H93
H92
H91
H89
H88
H87
H86
H112H111
H126
J123J122
H127
H32H31
H75H74
H125
H124
H30H29H28
H115
H27
H114H113
H77H76
1
11
11
1
1
1
1
1
1
1
11
1 11
1
1
1
1
11
1111
1 1 111
1
1
11
1
1
1
1
1
1
1
1
1
1
1
1
1
1
1
1
1
1
1
1
1
11
1
NC1NC1
1
1111
1
SHEETDATE
23
7 3 2 16 5 4
E
A
B
C
E
D
C
B
A
7 6 5 4
D
DEPARTMENT
SIZE
PROJECT DOCUMENT NUMBER REV
REVIEWER
DESIGNER
C



Thu Aug 24 10:15:31 2023<NAME_2>
<NAME_1>
MB FABCGTI V02
231 OF 365Blank
1
SHEETDATE
23
7 3 2 16 5 4
E
A
B
C
E
D
C
B
A
7 6 5 4
D
DEPARTMENT
SIZE
PROJECT DOCUMENT NUMBER REV
REVIEWER
DESIGNER
C



Thu Aug 24 10:15:32 2023<NAME_2>
<NAME_1>
MB FABCGTI V02
232 OF 365Blank
1
SHEETDATE
23
7 3 2 16 5 4
E
A
B
C
E
D
C
B
A
7 6 5 4
D
DEPARTMENT
SIZE
PROJECT DOCUMENT NUMBER REV
REVIEWER
DESIGNER
C



ADDRESS: 0XD4(8-BIT) / 0X6A(7-BIT)
20 MA
TO GPU FPGA
TO BMC
13 MA
20210602 MODIFY FOR GT
20211129 U248 CHANGE TO OR GATE
Thu Aug 24 14:09:19 2023<NAME_2>
<NAME_1>
MB FABCGTI V02
233 OF 365
VFG_3P3A_CLK_GEN
P3V3_AUX
P3V3_AUX
P3V3_AUX
VFG3P3_CLK_GENP3V3_AUX
P3V3_AUX
P3V3_AUX
VFG3P3_CLK_GEN
P3V3_AUX
VFG_3P3A_CLK_GEN
234
122
111 112 234
80
127
234234
150
80
111234112
150
122
234
234
151
151
234
9FGL0251DKILFT
IC
SMLF
0402 0402
X6S
10%0.1UF
X7R
0402
C0805
0.1P
NPO
C0402
1K
1K
CHIP
1/16W
0402LF
1%
PLACE CLOSE TO U247 ALL VDD PINS
FCM2012KF-601T/0.5A
SMLF
IND
IC
P3V3_PWRGD_CLKGEN
CLK_100M_GPU_FPGA_DP
CLK_GEN2_GPU_FPGA_OE_OR_N
GPU_FPGA_READY_R_N
CLK_GEN2_GPU_FPGA_OE_N
GPU_FPGA_READY_N
CLK_GEN2_GPU_FPGA_OE_R2_N
CLK-GEN(NON SSC)
10%
25V
X7R
0402LF
CHIP
1/16W
1%
10K
CHIP
0402LF
10K
1%
0402LF
1%
1/16W
EMPTY
0
0
5%
CHIP0
0402LF
1/16W
10K
1%
EMPTY
CHIP
1/16W
0402LF
1%
1 1%
10%
X7R
10%
X7R
10%
25V25V
0.1UF
X7R
10%
0402
25V
10%
X6S
10UF
5%0
1/16WCHIP
0402
10%
X 7R
0.1UF
25V
CHIP0
5%
1/16W
4.7K
EMPTY
1%
0402LF
0
1/16W
5%
CHIP0
0402LF
CHIP
CLK_GEN2_SMB_SADR
CHIP
CHIP
0.1UF
SMLF
74LVC1G32GW
10K
1/16W
FG_SS_EN
10K
CLK_100M_BMC_RC_DN
CHIP
1/16W 50V
0.1P
NPO
4.7PF
50V
4.7PF
CLK_GEN2_BMC_RC_OE_N
CLK_GEN2_GPU_FPGA_OE_OR_N
C0402
1%
1/16W
CHIP
0402LF
C LK_GEN 2_XTAL_IN _R
MISC
SMLF
0402LF
25MHZ
CLK_100M_BMC_RC_DPCHIP0
0402LF
0
CHIP
25V0.1UF
CLK_100M_GPU_FPGA_DN
25V25V
C0402
1/16W 0402LF 1UF
0402LF
1/16W
0.1UF
0402
FG_SS_EN
P3V3_PWRGD_CLKGEN
CLK_GEN2_GPU_OE_N
CLK_100M_GPU_FPGA_DN_R
CLK_100M_GPU_FPGA_DP_R
CLK_100M_BMC_RC_DN_R
CLK_100M_BMC_RC_DP_R
CLK_GEN2_BMC_RC_OE_R3_N
SMB_H OST_C LK_GEN 2_3V3AU X_SD A
SMB_H OST_C LK_GEN 2_3V3AU X_SC L
CLK_GEN2_SMB_SADR
CLK_GEN2_XTAL_OUT
CLK_GEN2_XTAL_IN
C94C71
C1884
R4080
R4081
R4082
R3335
R3336
R3337
R3338
R4078
R4079
R4077
C95C1889C1886
R4501
C1882
R4075
R4076
R3326
R3327
1
2
4
19
12
3
7
16
20
11
25
9
8
24
5
6
15
21
10
18
17
14
13
23
22
21
5
4
2
1
3
31
42
U247
L17
U248
Y8003
DESIGN NOTE:
TH_GND
GNDXTAL
^vSS_EN_tri
^CKPWRGD_PD#
GND_21
VDD3.3_20
vOE1#
DIF1#
DIF1
VDDA3.3
GNDA
DIF0#
DIF0
vOE0#
VDD3.3_11
GND_10
SDATA_3.3
SCLK_3.3
VDDDIG3.3
GNDDIG
GNDREF
vSADR||REF3.3
VDDXTAL3.3
X2
XIN||CLKIN_25
1 2
GND
O
I1
VCC
I0
X2
G2G1
X1
2
1
2
1
2
1
R3322
2
1
2
1 C97
2
1
2
1
2
1
2
1
21
21
21
21
2
1
2
1
21
2
1
2
1
2
1
2
1 C2257
2
1 C1883
21
2
1
21
21
2
1
21
21
1
SHEETDATE
23
7 3 2 16 5 4
E
A
B
C
E
D
C
B
A
7 6 5 4
D
DEPARTMENT
SIZE
PROJECT DOCUMENT NUMBER REV
REVIEWER
DESIGNER
IN
OUT
OUT
OUT
OUT
OUT
OUTOUTOUT
IN
IN
OUT
BI
IN
IN
IN
IN
R4521
R4514
C



HUB ADDRESS : 0X2C
USB_HUB_I2C ONLY FOR EEPROM.
20210527 MODIFY FOR GT
Thu Aug 24 14:09:16 2023<NAME_2>
<NAME_1>
MB FABCGTI V02
234 OF 365
P3V3_AUX
P3V3_AUX
P3V3_AUX
P3V3_AUX
P3V3_AUX
235
246176178
235
235
235
235
122
235
150
235
235
235
122
150
235
235
235
235
235
0402LF
USB2 BOM1
USB_HUB_PSELF
25V
1/16W 1%
CHIP
1/16W
RST_USB_HUB_N
10%
CHIP
C0402
0 CHIP
1UF
25V
10%
C0402
EMPTY
EMPTY
10%
25V
0.1UF
1/16W
USB2 BOM1
0402LF
E MP TY
NC_USB_HUB_DP4
NC_USB_HUB_DM3
NC_USB_HUB_DP3
0402LF
E MP TY
5%
USB2 BOM2
E MP TY
USB2_HUB_SWB_DN
CHIPUSB2_HUB_SWB_DP 0
0402LFCHIP
5%
0
E MP TY
49.9
USB2 BOM1
USB_HUB_OVCUR1
USB2 BOM1
1/16W
EMPTY
1%
10K
1%
10K
C0402
680
X 6S
C0402
0402
X 6S
0.1%
USB2 BOM1
100K
1%
1/16W
CHIP
0402LF
1%
CHIP
0402LF
USB_HUB_OVCUR1
10%
25V
0.1UF
10UF
X 6S
6.3V
20%
0.1UF
0402
X 7R
25V
10%
0.1UF
25V
10%
0402
X 7R
25V
1UF
C0402
25V
10%
X 7R
0402
X 7R
10%
USB2 BOM1
10%
25V
49.9 49.9
E MP TYE MP TY
US B 2 B OM1
15PF
NC_USB_HUB_DP2
USB2_HUB_BUF_SWB_DN
NC_USB_HUB_DM2
USB_HUB_OVCUR2
USB HUB (BMC TO EXAMAX)
0402LF
CHIP 0402LF
10%
EMPTY
C0402
25V
0402LF
5%
EMPTY
C0402
C0G
0402
SMLF
0
0402LF
SMLF
IC
12MHZ
USB2 BOM1
5%
50V
CHIP
USB2_P0_R_DN
0
5%
1/16W
50V
15PF
0402
MISC
C0G
USB2_HOST_BMC_B_DP
USB2 BOM1
0
0
USB2 BOM1
0402LF
NC_USB_HUB_DM4
X6S
P 3V 3_A UX _US B _HUB0
CHIP
10%
X 7R
GL852G-OHY60
0.1UF 0.1UF
25V
0402
0402LF
EMPTY
1%
1/16W
USB_HUB_OVCUR4
USB_HUB_OVCUR3
10K
10K
EMPTY
USB_HUB_OVCUR2
EMPTY
10K
USB2 BOM1
10K
EMPTY
USB2 BOM1
0
49.9
0402LFUSB2 BOM1
USB2 BOM2
EMPTY
0
USB2_HUB_BUF_SWB_DP
SHORT THE NET USB2_HUB_SWB_R_DP/DN TO USB2_HUB_BUF_SWB_R_DP/DN
TP_USB2_ENA_HS
0.1UF3.9K
1/16W
TP_USB2_CD
PD_U5201_RSTN
25V
10%
US B 2 B OM2
0
R2790/R3651,R3652/R2791 CO-LAYOUT
USB2_HOST_BMC_B_DN
USB2_HOST_BMC_B_BUF_DN
USB2_HOST_BMC_B_BUF_DP
USB2 BOM2
E MP TY
USB2 BOM2
SMLF
TUSB211IRWBR
EMPTY
PD_U5201_EQ
US B 2 B OM2
PD_U5201_VREG
USB2 BOM2 USB2 BOM2
0.1UF
EMPTY
C0402
USB2_HUB_BUF_SWB_R_DP
USB2_HUB_BUF_SWB_R_DN
USB2 BOM2
TP_USB2_TEST
USB2_HUB_BUF_SWB_R_DN
USB2_HUB_BUF_SWB_R_DP
0
R2788/R2786,R2789/R2787 CO-LAYOUT
USB2 BOM2
USB2 BOM1
0402LFCHIP
USB2_P0_R_DP
USB_HUB_XTAL_OUT
NC_USB_HUB_SDA
USB_HUB_TEST
USB_HUB_XTAL_IN
CHIP
0402LF
US B 2 B OM1
USB2_HUB_SWB_DP
USB2_HUB_SWB_DN
1UF
USB2 BOM1USB2 BOM1USB2 BOM1USB2 BOM1USB2 BOM1USB2 BOM1USB2 BOM1
0402LF
USB2 BOM1
USB2 BOM1
47K
EMPTY
US B _HUB _P G A NG
US B _HUB _P S E LF
0 USB_HUB_DVDD
0402LF
1/16W
0402LF
USB_HUB_RREF
USB_HUB_OVCUR4
0402LFCHIP10K
USB2 BOM1
US B 2 B OM1
1/16W
US B 2 B OM1
USB_HUB_OVCUR3
0402LF
1/16W
1UF
CHIP
33.2
1%
RST_USB_HUB_R_N
235
235235
235
R4419
R3665
C2038 C2031
C2032 C2033
R3653
R2789
R2791R2790
C2029 C2030
R4482 R4483
R4420
R3661
R3666
R3659
R3658
R3657
R3656
R3662
C2039 C2040
R3655
R3660
C2035C2034
R2788
31
42
11
10
28
27
TH
18
26
8
17
22
23
19
20
24
25
21
16
13
7
4
2
15
12
6
3
1
14
9
5
Y8004
R3654
21R3651
21R3652
U268
2
1 C5234
21R5234
21R5236
2
1 C5229
2
1 C5236
U5201
R5238
2
1 C5232
R2786
R2787
CAD NOTE:
CAD NOTE:
CAD NOTE:
GND
EQ
D2PD1P
D1M
CD
ENA_HS
VCCTEST
VREG
D2M
RSTN
X2
G2G1
X1
DM4
DP4
DM3
DP3
DM2
DP2
DM1
DP1
DM0
DP0
RREF
PSELF
PGANG
RESET#
OVCUR4#
OVCUR3#
OVCUR2#||SMD
OVCUR1#||SMC
TH
DVDD
AVDD
AVDD
AVDD
V33
V5 SDA
TEST||SCL
X2
X1
2
1
2
1
2
1
2
1
2
1
2
1
21
21
21
21
212
1
2
1 2
1
21
2
1
2
1
2
1
21
2
1
2
1
2
1
2
1
2
1
2
1
2
1
2
1
2
1
2
1
2
1
2
1
11
123
5 10
6 9
7
8
2
1
4
21
21
21
1
SHEETDATE
23
7 3 2 16 5 4
E
A
B
C
E
D
C
B
A
7 6 5 4
D
DEPARTMENT
SIZE
PROJECT DOCUMENT NUMBER REV
REVIEWER
DESIGNER
BI
BI
BI
BI
OUT
OUT
OUT
OUT
OUT
IN
IN
IN
IN
IN
IN
BI
BI
BI
BI
R3664
R3663
C2041
C



20211201 MODIFY FOR GT
ADDRESS : 0X90 (8-BIT) / 0X48 (7-BIT)
ADDRESS : 0X90 (8-BIT) / 0X48 (7-BIT)
ADDRESS : 0X90 (8-BIT) / 0X48 (7-BIT)
ADDRESS : 0X90 (8-BIT) / 0X48 (7-BIT)
Thu Aug 24 14:09:16 2023<NAME_2>
<NAME_1>
MB FABCGTI V02
235 OF 365
P3V3_AUX
P3V3_AUX
P3V3_AUX
P3V3_AUX
P3V3_AUX
P3V3_AUX
P3V3_AUX
P3V3_AUX
P3V3_AUX
P3V3_AUX
P3V3_AUX
P3V3_AUX
23685
253
23685
253
253
253272
23685
253
253272
253
253
23685
SMLF
X 7R
10%
LM75BD
IC
FM_G751_0_ALERT_N
10%
0402LF
SMB_LM75_0_3V3AUX_SCL_R1
SMLF
U271_1_A DD1
U 271_1_AD D 0
1/16W
1%
1K
0402LF
1/16W
1K
0.1UF
0.1UF
1%
1/16W
EMPTY
0402LF
EMPTY
1/16W
1%
FM_THERMAL_ALERT_N 0402LF
U272_2_A DD1
U 272_2_AD D 0
0402
25V
10%
X 7R
33.2CHIP1/16W 1% 0402LF
33.2 1%CHIP1/16W
CHIP0
CHIP
0402LF
1K
1/16W
1%
1K
0402LF
CHIP
0402LF
1/16W
1K
1%
1K
1%
CHIP
0402LF
EMPTY
1/16W
1K
0402LF
1%
EMPTY
1%
1/16W
1K
EMPTY
0402LF
CHIP
0402LF
1/16W
1K
1%1%
CHIP
0402LF
1K
1/16W
1%
1/16W
1K
EMPTY
0402LF
CHIP
0402LF
1K
1/16W
1%
0402
X 7R
25V
1/16W CHIP 1%33.2 0402LF
0 0402LFCHIP
CHIP 33.2 1%1/16W 0402LF
1%1/16W CHIP 0402LF33.2
CHIP0 0402LF
CHIP 33.2 1%1/16W 0402LF
25V
1%
1/16W
1K
0402LF
CHIP
0402LF
EMPTY
1K
1/16W
1%
1%
1/16W
1K
0402LF
CHIP
1%
1K
1/16W
0402LF
CHIP
0402LF
EMPTY
1K
1/16W
1%
EMPTY
1%
0402LF
1K
1/16W
CHIP 0402LF33.21/16W 1%
CHIP 0402LF0
33.2 0402LF1%CHIP1/16W
25V
X 7R
0402
10%
0.1UF
CHIP
0402LF
1K
1/16W
1%
1/16W
1K
1%
0402LF
EMPTY
CHIP
0402LF
1K
1/16W
1%
CHIP
0402LF
1/16W
1K
1%
1%
1/16W
1K
0402LF
EMPTY
1/16W
1K
0402LF
1%
EMPTY
200K
1%
1/16W
EMPTY
0402LF
EMPTY
1/16W
0402LF
1%
200K
200K
1%
0402LF
1/16W
EMPTY
1%
1/16W
CHIP
0402LF
200K
SMB_LM75_1_3V3AUX_SCL
TEMP SENSOR - LM75
FM_THERMAL_ALERT_N
SMB_LM75_2_3V3AUX_SCL
SMB_LM75_2_3V3AUX_SDA
SMB_LM75_0_3V3AUX_SDA
SMB_LM75_1_3V3AUX_SDA_R1
FM_THERMAL_ALERT_N
FM_G751_1_ALERT_N
SMB_LM75_1_3V3AUX_SCL_R1
SMB_LM75_3_3V3AUX_SDA
SMB_LM75_0_3V3AUX_SCL
SMB_LM75_1_3V3AUX_SDA
FM_LM75_2_ALERT_N
SMB_LM75_2_3V3AUX_SDA_R1
FM_LM75_3_ALERT_N
SMB_LM75_3_3V3AUX_SCL_R1
SMB_LM75_3_3V3AUX_SDA_R1
SMB_LM75_3_3V3AUX_SCL
IC
U 273_3_AD D 2
SMLF
IC
LM75BD
U 272_2_AD D 2
IC
FM_THERMAL_ALERT_N
LM75BD
SMLF
SMB_LM75_0_3V3AUX_SDA_R1
U 270_0_AD D 0
U270_0_A DD1
U 270_0_AD D 2
U 271_1_AD D 2
SMB_LM75_2_3V3AUX_SCL_R1
LM75BD
0.1UF
0402
U 273_3_AD D 0
U273_3_A DD1
R4209
R4208
R4210
R4211
R4200R4192
R4201R4193
R4184
R4185
R3554
R4212
R3553
R4202R4194
R4203R4195
R4186
R4187
R4181
R4213
R4178
R4179
R4214
R4182
R4189
R4188
R4197 R4205
R4196 R4204
R4190
R4191
R4206
R4207
R4198
R4199
R4215
R4183
R4180
81
2
3
4 5
6
7
81
2
3
4 5
6
7
81
2
3
4 5
6
7
81
2
3
4 5
6
7
U273
U272
U271
U270
VCC
A0
A1
A2GND
OS
SCL
SDA
VCC
A0
A1
A2GND
OS
SCL
SDA
VCC
A0
A1
A2GND
OS
SCL
SDA
VCC
A0
A1
A2GND
OS
SCL
SDA
2
1
2
1
2
1
2
1
2
1
2
1
2
1
2
1
2
1
2
1
2
1
21
21
21
2
1
2
1
2
1
2
1
2
1
2
1
2
1
21
21
21
21
21
21
2
1
2
1
2
1
2
1
2
1
2
1
2
1
2
1
2
1
2
1
2
1
2
1
2
1
21
21
21
2
1
1
SHEETDATE
23
7 3 2 16 5 4
E
A
B
C
E
D
C
B
A
7 6 5 4
D
DEPARTMENT
SIZE
PROJECT DOCUMENT NUMBER REV
REVIEWER
DESIGNER
BI
IN
OUT
OUT
OUT
OUT
IN
BI
IN
BI
BI
IN
C31
C32
C73
C2010
C



ADDRESS : 0X84 (8-BIT)
0X42 (7-BIT)
20211130 ADD R4093,R4094 PU TO P3V3_AUX
20210929 MODIFY FOR GT
ADDRESS : 0X82 (8-BIT)
0X41 (7-BIT)
Thu Aug 24 14:09:16 2023<NAME_2>
<NAME_1>
MB FABCGTI V02
236 OF 365
P3V3_OCP_SFF_R
P3V3_AUX
P3V3_OCP_SFF P3V3_OCP_SFF_R
P3V3_AUX
P3V3_E1S_0_RP3V3_E1S_0
P3V3_AUX
P3V3_AUX
P3V3_E1S_0_R
P3V3_AUX
358 82
358 82
252
252
252
252
POWER MONITOR WILL CHANGE TO AL000230001
1K
1/16W
CHIP0 E1S_0_P3V3_P12V_ADC_R_ALERT
CHIP
NC_INA230_2_NC5
NC_INA230_2_NC4
NC_INA230_2_NC1
E1S_0_P3V3_ADC_ALERT_R
OCP_SFF_P3V3_P12V_ADC_R_ALERTOCP_SFF_P3V3_ADC_ALERT_R
POWER MONITOR (1/4)
1K
CHIP
1/16W
1%
0402LF
0402LF
1%
NC_INA230_1_NC5
NC_INA230_1_NC4
NC_INA230_1_NC3
NC_INA230_1_NC2
0402LF
SMB_INA230_1_3V3AUX_SCL_R SMB_INA230_1_3V3AUX_SCL_R1
CHIP1/16W
0402LF 0402
E MP TY
1/16W
CHIP
SMLF
ISL28022FRZ-T
SMB_INA230_2_3V3AUX_SDA_R1
SMB_INA230_2_3V3AUX_SCL_R1
NC_INA230_2_NC0
1/16W
10
X 7R
IC
0402
0402LF
X7R
10%
1%
4.7K
ISL28022FRZ-T
V S E NS E _P 3V 3_INA 230_2_INN
V S E NS E _P 3V 3_INA 230_2_INP
INA230_2_A1
V S E NS E _P 3V 3_INA 230_1_INN
INA230_1_A1
NC_INA230_1_NC0
NC_INA230_1_NC1
NC_INA230_2_NC2
0
5%
2W
0.002 1%
CHIP
2512LF
X7R
25V
10%
0402
0.1UF
0402LF4.7K 1/16W 1% CHIP
1% 0402LFE MP TY1/16W4.7K
1% 0402LF
CHIP
25V
10%
0.1UF
0402
1/16W
0402LF1%10
10%
0.1UF
25V
0402LF
2512LF
CHIP
1%0.002
2W
1/16W
0402
X 7R
10%
X7R
0402
10%
25V
0.1UF
10 0402LF
4.7K
0402LF0 CHIP
X7R
25V
0.1UF
IC
SMLF
INA230_2_A0
CHIP
1/16W
1%
1/16W 1%
1%
CHIP
4.7K
4.7K
1/16W 1% E MP TY
SMB_INA230_1_3V3AUX_SDA_R
25V
0.1UF
V S E NS E _P 3V 3_INA 230_1_INP
0402LF
0 5% CHIP
CHIP5%0
CHIP
SMB_INA230_2_3V3AUX_SCL_R
SMB_INA230_2_3V3AUX_SDA_R
0 5% CHIP
0402LF 1/16W
CHIP5%0
10
1/16W
NC_INA230_2_NC3
0402LF
1%
CHIP 0402LF
1/16W0402LF
INA230_1_A0
SMB_INA230_1_3V3AUX_SDA_R1
R3752
R3563
R3767
R3763
R3764
R3760
R3758
R3645
R3603
R3602
R3617
R3616
13
12
9
11
TH
4
5
16
15
14
8
7
6
10
3
1
2
13
12
9
11
TH
4
5
16
15
14
8
7
6
10
3
1
2
U276
U266
BOM NOTE:
TH_GND
GND
NC5
NC4
NC3
NC2
NC1
NC0
EXT_CLK||INT
VINM
VINP
VBUS
SDA||SMBDAT
SCL|||SMBCLK
A0
A1
VCC
TH_GND
GND
NC5
NC4
NC3
NC2
NC1
NC0
EXT_CLK||INT
VINM
VINP
VBUS
SDA||SMBDAT
SCL|||SMBCLK
A0
A1
VCC
21R3754
21R3756
21R3601
21R3600
2
1
2
1
2
1
21
2
1
21
21
21 2
1
21
2
1
21
21
2
1
2
1
2
1
2
1
21
21
21
21
2
1
21
1
SHEETDATE
23
7 3 2 16 5 4
E
A
B
C
E
D
C
B
A
7 6 5 4
D
DEPARTMENT
SIZE
PROJECT DOCUMENT NUMBER REV
REVIEWER
DESIGNER
BI
IN
OUT
BI
IN
OUT
R4094
R4093
R3751
C2069
C2071
C2067
R3627 R3628
C2027
C2024
C2015
C



ADDRESS : 0X86 (8-BIT)
0X43 (7-BIT)
20210929 MODIFY FOR GT
ADDRESS : 0X88 (8-BIT)
0X44 (7-BIT)
0X45 (7-BIT)
ADDRESS : 0X8A (8-BIT)
20211130 ADD R4090,R4091,R4092 PU TO P3V3_AUX
Thu Aug 24 14:09:16 2023<NAME_2>
<NAME_1>
MB FABCGTI V02
237 OF 365
P3V3
P3V3_AUX
P3V3_AUX
P3V3_AUX
P12V_SCM_R
P3V3_M2_0
P3V3
P3V3_AUX
P3V3_OCP_V3_2_R
P3V3_OCP_V3_2
P3V3_AUX
P3V3_AUX
P12V_SCM_R
P12V_SCM
P3V3_OCP_V3_2_R
P3V3_AUX
P3V3_AUX
358 82
82
252
252
252
252
252
252
82
POWER MONITOR WILL CHANGE TO AL000230001
0402LF OCP_V3_2_P3V3_P12V_ADC_R_ALERT0
M2_0_P3V3_ADC_ALERT
CHIPOCP_V3_2_P3V3_ADC_ALERT_R
NC_INA230_3_NC0
NC_INA230_3_NC1
NC_INA230_3_NC2
NC_INA230_3_NC3
NC_INA230_3_NC4
NC_INA230_3_NC5
POWER MONITOR (2/4)
SMB_INA230_5_3V3AUX_SDA_R
SMB_INA230_5_3V3AUX_SCL_R
1K
1%
0402LF
1/16W
CHIP
1K
1/16W
1%
0402LF
CHIP
1K
0402LF
1%
1/16W
CHIP
CHIP
SMB_INA230_3_3V3AUX_SCL_R1
0402LF
NC_INA230_5_NC2
NC_INA230_5_NC1
P12V_SCM_ADC_ALERT_R
ISL28022FRZ-T
0
1/16W
E MP TY1/16W
V S E NS E _P 12V _INA 230_3_INN
10%
0402LF
V S E NS E _P 12V _INA 230_3_INP
NC_INA230_5_NC5
NC_INA230_5_NC4
NC_INA230_5_NC3
NC_INA230_5_NC0
0402
1/16W
4.7K
0402LF
INA230_5_A1
M2_0_P3V3_ADC_ALERT_R
NC_INA230_4_NC0
NC_INA230_4_NC1
SMB_INA230_4_3V3AUX_SDA_R1
SMB_INA230_4_3V3AUX_SCL_R1
ISL28022FRZ-T
SMLF
V S E NS E _P 12V _INA 230_4_INP
V S E NS E _P 12V _INA 230_4_INN
IC
CHIP
INA230_4_A1
INA230_4_A0
0402LF
CHIP
1/16W
1%
4.7K
CHIP
CHIP
CHIP
1/16W
0402LF
0 5% CHIP
1/16W
SMB_INA230_5_3V3AUX_SCL_R1
CHIP5%0 SMB_INA230_5_3V3AUX_SDA_R1
1/16W
SMB_INA230_4_3V3AUX_SCL_R
SMB_INA230_4_3V3AUX_SDA_R
1%
0
0402LF
CHIP5%0
10
SMB_INA230_3_3V3AUX_SDA_R
SMB_INA230_3_3V3AUX_SCL_R
NC_INA230_4_NC3
P12V_SCM_ADC_ALERT
V S E NS E _P 12V _INA 230_5_INN
V S E NS E _P 12V _INA 230_5_INP
2W
1%0.002
CHIP
2512LF
X7R
0402
10%
25V
0.1UF
10 1%
1/16W
10 1%
0.1UF
25V
X 7R
0402
1% E MP TY4.7K 1/16W
1%4.7K 1/16W CHIP
1/16W
0
0402LF
5%
X7R
10%
25V
0.1UF
0402
IC
SMLF
CHIP
2512LF
2W
0.002 1%
CHIP2W
0.002 1%
CHIP
1%
1/16W
1%
4.7K
CHIP
0402LF
0402LF
E MP TY
1%
0.1UF
25V
10%
X 7R
0402
25V
0.1UF
SMLF
0402LF4.7K 1% E MP TY
X7R
0.1UF
CHIP0
4.7K 1% 0402LFE MP TY
0402LF1%
CHIP
0402LF10 1%
1/16W
10%
25V
X7R
0.1UF
0402
IC1%4.7K
0402
10%
25V
0 0402LFCHIP
4.7K CHIP
CHIP
10 1%
CHIP
0402
X7R
10%
25V
0.1UF
0402LF
0402LF
1/16W 1%
1/16W
1/16W
1/16W
1/16W
0402LF
0402LF
2512LF
0402LF
0402LF
0402LF
5%0
5%
0402
X 7R
10%
1/16W
INA230_3_A0
INA230_3_A1
5%
CHIP
1/16W
0402LF
ISL28022FRZ-T
0.1UF
4.7K
X7R
NC_INA230_4_NC4
NC_INA230_4_NC2
25V
10%
INA230_5_A0
10
CHIP
NC_INA230_4_NC5
SMB_INA230_3_3V3AUX_SDA_R1
R3559
R3561
R3560
R3571
R3570
R3609
R3608
R3620
R3612
R3613
R3578
R3579
R3610
R3611
R3574
R3575
13
12
9
11
TH
4
5
16
15
14
8
7
6
10
3
1
2
13
12
9
11
TH
4
5
16
15
14
8
7
6
10
3
1
2
13
12
9
11
TH
4
5
16
15
14
8
7
6
10
3
1
2
U263
U265
U264
BOM NOTE:
TH_GND
GND
NC5
NC4
NC3
NC2
NC1
NC0
EXT_CLK||INT
VINM
VINP
VBUS
SDA||SMBDAT
SCL|||SMBCLK
A0
A1
VCC
TH_GND
GND
NC5
NC4
NC3
NC2
NC1
NC0
EXT_CLK||INT
VINM
VINP
VBUS
SDA||SMBDAT
SCL|||SMBCLK
A0
A1
VCC
TH_GND
GND
NC5
NC4
NC3
NC2
NC1
NC0
EXT_CLK||INT
VINM
VINP
VBUS
SDA||SMBDAT
SCL|||SMBCLK
A0
A1
VCC
21R3577
21R3576
21R3572 21R3573
21R3568
21R3569
2
1
2
1
2
1
21
2
1
21
21
2
1
21
21
2
1
2
1
21
21
21
2
1
2
1
2
1
2
1
2
1
2
1
21
2
1
21
21
21
21
2
1
21
2
1
2121
21
21
2
1
1
SHEETDATE
23
7 3 2 16 5 4
E
A
B
C
E
D
C
B
A
7 6 5 4
D
DEPARTMENT
SIZE
PROJECT DOCUMENT NUMBER REV
REVIEWER
DESIGNER
OUT
OUT
IN
BI
OUT
IN
BI
BI
IN
R4092
R4090
R4091
R3633
C2017
C2020
C2012
R3635
R3634
R3622 R3624
R3621 R3623
C2022
C2021
C2014
C2019
C2013
C2018
C



FRU ADDR: 0XA0 (8-BIT) / 0X50 (7-BIT)
CPU FRU EEPROM
FRU ADDR: 0XA2 (8-BIT) / 0X51 (7-BIT)
FRU EEPROM
TBC
20210603 MODIFY FOR GT
Thu Aug 24 14:09:17 2023<NAME_2>
<NAME_1>
MB FABCGTI V02
238 OF 365
P3V3_AUXP3V3_AUX
P3V3_AUX
P3V3_AUX
P3V3_AUX P3V3_AUX
251239
239251
239251
251239
CHIP 0402LF
CHIP
1K
0402LF
CHIP
1/16W
1%
MB_FRU_ADDR2
MB_FRU_ADDR0
EMPTY
1%
M24128-BWMN6TP
SMLF
10K
1%
0402LF
EMPTY
1/16W
0402
0.1UF
25V
X 7R
10%
0402LF
4.7K
5%
1/16W
EMPTY
0402LF
EMPTY
1/16W
5%
4.7K
IC
0402LF
EMPTY
1/16W
1%
10K
1/16W
0402LF
CHIP
1%
1K
1%
0402LF
1/16W
CHIP
1K
0402LF
EMPTY
1/16W
1%
1K
1/16W
1%
0402LF
CHIP
10K
0 5% CHIP
0 5% CHIP
0 CHIP5%
5% CHIP0
1/16W
CHIP
0402LF
1K
S MB _CP U_FRU_3V 3A UX _S CL
S MB _CP U_FRU_3V 3A UX _S DA
CPU_FRU_ADDR0
1K
1%
S MB _FRU_3V 3A UX _S CL
S MB _FRU_3V 3A UX _S DA
P D_CP U_FRU_W P
MB_FRU_ADDR1
0402LF
5%
4.7K
5%
1/16W
4.7K
X 7R
10%
25V
0.1UF
0402
1K
1/16W 1/16W
CHIP
1%
0402LF
1/16W
0402LF
10K
1%
EMPTY
0402LF
EMPTY
1/16W
10K
1% 1%
10K
1%
1K
0402LF
EMPTY
1/16W
IC
M24128-BWMN6TP
SMLF
MB FRU
CPU_FRU_ADDR2
CPU_FRU_ADDR1
EMPTY
S MB _FRU_3V 3A UX _S DA
S MB _FRU_3V 3A UX _S CL
1/16W
0402LF 0402LF
1/16W
S MB _FRU_3V 3A UX _R1_S DA
S MB _FRU_3V 3A UX _R1_S CL
P D_MB _FRU_W P
7
4
8
5
6 3
2
1
7
4
8
5
6 3
2
1
U1
U64
E0
E1
E2
VSSSDA
SCL
WC#
VCC
E0
E1
E2
VSSSDA
SCL
WC#
VCC
21R86
21R85
21R125
21R121
2
1
2
1
2
1
2
1
2
1
2
1
2
1
R4
2
1
R24
2
1
2
1
2
1
R26
2
1
R43
2
1
2
1
2
1
2
1
2
1
2
1
2
1
2
1
1
SHEETDATE
23
7 3 2 16 5 4
E
A
B
C
E
D
C
B
A
7 6 5 4
D
DEPARTMENT
SIZE
PROJECT DOCUMENT NUMBER REV
REVIEWER
DESIGNER
IN
BI
BI
IN
R69
R68
R54 R62
R60
R44
C1 R52
R721
R722
R710
C629
R714 R718
R713 R717
C



239 OF 365
V02GTI MB FABC
<NAME_1>
<NAME_2> Thu Aug 24 10:15:37 2023Blank
1
SHEETDATE
23
7 3 2 16 5 4
E
A
B
C
E
D
C
B
A
7 6 5 4
D
DEPARTMENT
SIZE
PROJECT DOCUMENT NUMBER REV
REVIEWER
DESIGNER
C



20211206 ADD FOR EMI
20210616 MODIFY FOR GT
Thu Aug 24 14:09:17 2023
MB FABC
240 OF 365
V02GTI
<NAME_1>
<NAME_2>
P12V_PSU
P3V3_AUX
P3V3_AUX
P3V3_AUX
P3V3_AUX
P3V3_AUX
EMPTY
1K
1%
HPDB_HSC_PWRGD
FM_GPU_HSC_EN_BUF
20%
16V
CHIP
5%0
241
242
269
242
80
241
241
241
241
241
82
150243
258
80132139246251253
241
241
241
150151 241
150151
130
242
SMB_FAN_3V3AUX_BUF_R_SCL
0402LF
1/16W
CHIP PDB_PRSNT_R_N
FM_FAN_PWR_EN
SMB_FAN_3V3AUX_BUF_R_SDA
5%
CHIP
0.1UF
22UF
HPDB_HSC_PWRGD_R
FM_GPU_HSC_EN_BUF_R1
C0805
5%
FM_AC_PWR_BTN_PDB_N
FM_GPU_HSC_EN_BUF_R1
FM_FAN_PWR_EN_R
CHIP
0
FM_FAN_PWR_EN_R
EMPTY
CHIP
0
0
5%
PDB_PRSNT_N
4.7K4.7K
5%
1/16W
EMPTY
HPDB_HSC_PWRGD_R
FM_PDB_BUF_EN_R1_N
CHIP
4.7K
5%
FM_PDB_BUF_EN_R_N
0
FM_AC_PWR_BTN_PDB_N
TP_J45_A1
RST_SMB_SWITCH_R_N
FM_AC_PWR_BTN_R_N CHIP5%0
5%
P3V3_PDB_AUX_ADC
RST_SMB_SWITCH_N
0.1UF
0.1UF EMPTY
0.1UF EMPTY
CHIP
IO
THLF
CONN60_10106263-6003K02LF
SMB_FAN_3V3AUX_BUF_R_SCL
1%
RST_SMB_SWITCH_R_N
PDB_PRSNT_N
33.2
POWER CONNECTOR/ISOLATED
SMB_FAN_3V3AUX_BUF_SDA
SMB_FAN_3V3AUX_BUF_SCLCHIP1%33.2
CHIP1%SMB_FAN_3V3AUX_SDA SMB_FAN_3V3AUX_R_SDA SMB_FAN_3V3AUX_BUF_R_SDA
0.1UF EMPTY
0.1UF EMPTY
0402LF 1/16W
E MP TY5%0
0 E MP TY
CHIP33.2
1% CHIP33.2
0402
0.1UF
10%
25V
X 7R
LTC4307CMS8
IC
1/16W
SMB_FAN_3V3AUX_SCL
0 5% CHIP
SMLF
5%
0
SMB_FAN_3V3AUX_R_SCL
MB_PDB_SMB9_R_EN
2N7002K
IC
SMLF
CHIP
1K
1%
1/16W
CHIP
0402LF
FM_PDB_BUF_EN_R1
0402LF
PWRGD_P3V3_AUX_PDB_BUF
0402LF
EMPTY
0402LF
5%
1/16W
EMPTY
241
241
241
241
241
241
G
S D
C1115
R1526
C8011
R8102
R3114
R3113
C67
C66
C65
C64
C74
R2905
R2906
R2807R2805
R2801
R2800
R2812
R2811
R2796
C1751
R2793
R2803
R2802
P6_8
P6_7
P6_6
P6_5
P6_4
P6_3
P6_2
P6_1
P5_8
P5_7
P5_6
P5_5
P5_4
P5_3
P5_2
P5_1
P4_8
P4_7
P4_6
P4_5
P4_4
P4_3
P4_2
P4_1
P3_8
P3_7
P3_6
P3_5
P3_4
P3_3
P3_2
P3_1
P2_8
P2_7
P2_6
P2_5
P2_4
P2_3
P2_2
P2_1
P1_8
P1_7
P1_6
P1_5
P1_4
P1_3
P1_2
P1_1
D3
D2
D1
C3
C2
C1
B3
B2
B1
A3
A2
A1
8
76
23
54
1
G
S D
J45
U192
U190
POWER
SIGNAL
D3
C3
B3
A3
P6_8
P6_7
P6_6
P6_5
P6_4
P6_3
P6_2
P6_1
P3_8
P3_7
P3_6
P3_5
P3_4
P3_3
P3_2
P3_1
P5_8
P5_7
P5_6
P5_5
P5_4
P5_3
P5_2
P5_1
D1
C1
B1
A1
P4_8
P4_7
P4_6
P4_5
P4_4
P4_3
P4_2
P4_1
P2_8
P2_7
P2_6
P2_5
P2_4
P2_3
P2_2
P2_1
P1_8
P1_7
P1_6
P1_5
P1_4
P1_3
P1_2
P1_1
D2
C2
B2
A2
READY
SDA_OUT
SCL_OUT
VCC
GND
SDA_IN
SCL_IN
ENABLE
S
G
D
2
1
21
2
1
R2950
2
1
R9000
21
21
21
21
21
21
21
21
21
21
21
2
1
2
1
21
21
21
21
21
2
1
2
1
R2794
21
21
21
1
SHEETDATE
23
7 3 2 16 5 4
E
A
B
C
E
D
C
B
A
7 6 5 4
D
DEPARTMENT
SIZE
PROJECT DOCUMENT NUMBER REV
REVIEWER
DESIGNER
OUT
OUT
IN
OUT
OUT
OUT
OUT
OUT
OUT
IN
OUT
OUT
IN
BIBI
IN
IN
IN
BI
IN
ININ
C



20210616 MODIFY FOR GT
OUT PUT IS PUSH PULL MODE
20211201 ADD BUF TO PDB
Thu Aug 24 14:09:17 2023<NAME_2>
<NAME_1>
MB FABCGTI V02
241 OF 365
P3V3_AUX
P3V3_AUX
P3V3_AUX
P3V3_AUX
P3V3_AUX
P3V3_AUX
P3V3_AUX
P3V3_AUX
81
241
81
126
241
24185
1/16W
PJT138K
SMLF
54.9K
0402LF
CHIP
1/16W
74LVC2G07DW-7
SMLF
0402
X7R
10%
25V
0.1UF
1%
100K
0402LF
CHIP
10%
25V
X 7R
0.1UF
0402
0402LF CHIP
33.2
4.7K
5%
1/16W
EMPTY
0402LF
4.7K
5%
0402LF
EMPTY
1/16W
0402LF
1%
1/16W
CHIP
100K
1/16W
EMPTY
5%
0402LF
4.7K
SMLF
74LVC1G08W5-7
IC
1/16W
CHIP5%0
0402LF
IC
0.1UF
0402
25V
10%
X 7R
0
0402LF 1/16W
CHIP5%
4.7K
5%
EMPTY
1/16W
0402LF
4.7K
5%
0402LF
1/16W
CHIP
CHIP0402LF
33.2
0402LF
100K
1%
1/16W
CHIP
1%
EMPTY
0402LF
1/16W
IC
PJT138K
5%
4.7K
IC
SMLF
POWER CONNECTOR/ISOLATED
HPDB_HSC_PWRGD_ISO
HPDB_HSC_PWRGD_N
HPDB_HSC_PWRGD
FM_GPU_HSC_EN
GPU_PRSNT GPU_PRSNT_R
FM_GPU_HSC_EN_BUF_R
PWRGD_P3V3_AUX_PDB_BUF_R
FM_GPU_HSC_EN_BUF
PWRGD_P3V3_AUX_PDB_BUFPWRGD_P3V3_AUX_PDB_RPWRGD_P3V3_AUX_PDB
G2
G1
S2 D2
D1S1
R4554
R4553
R4264
R3770
R2940
R2946
5
2
52
43
61
4
5
3
2
1
4 3
1 6
Q145
Q145
21R4266
U308
U278
21R2944
VCCGND
2Y
1Y
2A
1A
VCC
Y
GND
B
A
2
1
2
1
2
1
2
1
2
1
2
1
2
1
21
2
1 C69
21
2
1
2
1
2
1
2
12
1 C1775
1
SHEETDATE
23
7 3 2 16 5 4
E
A
B
C
E
D
C
B
A
7 6 5 4
D
DEPARTMENT
SIZE
PROJECT DOCUMENT NUMBER REV
REVIEWER
DESIGNER
IN
OUT
IN
OUTIN
IN
OUT
C70R4551
R4552
R4265
R4268
R2948
R2941
C



20210616 MODIFY FOR GT
Thu Aug 24 14:09:17 2023<NAME_2>
<NAME_1>
MB FABCGTI V02
242 OF 365
P3V3_AUX P3V3_AUX
P12V_AUX
P12V_AUX
P3V3_AUX
FM_AC_PWR_BTN_PLD_N
0402LFEMPTY
0.1UF
SMLF
10%
EMPTY
25V
10%
EMPTY
C0402
1/16W
0
FM_AC_PWR_BTN_PLD_ISO_R_N
EMPTY
5%
0402LF
EMPTY
0402
1UF
8.45K
1%
EMPTY
25V
2N7002K
FM_P12V_HSC_EN_R
P12V_AU X_BLEED IN G
0402LF 1/16W
5%
IC
SMLF
CHIP
0402LF 1/16W
0 5%
1/16W
CHIP
1%
100K
0402LF
4.7K
5%
0402LF
CHIP
1/16W
MB0_P12V_STBY_PWRGD
PSU POWER CONNECTORS
IC
2N7002K
SMLF
FM_P12V_HSC_EN_N FM_P12V_HSC_EN_R_N
CHIP0
0402LF
74LVC2G07DW-7
1/16W
1/16W
FM_AC_PWR_BTN_R_N
5%0N C _U 8004_2Y
CHIP
0402LF
FM_AC_PWR_BTN_PLD_ISO_N
1/16W
1%
1K
254 189 268 263
241 150 81
G
G
S D
S D
52
43
61
G
G
S D
S D
U8004
Q54
U158
S
G
D
VCCGND
2Y
1Y
2A
1A
S
G
D
2
1
2
1
2
1
2
1
2121
2
1
2
1
21R2529
21R2531
1
SHEETDATE
23
7 3 2 16 5 4
E
A
B
C
E
D
C
B
A
7 6 5 4
D
DEPARTMENT
SIZE
PROJECT DOCUMENT NUMBER REV
REVIEWER
DESIGNER
OUTIN
IN
R8106
R8103
C8012
C8013
R8105R8104
R2530
R2528
C



Thu Aug 24 10:15:40 2023 243 OF 365
GTI MB FABC
<NAME_2>
<NAME_1>
V02Blank
1
SHEETDATE
23
7 3 2 16 5 4
E
A
B
C
E
D
C
B
A
7 6 5 4
D
DEPARTMENT
SIZE
PROJECT DOCUMENT NUMBER REV
REVIEWER
DESIGNER
C



Thu Aug 24 10:15:41 2023<NAME_2>
<NAME_1>
MB FABCGTI V02
244 OF 365Blank
1
SHEETDATE
23
7 3 2 16 5 4
E
A
B
C
E
D
C
B
A
7 6 5 4
D
DEPARTMENT
SIZE
PROJECT DOCUMENT NUMBER REV
REVIEWER
DESIGNER
C



PCA9539 ADDR: 0XE8 (8-BIT) / 0X74 (7-BIT)
20211130 POP R3499,R3516,R3517,R3518
Thu Aug 24 14:09:18 2023<NAME_2>
<NAME_1>
MB FABCGTI V02
245 OF 365
P3V3_AUX
P3V3_AUX
P3V3_AUX
P3V3_AUX
176178235
246
246
246
246
246
246
246
246
246
246
246
246
130
246
246
246
246
246
246
246
246
246
246
246
246
246
246
121123
251
121123
246
251
121123
121123
123
12681
12580
123
12581
12381
123
12581
246
246
246
246
80132139241251253
246
246
246
BMC - PCA9539
SMLF
IC
PCA9539RPW
0 5% CHIP
0402
0.1UF
X 7R
25V
10%
5%0 CHIP
0 5% CHIP
CHIP5%0
CHIP0 5%
0 CHIP5%
5% CHIP0
5%0 CHIP
5%0 CHIP
0 5% CHIP
0 5% CHIP
5% CHIP0
CHIP0 5%
0 5% CHIP
CHIP5%0
0402LF
E MP TY
4.7K
1/16W
5%
0402LF
1%
10K
EMPTY
1/16W
0 5% CHIP
0402LF
EMPTY
1%
1K
1/16W
0402LF
1/16W
1%
1K
CHIP
0402LF
EMPTY
1K
1/16W
1%
0402LF
1/16W
1%
1K
CHIP
R ST_U SB_H U B_N
R ST_SW B_BIC _N
TP_TC A9539_0_P0_2
TP_TC A9539_0_P0_3 PRSNT_CABLE_GPU_A1_ISO_R1_N
GPU _PEX_STR AP1_R
GPU _PEX_STR AP0_R
GPU _BASE_ID 1_R
GPU _BASE_ID 0_R
PRSNT_CABLE_SWB_B1_ISO_R_N
PRSNT_CABLE_GPU_A2_ISO_R1_N
SMB_IOEXP_3V3AU X_SD A_R 1
SMB_IOEXP_3V3AU X_SC L_R 1
TC A9539_0_AD D 0
PRSNT_CABLE_GPU_A3_ISO_R_N
RST_SWB_BIC_R_N
SMB_IOEXP_3V3AUX_SCL_R1
SMB_IOEXP_3V3AUX_SDA_R1
GPU_BASE_ID0_R
GPU_BASE_ID1_R
GPU_PEX_STRAP1_R
PRSNT_CABLE_SWB_B2_ISO_R_N
PRSNT_CABLE_GPU_A2_ISO_R1_N
PRSNT_CABLE_GPU_A3_ISO_R_N
PRSNT_CABLE_GPU_B3_ISO_R1_N
GPU_PRSNT_N_ISO_R1
GPU_PEX_STRAP0_R
PRSNT_SWB_ISO_R1_N
PRSNT_CABLE_SWB_B1_ISO_R_N
PRSNT_CABLE_GPU_A1_ISO_R1_N
GPU_BASE_ID1
SMB_IOEXP_3V3AUX_SDA
GPU_BASE_ID0
RST_SWB_BIC_N
SMB_IOEXP_3V3AUX_SCL
GPU_PEX_STRAP1
GPU_PEX_STRAP0
PRSNT_CABLE_SWB_B1_ISO_N
GPU_PRSNT_N_ISO
PRSNT_CABLE_GPU_B3_ISO_N
PRSNT_CABLE_GPU_A3_ISO_N
PRSNT_CABLE_GPU_A1_ISO_N
PRSNT_SWB_ISO_N
PRSNT_CABLE_SWB_B2_ISO_N
PRSNT_CABLE_GPU_A2_ISO_N
PRSNT_CABLE_SWB_B2_ISO_R_N
P U_U181_INT
TC A9539_0_AD D 1
GPU_PRSNT_N_ISO_R1
PRSNT_SWB_ISO_R1_N
P U_RS T_S MB _U181_NRS T_S MB _S W ITCH_N
TC A9539_0_AD D 0
TC A9539_0_AD D 1
PRSNT_CABLE_GPU_B3_ISO_R1_N
R2982
R2848
R2983
R3499
R3516
R3517
R3518
R9001
R9011
R9018
R9013
R9019
R8004
R9010
R9012
R2922
R2695
R2696
R2693
R2694
12 24
23
22
3
20
19
18
17
16
15
14
13
11
10
9
8
7
6
5
4
1
2
21
U181
VDD
SDA
SCL
A0
IO1_7
IO1_6
IO1_5
IO1_4
IO1_3
IO1_2
IO1_1
IO1_0
VSS
IO0_7
IO0_6
IO0_5
IO0_4
IO0_3
IO0_2
IO0_1
IO0_0
RESET
A1
INT
21
2
1C1713
21
21
21
21
21
21
21
21
21
21
21
21
21
21
2
1
21
2
1
2
1
2
1
2
1
2
1
1
SHEETDATE
23
7 3 2 16 5 4
E
A
B
C
E
D
C
B
A
7 6 5 4
D
DEPARTMENT
SIZE
PROJECT DOCUMENT NUMBER REV
REVIEWER
DESIGNER
OUT
OUT
OUT
OUT
IN
IN
IN
IN
IN
IN
IN
IN
IN
IN
BI
OUT
OUT
OUT
OUT
OUT
OUT
OUT
OUT
OUT
OUT
OUT
OUT
OUT
IN
OUT
OUT
IN
IN
IN
IN
IN
IN
IN
IN
IN
IN
IN
IN
IN
IN
IN
IN
IN
IN
IN
IN
R2923
R2921
C



Thu Aug 24 10:15:42 2023<NAME_2>
<NAME_1>
MB FABCGTI V02
246 OF 365Blank
1
SHEETDATE
23
7 3 2 16 5 4
E
A
B
C
E
D
C
B
A
7 6 5 4
D
DEPARTMENT
SIZE
PROJECT DOCUMENT NUMBER REV
REVIEWER
DESIGNER
C



20210818 MODIFY FOR GT
FROM CPLD
FROM OCP_12V_HSC PWRGD
FROM CPLD
FROM OCP_12V_HSC PWRGD
FROM OCP HSC ENABLE
FROM OCP HSC ENABLE
Thu Aug 24 14:09:20 2023<NAME_2>
<NAME_1>
MB FABCGTI V02
247 OF 365
P3V3_OCP_V3_2P3V3_OCP_V3_2
P3V3_OCP_SFFP3V3_AUX
P3V3_AUX
P3V3_OCP_SFF
137
140 141 142
81 83 140 141
136 134 135
137
142 140 141
131150151
150151
150151
150151
80 83 134 135
134 135 136
131
5%0 CHIP
X 7R
S MB _O CP _V 3_2_3V 3A UX _B UF_S CL
0402LF
CHIP
1/16W
E MP TY
HP_LVC3_OCP_V3_2_P12V_PWRGD
P3V3_OC P_V3_2_EN _R
P12V_OCP_SFF_BUF_EN_R
5%
H P_LVC 3_OC P_V3_2_R _EN
S MB _O CP _V 3_2_3V 3A UX _B UF_S DA
0402
10%
0.1UF
25VPCA9617ADP
P12V_OCP_V3_2_BUF_EN_R
0
E MP TY
0402LF
E MP TY
H P_LVC 3_OC P_V3_1_R _EN 0 5%
S MB _O CP _S FF_3V 3A UX _B UF_S CLS MB _O CP _S FF_3V 3A UX _S CL
S MB _O CP _S FF_3V 3A UX _S DA
S MB _O CP _V 3_2_3V 3A UX _S DA
S MB _O CP _V 3_2_3V 3A UX _S CL
SMBUS - ISOLATED
4.7K
5%
1/16W
0402LF
CHIP
1/16W
5%
4.7K
CHIP
X 7R
0402
25V
0.1UF
10%
0402
25V
X 7R
10%
0.1UF
IC
PCA9617ADP
SMLF
SMLF
10%
0402
X 7R
25V
0.1UF
0402LF
IC
5%
P3V3_OC P_SFF_EN _R
HP_LVC3_OCP_V3_1_P12V_PWRGD0402LF
S MB _O CP _S FF_3V 3A UX _B UF_S DA
0
5%
4.7K
CHIP5%
0
4.7K
5%
1/16W
CHIP
0402LF
5%
0
E MP TY
R1180
R1135
R3264
R3263
R3501R3500
81
63
72
4 5
81
63
72
4 5
U236
U235
GND
SCLB
SDABSDAA
SCLA
VCCBVCCA
EN
GND
SCLB
SDABSDAA
SCLA
VCCBVCCA
EN
21
21
R1522
21R1500
21
21
21
2
1
2
1
2
1
2
1
2
1
2
1
2
1
2
1
1
SHEETDATE
23
7 3 2 16 5 4
E
A
B
C
E
D
C
B
A
7 6 5 4
D
DEPARTMENT
SIZE
PROJECT DOCUMENT NUMBER REV
REVIEWER
DESIGNER
IN
IN
IN
IN
IN
OUT
BI
IN
OUT
BI
IN
IN
BI
BI
R3519 R3520
C1862C1860
C1861C1859
C



202120215 ADD R4603
20210607 U176 NEED CHANGE TO I3C BUFFER
20210607 MODIFY FOR GT
TBC
TBC
TBC
I3C FROM BMC
20211220 PO BYPASS U176
Thu Aug 24 14:09:20 2023<NAME_2>
<NAME_1>
MB FABCGTI V02
248 OF 365
P3V3_AUXP3V3_AUX
P3V3_AUXP3V3_AUX
P3V3_AUXP3V3_AUX
P3V3_AUX
P3V3_AUX
116
150151
80249
116
122
122
119
119
122
122
82249
150151
150151
82249
251
80249
251
150151
150151
150151
0402LF 1/16W
27 5% CHIP I3C_B MC_S W B _B UF_S DA
0402LF
1%I3C_B MC_S W B _S CL
S MB _B MC_S W B _E N
0402LF
CHIP5%0
0 CHIP5%
1/16W0402LF
CHIP5%0
E MP TY
1/16W0402LF
5%0
E MP TY0
0402LF
CHIP
1/16W
10K
1%
CHIP0
CHIP
0402LF
0
1/16W
5%
10%
0.1UF
25V
X 7R
0402
0
0402LF
5% CHIP
1/16W
CHIP0 5%
0402LF
54.9K
1%
1/16W
CHIP
1/16W
0402LF
54.9K
1%
CHIP
0402LF 1/16W
1%33.2 CHIP
33.2 1% CHIP
0402LF
CHIP5%0
1/16W
CHIP5%0
5%0 CHIP
0 E MP TY
E MP TY0
1/16W0402LF
5%
5% CHIP0
0.1UF
25V
10%
X 7R
0402
1/16W
CHIP
5%
0402LF
2.2K
1%33.2 CHIP
2.2K
5%
0402LF
1/16W
CHIP
1/16W
1% CHIP
0402LF
33.2
0.1UF
25V
10%
X 7R
0402
5%
1/16W
EMPTY
4.7K
5%
4.7K
1/16W
EMPTY
0402LF
1/16W
0
0402LF
E MP TY5%
E MP TY0
33.2 CHIP
1% CHIP33.2
CHIP33.2 1%
0402LF 1/16W
0402
0.1UF
X 7R
25V
10%
CHIP
0402LF
54.9K
1%
1/16W
CHIP
1/16W
1%
54.9K
0402LF
I3C_B MC_S W B _R_S CL I3C_B MC_S W B _B UF_S CL
SMLF
LTC4307CMS8
IC
LTC4307CMS8
IC
SMLF
EMPTY
SMLF
LTC4307CMS8
1%
SMLF
LTC4307CMS8
IC
S MB _B MC_S W B _B UF_R_S CL
S MB _B MC_S W B _B UF_R_S DA
S MB _B MC_G P U_E N_R1
S MB _1_B MC_G P U_R_S DA
S MB _1_B MC_G P U_R_S CL S MB _1_B MC_G P U_B UF_S CL
S MB _1_B MC_G P U_B UF_S DAS MB _1_B MC_G P U_B UF_R_S DA
S MB _1_B MC_G P U_B UF_R_S CL
I3C_B MC_S W B _B UF_R_S DA
I3C_B MC_S W B _B UF_R_S CL
S MB _B MC_S W B _B UF_S CL
S MB _B MC_S W B _B UF_S DA
S MB _2_B MC_G P U_B UF_S DA
S MB _2_B MC_G P U_B UF_S CL
S MB _B MC_G P U_E N
S MB _B MC_S W B _R_S DA
S MB _B MC_S W B _R_S CL
S MB _B MC_S W B _E N_R
S MB _2_B MC_G P U_B UF_R_S CL
S MB _2_B MC_G P U_B UF_R_S DA
S MB _1_B MC_G P U_S CL
S MB _1_B MC_G P U_S DA
S MB _B MC_G P U_E N_R3
SMB_2_BMC_GPU_R_SDA
SMB_2_BMC_GPU_R_SCL
S MB _B MC_G P U_E N
S MB _B MC_S W B _S CL
S MB _B MC_S W B _E N
S MB _B MC_S W B _S DA
S MB _2_B MC_G P U_S DA
SMBUS - PCIE3 SMBUS
S MB _2_B MC_G P U_S CL
S MB _B MC_S W B _E N_R2
CHIP33.2
0 5% CHIP
0402LF 1/16W
10K
1%
CHIP
1/16W
I3C_B MC_S W B _R_S DAI3C_B MC_S W B _S DA 0 5% CHIP 0402LF
R2669R2667
R3523
R3105
R3106
R3109
R3110
R3108
R3107
R2674R3111
R2897
R2898
R2675
R2893
R2894
R2670R2668
R2671
R2672
R2899
R2724
R2705
R2707
R2991
R2990
R2725
R2706
R2676
R3112
R2986
R2987
R2992
8
76
23
54
1
8
76
23
54
1
8
76
23
54
1
8
76
23
54
1
U175
U194
U176
U200
READY
SDA_OUT
SCL_OUT
VCC
GND
SDA_IN
SCL_IN
ENABLE
READY
SDA_OUT
SCL_OUT
VCC
GND
SDA_IN
SCL_IN
ENABLE
READY
SDA_OUT
SCL_OUT
VCC
GND
SDA_IN
SCL_IN
ENABLE
READY
SDA_OUT
SCL_OUT
VCC
GND
SDA_IN
SCL_IN
ENABLE
2121
2
1
2
1
2
1
21
21
21
21
21
2
1
2
1
2
1
21
2
1
21
2
1
2
1
21
21
21
21
21
21
21
21
2
1
2
1
21
21
2
1
21
21
21
21
2
1
21
21
21
21
21
2
1
1
SHEETDATE
23
7 3 2 16 5 4
E
A
B
C
E
D
C
B
A
7 6 5 4
D
DEPARTMENT
SIZE
PROJECT DOCUMENT NUMBER REV
REVIEWER
DESIGNER
BI
BI
OUT
BI
OUT
BI
OUT
BI
OUT
IN
BI
IN
BI
IN
IN
BI
IN
IN
IN
IN
R3524C1766
C1708
C1707
R3522R3521C1796
R4603
R2666
C



Thu Aug 24 10:15:45 2023<NAME_2>
<NAME_1>
MB FABCGTI V02
249 OF 365Blank
1
SHEETDATE
23
7 3 2 16 5 4
E
A
B
C
E
D
C
B
A
7 6 5 4
D
DEPARTMENT
SIZE
PROJECT DOCUMENT NUMBER REV
REVIEWER
DESIGNER
C



20210604 MODIFY FOR GT
PCA9548 ADDR: 0XE0 (8-BIT) / 0X70 (7-BIT)
Thu Aug 24 14:09:21 2023<NAME_2>
<NAME_1>
MB FABCGTI V02
250 OF 365
P3V3_AUX
P3V3_AUX
P3V3_AUX
P3V3_AUX
150 251
150 251
251 252
239 251
251 239
251
251
251
251
251148
148251
176178179251
251
251
251 252
251 148
239 251
249 251
179 251 176 178
176 178 179 251
251 148
148 251
251148
148251
251246
179251176178
251246
148 251
251 249
251 246
251 246
251 252
251 252
150 251
150 251
251 249
249 251
251 239
80132139241246253
S MB _B MC_S W B _S CL_R4
S MB _B MC_S W B _S DA _R4
S MB _P CIE 0_3V 3A UX _S DA
S MB _P CIE 0_3V 3A UX _S CL
CHIP
CHIP
5%0
S MB _INA 230_3V 3A UX _S CL_R
S MB _INA 230_3V 3A UX _S DA _R 5%0 CHIP
0 5% CHIP
5%
5%
0
S MB _INA 230_3V 3A UX _S CL
S MB _FRU_3V 3A UX _S DA
S MB _FRU_3V 3A UX _S CL
S MB _P CIE 0_3V 3A UX _S CL_R5
S MB _P CIE 0_3V 3A UX _S DA _R5
S MB _P CIE 0_3V 3A UX _S CL_R3
SMB_U SB_C PU 0_H U B1_SC L_R
SMB_U SB_C PU 0_H U B1_SD A_R
P U_RS T_S MB _P CIE 0_N
P CA 9548_P CIE 3_A DDR2
S MB _P CIE 0_3V 3A UX _S DA _R3
IC
PCA9548_PCIE3_ADDR0
PCA9548_PCIE3_ADDR1
PCA9548_PCIE3_ADDR2
IO_SLOT
1K
0402LF
CHIP
1/16W
1%
IO_SLOT 0402LF
1K
CHIP
1/16W
1%
IO_SLOT
1/16W
CHIP
1K
0402LF
1%
EMPTY
1%
0402LF
10K
1/16W
EMPTY
1%
0402LF
1/16W
10K
EMPTY
1/16W
0402LF
1%
10K
CHIP
CHIP
CHIP
CHIP
CHIP
CHIP
10%
25V
S MB _S E NS O R_E 1S _3V 3A UX _S CL
S MB _S E NS O R_E 1S _3V 3A UX _S DA
5%
S MB _IO E X P _3V 3A UX _S CL_R
S MB _IO E X P _3V 3A UX _S DA _R
SMB_U SB_C PU 0_H U B1_SD A
P CA 9548_P CIE 3_A DDR1
P CA 9548_P CIE 3_A DDR0
0402
S MB _INA 230_3V 3A UX _S DA
0402LF
S MB _S E NS O R_M2_P 1_3V 3A UX _S CL
S MB _FRU_3V 3A UX _S DA
S MB _B MC_S W B _S CL
CHIP
5%2.2K
2.2K
1/16W
0402LF
CHIP
CHIP
5%
0
S MB _P CIE 0_3V 3A UX _S CL_R
CHIP
SMB_USB_CPU0_HUB1_SCL
SMB_USB_CPU0_HUB1_SDA
1/16W0402LF
2.2K 5% CHIP
S MB _S E NS O R_E 1S _3V 3A UX _S CL
S MB _S E NS O R_E 1S _3V 3A UX _S DA
2.2K 5% CHIP
CHIP5%2.2K
1/16W0402LF
5%2.2K
2.2K
1/16W
1/16W
S MB _S E NS O R_M2_P 1_3V 3A UX _S CL
S MB _S E NS O R_M2_P 1_3V 3A UX _S DA
0
0
5%
S MB _IO E X P _3V 3A UX _S CL
SMB_U SB_C PU 0_H U B1_SC L
S MB _IO E X P _3V 3A UX _S DA
CHIP 0
10K
1%
1/16W
CHIP
0402LF
5% 0
CHIP
CHIP0 5%
5%
0
5%
5%
5%
0
1/16W
1/16W
CHIP S MB _S E NS O R_M2_P 1_3V 3A UX _S DA
S MB _B MC_S W B _S DA
S MB _IO E X P _3V 3A UX _S DA
S MB _IO E X P _3V 3A UX _S CL
S MB _INA 230_3V 3A UX _S DA
S MB _INA 230_3V 3A UX _S CL
S MB _P CIE 0_3V 3A UX _S DA
S MB _P CIE 0_3V 3A UX _S CL
S MB _P CIE 0_3V 3A UX _S DA _R
SMBUS - PCIE0 SMBUS
S MB _B MC_S W B _S DA
S MB _B MC_S W B _S CL
S MB _FRU_3V 3A UX _S CL
TCA9548APWR
SMLF
33.2
1/16W 0402LF
1%CHIP
1% 33.2
0
5%2.2K EMPTY
5%2.2K EMPTY
2.2K CHIP5%
CHIP5%2.2K
5% CHIP
0402LF
CHIP
CHIP5%
0402LF
2.2K 5% CHIP
2.2K 5%
0402LF
CHIP
5%2.2K CHIP
2.2K 5%
1/16W
2.2K 5% CHIP
0402LF
X 7R
0.1UF
05%
0
RS T_S MB _S W ITCH_N
S MB _FRU_3V 3A UX _S CL_R
S MB _FRU_3V 3A UX _S DA _R
R6212
R6211
R6201
R6200
R65
R55
R2566
R2703
R2704
R3580
R3581
R2565
R2204
R2205
R3396
R3395
R3582
R3583
R3535
R3536
R2985
R2984
R66
R67
R1090
R1089
R3394
R3393
R2968
R2967
R3527
R3526
R2268
24
23
19
17
15
13
10
8
6
4
22
20
18
16
14
11
9
7
5
3
12
21
2
1
U36
SD4
SC4
SD5
SC5
SD6
SC6
SD7
SC7
A2 SCL
SDA
VCC
GND
SC3
SD3
SC2
SD2
SC1
SD1
SC0
SD0
RESET#
A1
A0
21
21
2 1
2 1
2 1
2 1
21
21
21
21
21
21
21
21
2
1
21
2 1
2
1
2
1
2
1
2
1
2
1
2
1
2
1
1
SHEETDATE
23
7 3 2 16 5 4
E
A
B
C
E
D
C
B
A
7 6 5 4
D
DEPARTMENT
SIZE
PROJECT DOCUMENT NUMBER REV
REVIEWER
DESIGNER
OUT
OUT
BI
OUT
BI
IN
BI
OUT
BI
OUT
BI
OUT
OUT
OUT
OUT
OUT
OUT
OUT
OUT
OUT
OUT
OUT
OUT
OUT
OUT
OUT
IN
IN
IN
OUT
OUT
OUT
BI
BI
BI
IN
OUT
OUT
OUT
C106
R1822
R320R318R316
R587R319R317
C



20210622 MODIFY FOR GT
Thu Aug 24 14:09:21 2023<NAME_2>
<NAME_1>
MB FABCGTI V02
251 OF 365
358
358
358
358
358
358
238
238
237
237
238
251
251 237
237
238
238
238
1%
1/16W
CHIP33.2
0402LF
33.2 CHIP1%
0402LF
33.2 1%
1/16W
CHIP
33.2 1% CHIP
CHIP33.2 1%
0402LF 1/16W
1% CHIP33.2
SMB_INA230_7_3V3AUX_SCL_R
SMB_INA230_8_3V3AUX_SCL_R
SMB_INA230_8_3V3AUX_SDA_R
SMB_INA230_7_3V3AUX_SDA_R
SMB_INA230_6_3V3AUX_SCL_R
SMB_INA230_6_3V3AUX_SDA_R
1/16W
33.2
33.2
SMB_INA230_5_3V3AUX_SCL_R
SMB_INA230_5_3V3AUX_SDA_R
0402LF
33.2 1%
CHIP
SMB_INA230_2_3V3AUX_SDA_R
SMB_INA230_2_3V3AUX_SCL_R
SMB_INA230_3_3V3AUX_SCL_R
SMBUS - PCIE1 SMBUS
SMB_INA230_3V3AUX_SDA
SMB_INA230_3V3AUX_SCL SMB_INA230_1_3V3AUX_SCL_R
SMB_INA230_1_3V3AUX_SDA_R
0402LF
CHIP1%33.2
CHIP33.2 1%
0402LF
33.2 1% CHIP
33.2 1% CHIP
1%33.2
CHIP
CHIP1%
33.2 1%
0402LF 1/16W
1/16W
1/16W
SMB_INA230_4_3V3AUX_SDA_R
SMB_INA230_3_3V3AUX_SDA_R
SMB_INA230_4_3V3AUX_SCL_R
CHIP
0402LF
CHIP1%
CHIP1%
33.2
1/16W
21R1349
21R1348
21R1347
21R1346
21R1345
21R1344
21R3586
21R3587
21R3588
21R3589
21R3590 21R3591
21R3594
21R3595
21R3592
21R3593
1
SHEETDATE
23
7 3 2 16 5 4
E
A
B
C
E
D
C
B
A
7 6 5 4
D
DEPARTMENT
SIZE
PROJECT DOCUMENT NUMBER REV
REVIEWER
DESIGNER
OUT
BI
OUT
BI
BI
OUT
BI
OUT
OUT
IN
BI
OUT
BI
BI
OUT
BI
OUT
BI
C



20210929 MODIFY FOR GT
PCA9548 ADDR: 0XE0 (8-BIT) / 0X70 (7-BIT)
20211201 ADD R4269,R4270
Thu Aug 24 14:09:20 2023<NAME_2>
<NAME_1>
MB FABCGTI V02
252 OF 365
P3V3_AUX
P3V3_AUX
P3V3_AUX
P3V3_AUX
253 259
253 259
253 259
236 253
253 236
150 253
150 253
253 259
236 253
268
236253
253272236
236253272
253236
253236
236253
268
253 236
150 253
80132139241246251
253151
151253
253
253
253
253 236
236 253
253 236
236 253 272
151 253
253 272 236
253 151
236 253
150 253
253
253
253
CHIP5%0
CHIP0 5%
1/16W
5% CHIP
0402LF
2.2K
2.2K CHIP5% SMB_ADC_SDA_R
2.2K
SMB_ADC_SCL_R
1/16W
2.2K
5%
SMB_ADC_SCL_R
5%
CHIP
S MB _LM75_3_3V 3A UX _S CL
S MB _LM75_3_3V 3A UX _S DA
S MB _V R_S E NS O R_3V 3A UX _S CL
S MB _V R_S E NS O R_3V 3A UX _S DA
2.2K CHIP5%
2.2K
1/16W
CHIP
0402LF
2.2K
2.2K
1/16W
1/16W
5%2.2K
5%
2.2K
2.2K
1/16W
1/16W
2.2K
S MB _V R_S E NS O R_3V 3A UX _S DA _R
S MB _V R_S E NS O R_3V 3A UX _S CL_R
SMB_ADC_SDA_R
SMB_ADC_SCL
0 CHIP
S MB _LM75_3_3V 3A UX _S CL
SMB_P12V_H SC _SD A5%0 CHIP
0 CHIP
S MB _LM75_2_3V 3A UX _S CL_R5%CHIPS MB _LM75_2_3V 3A UX _S CL
CHIP
CHIP
CHIP
CHIP
CHIP 5% 0 S MB _LM75_0_3V 3A UX _S DA _R
S MB _LM75_0_3V 3A UX _S CL_R
S MB _LM75_1_3V 3A UX _S DA _R
S MB _LM75_1_3V 3A UX _S CL_R
S MB _V R_3V 3A UX _S CL_R6
05%
S MB _LM75_0_3V 3A UX _S DA
S MB _LM75_0_3V 3A UX _S CL
S MB _LM75_1_3V 3A UX _S DA
S MB _LM75_2_3V 3A UX _S DA
S MB _LM75_1_3V 3A UX _S CL
TCA9548APWR
S MB _LM75_2_3V 3A UX _S DA _R
S MB _V R_3V 3A UX _S DA _R6
SMB_P12V_H SC _SC L
SMLF
33.2
S MB _LM75_3_3V 3A UX _S DA
0 5% CHIP
0
5% 0
5% 0
05%
1%
EMPTY
0402LF
10K
1/16W
5% CHIP0
05%
CHIP
0402LF 1/16W
5% 0CHIP
25V
0.1UF
10%
X 7R
0402
2.2K EMPTY
5%
0402LF
EMPTY
CHIP5%
2.2K
0402LF
5% CHIP
0402LF
CHIP5%
5% CHIP
CHIP
0402LF
CHIP5%
CHIP5%
0402LF
5%
1%CHIP
0402LF
33.21%CHIP
1/16W
S MB _V R_S E NS O R_3V 3A UX _S DA
RS T_S MB _S W ITCH_N
S MB _V R_3V 3A UX _S CL
S MB _V R_3V 3A UX _S DA
P CA 9548_P CIE 0_A DDR1
P CA 9548_P CIE 0_A DDR2
P CA 9548_P CIE 0_A DDR0
P U_RS T_S MB _P CIE 2_N
S MB _LM75_1_3V 3A UX _S DA
S MB _LM75_2_3V 3A UX _S CL
S MB _LM75_2_3V 3A UX _S DA
S MB _LM75_0_3V 3A UX _S CL
S MB _V R_3V 3A UX _S DA
S MB _LM75_0_3V 3A UX _S DA
S MB _V R_3V 3A UX _S CL
S MB _LM75_1_3V 3A UX _S CL
S MB _V R_S E NS O R_3V 3A UX _S CL
IC
SMBUS - PCIE2 SMBUS
0402LF
EMPTY
1%
10K
1/16W
0402LF
EMPTY
1%
1/16W
10K
EMPTY
1%
0402LF
10K
1/16W
1/16W
CHIP
1K
1%
0402LFIO_SLOT0402LF
1K
CHIP
1/16W
1%
IO_SLOT
1/16W
1K
0402LF
CHIP
1%
IO_SLOT
PCA9548_PCIE0_ADDR1
PCA9548_PCIE0_ADDR2
PCA9548_PCIE0_ADDR0
5%
SMB_P12V_H SC _SD A_R
S MB _LM75_3_3V 3A UX _S CL_R
SMB_P12V_H SC _SC L_R
S MB _LM75_3_3V 3A UX _S DA _R
SMB_ADC_SDA
R1341
R1316
R1315
R1312
R6229
R6228
R3711
R3712
R3721
R3722
R3723
R3724
R3725
R3726
R3727
R3728
R3730
R3729
R4269
R4270
R3713
R3714
R3715
R3716
R3718
R3717
R3720
R3719
R3731
R3732
R3710
24
23
19
17
15
13
10
8
6
4
22
20
18
16
14
11
9
7
5
3
12
21
2
1
U39
SD4
SC4
SD5
SC5
SD6
SC6
SD7
SC7
A2 SCL
SDA
VCC
GND
SC3
SD3
SC2
SD2
SC1
SD1
SC0
SD0
RESET#
A1
A0
21
21
21
21
21
21
2 1
2 1
21
21
21
21
2
1
2 1
2 1
21
2
1
2
1
2
1
2
1
2
1
2
1
2
1
1
SHEETDATE
23
7 3 2 16 5 4
E
A
B
C
E
D
C
B
A
7 6 5 4
D
DEPARTMENT
SIZE
PROJECT DOCUMENT NUMBER REV
REVIEWER
DESIGNER
OUT
OUT
OUT
OUT
OUT
BI
BI
IN
BI
OUT
OUT
OUT
OUT
OUT
OUT
OUT
OUT
OUT
OUT
OUT
OUT
OUT
IN
IN
IN
BI
OUT
BI
OUT
IN
OUT
OUT
OUT
BI
OUT
BI
OUT
C2056
R3705
R3708R3706R3703
R3709R3707R3704
C



20220215 ADD ISOLATER
Thu Aug 24 14:09:23 2023<NAME_2>
<NAME_1>
MB FABCGTI V02
253 OF 365
P3V3_AUX
P3V3_AUX
80
150
254 255263268189243
254255
PWRGD_ISOLATOR
33.2 1%
SMLF
IC
PJT138K
CHIP5%0
0 5% CHIP
0402LF
1/16W
CHIP
4.7K
IC
PWRGD_PS_PWROK_PLD_ISO_R
PWRGD_PS_PWROK
PWRGD_PS_PWROK_PLD
PWRGD_PS_PWROK_PLD_ISO
MB0_P12V_STBY_PWRGD
PJT138K
0402LF
1/16WCHIP
PWRGD_PS_PWROK_PLD_N
SMLF
PWRGD_PS_PWROK_PLD
5% 0402LF
CHIP
1/16W
1K
1%
R3047
R3048
G1
G2
D1S1
S2 D2
R4605
R4604
5
2
4 3
1 6
Q144
Q144
21R9446
2
1
21
21
2
1
1
SHEETDATE
23
7 3 2 16 5 4
E
A
B
C
E
D
C
B
A
7 6 5 4
D
DEPARTMENT
SIZE
PROJECT DOCUMENT NUMBER REV
REVIEWER
DESIGNER
IN
OUT
OUT
OUTIN
C



PWRGD_P1V2_AUX 1 = ON
RST_CPU0_RSMRST_N 1 = ON
PWRGD_PS_PWROK 1 = ON
PWRGD_SYS_PWROK 1 = ON
P3V3 1 = ON
P5V 1 = ON
PWRGD_P1V8_AUX 1 = ON
Thu Aug 24 14:09:23 2023<NAME_2>
<NAME_1>
MB FABCGTI V02
254 OF 365
P3V3_AUX
P3V3
P5V
P3V3_AUX
P3V3_AUX
P3V3_AUX
P3V3_AUX
85
2881
254
27081148271
27181
LED_BLUE
LTST-C281TBKT-5A
IC
0402LF
LTST-C281TBKT-5A
LTST-C281TBKT-5A
SMLF
LED_BLUE
LED_BLUE
LTST-C281TBKT-5A
SCM_SYS_PWROK_R2
1%
1/16W
130
CHIP
0402LF
SMLF
LED_PWRGD_PS_PWROK_PLD_D LED_PWRGD_PS_PWROK_PLD
1/16WCHIP
LED_RST_RSMRST_PLD_R_N
130
1/16W
LED_RST_RSMRST_PLD_R_N_D
SMLF ICSMLF
LED_PWRGD_SYS_PWROK_R_D
CHIP
0402LF1%
IC
IC
RST_CPU0_RSMRST_N
PJT138K
IC
SMLF
IC
LED_BLUE
PWRGD_PS_PWROK_PLD
IC
PJT138K
SMLF
130 1%
LED_P3V3
LED_P5V
LED_BLUE
SMLF IC
LTST-C281TBKT-5A
LED_BLUE
SMLF IC
LTST-C281TBKT-5A
1/16W
130 1%
CHIP
0402LF
1% 0402LF
1/16WCHIP
470
LED_PWRGD_SYS_PWROK_R
PJT138K
POWER GOOD LED'S 1/3
LED_BLUE
LTST-C281TBKT-5A
1/16WCHIP
130 1% 0402LF
SMLF
PJT138K
IC
LED_PWRGD_P1V8_AUX_D
PWRGD_P1V8_AUX_R
ICSMLF
LED_PWRGD_P1V8_AUX
SMLF SMLF
1/16WCHIP
130 1% 0402LFLED_PWRGD_P1V2_AUXLED_PWRGD_P1V2_AUX_D
PJT138K
PWRGD_P1V2_AUX_R
IC
G1
G1
G2
G1
G2
D1S1
D1S1
S2 D2
D1S1
S2 D2
R3102
Q6000
D6000
D93
Q87
5 Q87
D88
Q78
D91
5 Q78
D98
D96
D99
AC
AC
AC
AC
AC
AC
AC
4 3 4 3
2
21C A
21C A
2
C A 21
2
C A 21
C A
21C A
21
21C A
1 6
1 6 1 6
1
SHEETDATE
23
7 3 2 16 5 4
E
A
B
C
E
D
C
B
A
7 6 5 4
D
DEPARTMENT
SIZE
PROJECT DOCUMENT NUMBER REV
REVIEWER
DESIGNER
IN
IN
IN
IN
IN
R6246
R3074
R3069
R3071
R3075
R3100
C



PWRGD_PVDDCR_CPU0_P0 1 = ON
PWRGD_PVDD33_S5 1 = ON
PWRGD_PVDDCR_SOC_P0 1 = ON
PWRGD_PVDDIO_P0 1 = ON
PWRGD_PVDDCR_CPU1_P0 1 = ON
PWRGD_PVDD18_S5_P0 1 = ON
PWRGD_PVDD11_S3_P0 1 = ON
Thu Aug 24 14:09:29 2023<NAME_2>
<NAME_1>
MB FABCGTI V02
255 OF 365
P3V3_AUX
P3V3_AUX
P3V3_AUX
P3V3_AUX
P3V3_AUX
P3V3_AUX
P3V3_AUX
81
82
82
82
81
81
81
LED _PW R GD _PVD D C R _C PU 0_P0_D
SMLF
PJT138K
IC
SMLF
PJT138K
LED_PWRGD_PVDDCR_CPU1_P0_R
LTST-C281TBKT-5A
LED_BLUE
N C _Q83_D 2
N C _Q83_G2
N C _Q83_S2
LED_PWRGD_PVDD11_S3_P0_R
SMLF
IC
LED_BLUE
LED_PWRGD_PVDDIO_P0_R
FM_LED_PWRGD_PVDDIO_P0
PJT138K
PJT138K
LED _PW R GD _PVD D C R _SOC _P0_D
PJT138K
SMLF
LED_BLUE
LTST-C281TBKT-5A
SMLF SMLFSMLF
SMLF
IC
LED_BLUE
SMLF
LTST-C281TBKT-5A
PJT138K
IC
IC
IC
IC
LED_BLUE
SMLF IC
IC
SMLF
IC
SMLF
IC
PJT138K
FM_LED _PW R GD _PVD D C R _C PU 0_P0
SMLF
FM_LED _PW R GD _PVD D C R _SOC _P0
LED_BLUE
SMLF
LTST-C281TBKT-5A
FM_LED_PWRGD_PVDDCR_CPU1_P0
LED _PW R GD _PVD D C R _C PU 1_P0_D
IC
LED_PWRGD_PVDDCR_CPU0_P0_R
LED_PWRGD_PVDD33_S5_R LED_PWRGD_PVDDIO_P0_D
FM_LED _PW R GD _PVD D 11_S3_P0
LED _PW R GD _PVD D 18_S5_P0_D
LED_BLUE
IC
LTST-C281TBKT-5A
LED _PW R GD _PVD D 18_S5_P0_R
LTST-C281TBKT-5A
LED_PWRGD_PVDD11_S3_P0_D
LTST-C281TBKT-5A
POWER GOOD LED'S 2/3
IC
PJT138K
SMLF
LED_PWRGD_PVDDCR_SOC_P0_R
FM_LED _PW R GD _PVD D 18_S5_P0
IC
0402LF
1/16WCHIP
1%130
0402LF
1/16WCHIP
1%130
0402LF
1/16WCHIP
1%130
130
1/16W
0402LF1%
CHIP
130 1%
1/16WCHIP
0402LF
1/16W
0402LF130 1%
CHIP
0402LF
1/16WCHIP
1%130
LED_PWRGD_PVDD33_S5_D
FM_LE D_P W RG D_P V DD33_S 5
G2
G1
G2
G1
G2
G2
G1
G1
S2 D2D1S1
S2 D2
D1S1
S2 D2
S2 D2D1S1
D1S1
5
4 3
Q83
D77
Q81
D78
D79
5 Q81
Q83
D73
Q79
D74
D75
D76
5 Q79
Q80
5 Q80
AC
AC
AC
AC
AC
AC
AC
4 3
4 34 3
21
21
21
C A
2
C A
C A
2
21C A
2
21
21
C A
C A
21C A
2
1 61 6
1 61 6
1
SHEETDATE
23
7 3 2 16 5 4
E
A
B
C
E
D
C
B
A
7 6 5 4
D
DEPARTMENT
SIZE
PROJECT DOCUMENT NUMBER REV
REVIEWER
DESIGNER
IN
IN
IN
ININ
IN
IN
R3092
R3090
R3091
R3086
R3087
R3089
R3088
C



PWRGD_PVDDIO_P1 1 = ON
PWRGD_PVDD18_S5_P1 1 = ON
P12V_AUX 1 = ON
PWRGD_PVDD11_S3_P1 1 = ONPWRGD_PVDDCR_CPU0_P1 1 = ON
PWRGD_PVDDCR_CPU1_P1 1 = ON
PWRGD_PVDDCR_SOC_P1 1 = ON
P12V_PSU 1 = ON
P12V_SCM FAULT 0 = ON
Thu Aug 24 14:09:29 2023<NAME_2>
<NAME_1>
MB FABCGTI V02
256 OF 365
SMLF
P12V_PSU
P3V3_AUX
P3V3_AUX
P3V3_AUX
P12V_AUX
P3V3_AUX
P3V3_AUX
P3V3_AUX
P3V3_AUX
P3V3_AUX
152
80
8081
80
80
80
CHIP
560
1/16W
LED_P12V_PSU_R2
1%
LED_P12V_PSU_R3
CHIP
LED _P12V_SC M_FAU LT_D 2
0402LF
SMLF
P12V_SCM_FAULT_R_N
PJT138K
PJT138K
SMLF
SMLF
IC 0402LF
IC
0402LF
LED_PWRGD_PVDD18_S5_P1_D
FM_LED _PW R GD _PVD D 18_S5_P1
1/16W
0402LF 1/16W
560 1%
130 1% 0402LF
LED_BLUE CHIP
1/16W
560 1%
0402LF
LED_P12V_AUX_R1 LED_P12V_AUX_R3
LTST-C281TBKT-5A
LED_BLUE
IC
SMLF
1%560
CHIP 1/16W
560
0402LFCHIP
1%
1/16W
560 1%
CHIP 0402LF
IC
SMLF
FM_LED _PW R GD _PVD D 11_S3_P1
SMLF
LTST-C281TBKT-5APJT138K
POWER GOOD LED'S 3/3
PJT138K
IC
130 1%
CHIP 1/16W
0402LF
130 1%
CHIP
SMLF
LTST-C281TBKT-5APJT138K
SMLF
IC
LTST-C281TBKT-5A
LED_BLUE
ICSMLF
130 1%
CHIP 1/16W
0402LF
CHIP
ICSMLF
LED_BLUE
IC
SMLF
PJT138K
LTST-C281TBKT-5A
LED_BLUE
SMLF IC
IC
PJT138K
SMLF
LED _PW R GD _PVD D C R _C PU 0_P1_D LED _PW R GD _PVD D C R _C PU 0_P1_R
LED _PW R GD _PVD D C R _SOC _P1_D
LED _PW R GD _PVD D C R _C PU 1_P1_D LED _PW R GD _PVD D C R _C PU 1_P1_R
LED_PWRGD_PVDDIO_P1_R
FM_LED _PW R GD _PVD D C R _C PU 0_P1
FM_LED _PW R GD _PVD D C R _SOC _P1
FM_LED _PW R GD _PVD D C R _C PU 1_P1
FM_LED_PWRGD_PVDDIO_P1
LED_BLUE
IC
130 1%
CHIP 1/16W
0402LF
130 1%
CHIP 1/16W
0402LF
IC
LED_BLUE
SMLF
IC
SMLF IC
LED_BLUE
LED_PWRGD_PVDD11_S3_P1_RLED_PWRGD_PVDD11_S3_P1_D
1/16W
LTST-C281TBKT-5A
LED _PW R GD _PVD D C R _SOC _P1_R
LTST-C281TBKT-5APJT138K
LED_PWRGD_PVDD18_S5_P1_R
IC
LED_P12V_AUX_R2
0402LF
LED_P12V_PSU_R1
5%
LED_PWRGD_PVDDIO_P1_D
1/16W
CHIP
1%
CHIP
IC
0402LF
4.7K
LTST-C281TBKT-5A
SMLF
1/16W
LTST-C190KSKT-P
LED_YELLOW
249
LED_P12V_SCM_FAULT
1/16W
LED _P12V_SC M_FAU LT_D 1
G1
G2
G1
G1
G2
G2
G1
G2
D1S1
S2 D2
D1S1
D1S1S2 D2
S2 D2 D1S1S2 D2
5
2
C A
C A
C A
4 3
1 6
Q8001
Q8001
D8002
D8001
D8000
D84
D85
Q86
5 Q86
D80
D81
D82
D83
Q84
5 Q84
Q85
5 Q85
AC
AC
AC
AC
AC
AC
AC
AC
AC
4 3
4 34 3
2
1 21
21 21 21
212121
21
21
C A
C A
2
21C A
21C A
21
21
C A
C A
2
2
1 6
1 61 6
1
SHEETDATE
23
7 3 2 16 5 4
E
A
B
C
E
D
C
B
A
7 6 5 4
D
DEPARTMENT
SIZE
PROJECT DOCUMENT NUMBER REV
REVIEWER
DESIGNER
IN
IN
IN
IN
IN
IN
IN
R8028
R8029
R8026 R8027
R8024R8023
R3099
R3097
R3093
R3094
R3096
R3095
C
R8025
R8022



NOTE:R4567 NEED CHANGE TO 5.11K OHM ON EVT STATES AND POP R4568
VI=1.581V
20220105 ADD R4567,R4568
ADDR: 0X3A(8-BIT) / 0X1D(7-BIT)
IF USE AD128,POP R3668,R3670
VIN 1.599V 1.599V 1.677V 1.581V
V SOURCE P3V3_AUX P3V3 P5V P12V_AUX
ADDR: 0X6A(8-BIT) / 0X35(7-BIT)
20210615 MODIFY FOR GT
Thu Aug 24 14:09:28 2023<NAME_2>
<NAME_1>
MB FABCGTI V02
257 OF 365
P12V_AUX
P3V3_AUX
P3V3_AUX
P5V
P3V3
P3V3_AUX
P3V3_AUX
P 12V _E 1S _0_IS E NS E _MA M_MA M
CO-LAYOUT
AD C _TI_BOM3
P 12V _E 1S _0_IS E NS E _TIC
5%
50V
100P F
EMPTY
E MP TY
P 12V _E 1S _0_IS E NS E _MA M
P 12V _E 1S _0_IS E NS E _MP S _TIC
0402
A DC_TI_B OM1
ADC_TI_BOM1
A DC128_A 0
P 12V _E 1S _0_IS E NS E _TIC
258
258
258
10%
CHIP
0
P 12V _E 1S _0_IS E NS E _MA M_TIC
AD C _MAM_BOM2
ADC_TI_BOM3
CO-LAYOUT
X 7R
0402
A DC_TI_B OM1
P 12V _O CP _V 3_2_IS E NS E _MA M
CO-LAYOUT
CHIP P 12V _O CP _V 3_2_IS E NS E _TIC
EMPTY5%0P 12V _O CP _V 3_2_IS E NS E _MP S _TIC
0 5%P 12V _O CP _V 3_2_IS E NS E _MA M_TIC
A DC_TI_B OM1
AD C _MAM_BOM2
0
AD C _TI_BOM3
CHIP5%
P 12V _O CP _S FF_IS E NS E _MP S _TIC 5% EMPTY
P 12V _O CP _S FF_IS E NS E _TIC
CO-LAYOUT
A DC_TI_B OM1
P 12V _O CP _S FF_IS E NS E _MA M_TIC
140
258
258
134
258
147
141
258
258
258
258
258
258
135
258
258
258
258
258
258
258
258
258
258 258
258
258
151258
151258
258
258
258
258
146
241
258
258
258
258
140
258
147
258
258
258
258
258
151258
151258 258
258
258
258
258
134
135
146
141
SMLF
MAX11617EEE+T
10%
X 7R
MAX11617_VREF_RCHIP
X 6S
X 7R
0.1UF
0402
MAX11617_VREF
10UF
ADC_MAM_BOM2
0.1UF
IND
25V
P 3V 3_MA X 11617_V DD
EMPTY
0402LF
EMPTY
EMPTY
POP U269, AND DE-POP U193 WHICH IS 2ND SOLUTION
10%
10%
100P F
1%2K
AD C _MAM_BOM2
AD C _MAM_BOM2
A DC_TI_B OM1
0402
EMPTY5%
P 12V _E 1S _0_IS E NS E _MP S _MA M
50V
0402
AD C _MAM_BOM2
EMPTY
P 12V _O CP _V 3_2_IS E NS E _MP S _MA M
P 12V _O CP _S FF_IS E NS E _MA M
5%
CO-LAYOUT
AD C _MAM_BOM2
AD C _MAM_BOM2
1/16W
CHIP
A DC_TI_B OM1
10%
25V
0.1UF
100P F
5%0
ADC_MAM_BOM2
0402LF
P 12V _A UX _A DC
0402LF
A DC_TI_B OM1
CHIP
EMPTY P 5V _A DC_MA M
AD C _MAM_BOM2
0402
E MP TY
5%
50V
100P F
CO-LAYOUT
AD C _MAM_BOM2
A DC_TI_B OM1
P 3V 3_A UX _A DC_TIC
5%0 P 3V 3_A UX _A DC_MA M
0.1UF
25V
10%
X 7R
0402
P 3V 3_A DC_TIC
0.1UF
10%
0402
100P F
P 5V _A DC_TIC
AD C _MAM_BOM2
CO-LAYOUT
ADC_TI_BOM1
1/16W
CHIP
0402LF
P 5V _A DC 0 5%
AD C _MAM_BOM2
0402
CHIP
P 3V 3_A DC 0 5%
A DC_TI_B OM1
P 3V 3_A UX _A DC
CHIP
0
0
0402
P 12V _E 1S _0_IS E NS E _MA M
S MB _S E N_MA M_3V 3A UX _S CL
S MB _S E N_MA M_3V 3A UX _S DA
0402
AD C _MAM_BOM2
16V
C0805
1/16W
10%
X 6S
16V
10%
C0805
P 3V 3_P DB _A UX _A DC_MA M
P 3V 3_A UX _A DC_MA M
ADC_TI_BOM1
4.7K
S MB _S E N_TIC_3V 3A UX _S CL
S MB _S E N_TIC_3V 3A UX _S DA
ADC_TI_BOM1
SMLF
X 7R
10%
25V
A DC_TI_B OM1
100P F
X 7R
1/16W
A DC_TI_B OM1
25V
0
CHIP
0402LF
P 12V _A UX _A DC_TIC
P 12V _A UX _A DC_MA M
50V
5%
E MP TY
EMPTY
A DC_TI_B OM1
1.21K
5%
0402
X 7R
10%
18K
9.09K
A DC_TI_B OM1
5%
EMPTY
4.7K
1%
5%
4.7K
1/16W
1%
5.11K
4.7K
A DC128_A 1
E MP TY
5.11K
P 12V _O CP _V 3_2_IS E NS E _TIC
CHIP
P 3V 3_A DC128_V CC
0.1UF
0402LF
EMPTY
A DC_TI_B OM1
1%
1/16W
1/16W 1/16W
1%
ADC_TI_BOM1
S MB _S CM_2_R4_S DA
ADC_TI_BOM1
CHIP
CHIP
0402LF
S MB _S CM_2_R4_S CL
1/16W
P 3V 3_A UX _A DC_TIC
A DC128_V RE F
P 3V 3_P DB _A UX _A DC_TIC
1%
0402
TP _A DC128_INT
ADC_TI_BOM1
25V
S MB _S E N_TIC_3V 3A UX _S CL
S MB _S E N_TIC_3V 3A UX _S DA
5%0
5%0
100P F
5%
0 5% EMPTY
1%
1/16W
5%
5%0
1%
5%0
1/16W
0402LF
CHIP
1/16W
1/16W
1%
0 CHIP
1%
0402LF
CHIP
10%
0402
50V
5%
0402LF
1K
1%
1/16W
CHIP
0402LF
CHIP5%
0 EMPTY5%
0402
0402
CHIP
1%
1/16W
7.87K
1%
EMPTY
1K
0402LF
1K
B LM18P G 300S N1D
S MLF
0402LF
4.7K
1%
0.1UF
5%
0
0.1UF
0402
EMPTY5%0
5.11K
1%
0
5%
0402
CHIP
50V
VOLTAGE SENSOR (1/2)
P 3V 3_A DC_MA M
P 3V 3_P DB _A UX _A DC
X 7R
E MP TY
E MP TY
IC
X 7R
25V
X 7R
IND
A DC_TI_B OM1
10%
E MP TY
P 12V _A UX _A DC_TIC
P 5V _A DC_TIC
P 3V 3_A DC_TIC
CHIP
A DC128_A 1
1%
1/16W
ADC_TI_BOM1
1K
A DC128_A 0
0402LF
EMPTY
A DC_TI_B OM1
0402LF
ADC_TI_BOM1
0402LF
0 5%
CHIP
X 7R
0402
50V
25V
A DC_TI_B OM1
X 7R
10%
ADC_TI_BOM1
P 12V _O CP _S FF_IS E NS E _TIC
ADC128D818CIMTX/NOPB
5%
1/16W
10UF
S MLF
B LM18P G 300S N1D
25V
25V
P 12V _A UX _A DC_MA M
P 12V _O CP _S FF_IS E NS E _MA M
P 12V _O CP _V 3_2_IS E NS E _MA M
P 5V _A DC_MA M
0402LF
S MB _S CM_2_R4_S CL
S MB _S CM_2_R4_S DA
0
1/16W
S MB _S E N_MA M_3V 3A UX _S DA
S MB _S E N_MA M_3V 3A UX _S CL
AD C _MAM_BOM2
0
E MP TY
CHIP
EMPTY
0.1UF
CO-LAYOUT
AD C _MAM_BOM2
100P F
1/16W
5%
0402LF
P 3V 3_A DC_MA M
25V0402LF
25V
0.1UF
A DC_TI_B OM1
AD C _MAM_BOM2
1%
P 3V 3_P DB _A UX _A DC_TIC
0.1UF
P 1V 581_P DB _A DC
0402
E MP TY
P 3V 3_P DB _A UX _A DC_MA M
CO-LAYOUT
AD C _MAM_BOM2
CO-LAYOUT
P 12V _O CP _S FF_IS E NS E _MA M_MA M
P 12V _O CP _S FF_IS E NS E _MP S _MA M 0 EMPTY
AD C _MAM_BOM2
P 12V _O CP _V 3_2_IS E NS E _MA M_MA M
0 5% EMPTY 50V
CO-LAYOUT
5%
0.1UF
L15
C1768
R3672
R3671
R1793
R1792
C1767
R3863
C2176
R3864
R3865
R3866
R3859
C2042
C59
R3860
R3861
R3862
R3939
R3940
C35
R3941
R3942
C2043
C2044
C1344
C2045
R3681
R2907
R3682
R3683
R3684
R2908
R3685
R3686
R1791
R1799
R1800
C1757
R2900
R3689
C1347
C2047
R3669R3667
C2046
R3687
R3688
R3670R3668
C2050
C2048
R1785
R2843
C2049
R3005
R3679
R3680
R4567
R4568
16
14
13
15
1
2
3
4
12
11
10
98
7
6
5
21
1
5
2
3
6
9
10
11
12
13
14
15
16 4
8
7
21
U193
U269
L16
CAD NOTE:
1 2
VDD
GND
SDA
SCL
AIN7
AIN6
AIN5
AIN4AIN3
AIN2
AIN1
AIN0
AIN8
AIN9
AIN10
AIN11||REF
1 2
INT#
GND
SCL
SDA
IN0
IN1
IN2
IN3
IN4
IN5
IN6
IN7
A1
A0
V+
VREF
2
1
2
1
2
1
21
21
21
21
21
2
1
2
1
R3690
2
1
2
1
21
2
1
2
1
C37
21
21
21
21
2
1
2
1
2
1
2
1
C33
21
21
21
21
21
2
1
2
1
C2194
21
21
2
1
2
1
2
1
2
1
2
1
2
1
2
1
2
1
21
21
2
1
2
12
1
2
1
2
1
21
2
1
21
2
1
21
21
2
1
2
1
21
2
1
21
2
1
2
1
21
21
2
1
2
1
2
1
1
SHEETDATE
23
7 3 2 16 5 4
E
A
B
C
E
D
C
B
A
7 6 5 4
D
DEPARTMENT
SIZE
PROJECT DOCUMENT NUMBER REV
REVIEWER
DESIGNER
IN
IN
IN
INOUT
OUT
OUT
IN
IN
IN
IN
IN
IN
IN
OUT
OUT
OUT
OUT
OUT
OUT
OUT
OUT
IN
IN
IN
IN
IN
IN
IN
BI
OUT
OUT
BI
BI
IN
BI
IN
IN
BI
IN
IN
IN
IN
IN
IN
IN
IN
IN
IN
OUT
OUT
OUT
OUT
OUT
IN
IN
IN
IN
IN
OUT
OUT
C2052C2051
C



1.402V
PVDD18_S5_P1
ADDR: 0X6A(8-BIT) / 0X35(7-BIT)
VIN
V SOURCE P5V_AUX
1.677V
P1V8_AUX
ADDR: 0X3A(8-BIT) / 0X1D(7-BIT)
IF USE AD128,POP R3668,R3670
P1V2_AUX
1.402V
P1V8_CPU0_RT_1D
1.402V 1.581V
PVDD_33_S5
1.402V 0.934V
P1V8_CPU1_RT_1D PVDD18_S5_P0
1.402V
Thu Aug 24 14:09:58 2023<NAME_2>
<NAME_1>
MB FABCGTI V02
258 OF 365
P1V8_CPU1_RT_1D
PVDD18_S5_P1
PVDD18_S5_P0
P1V8_CPU0_RT_1D
P3V3_AUX
PVDD_33_S5
P1V8_AUX
P1V2_AUX
P3V3_AUX
P5V_AUX
P3V3_AUX
259
259
259
259
259
259
259253259
259
259
259
259
259
259
259
259
253259
259
259
259
259
259
259
259
259
253259 259
259
259
259
259
259
259
259
259
259
259
259
259
259
259
253259
259
259
259
259
259
259
1/16W0402LF
MAX11617_2_VREF
0.1UF
25V
10%
X 7R
0402
X 6S
10%
MAX11617_2_VREF_R
MAX11617EEE+T
S MLF
B LM18P G 300S N1D
10%
10%
16VEMPTY
X 7R
25V
AD C _MAM_BOM2
P 1V 8_CP U1_RT_1D_A DC_MA M
CO-LAYOUT
C0805
SMLF
ADC_MAM_BOM2
P 5V _A UX _A DC_MA M
0.1UF
P 3V 3_MA X 11617_2_V DD
16V
10UF
E MP TYX 7R
0402LF
P 1V 2_A UX _A DC_MA M
P 1V 2_A UX _A DC_TIC
1%
1/16W
P 1V 8_CP U0_RT_1D_A DC_TIC
5.11K
CHIP
CO-LAYOUT
ADC_MAM_BOM2
0 5% EMPTY
EMPTY
1/16W
S MB _S E N_MA M_2_3V 3A UX _S DA
0402LF
S MB _S E N_MA M_2_3V 3A UX _S CL
POP U51, AND DE-POP U50 WHICH IS 2ND SOLUTION
ADC_MAM_BOM2
5%0
SMB_ADC_SCL_R
S MB _S E N_MA M_2_3V 3A UX _S DA
P 3V 3_A DC128_2_V CC
25V
P V DD18_S 5_P 1_A DC_MA M
AD C _MAM_BOM2
E MP TY
0.1UF
ADC_MAM_BOM2
1/16W
CHIP
25V
P V DD18_S 5_P 0_A DC_TIC
P V DD18_S 5_P 0_A DC_MA M
ADC_MAM_BOM2
25V
0402LF
ADC_MAM_BOM2
100P F
1/16W
P V DD_33_S 5_A DC
CO-LAYOUT
AD C _MAM_BOM2
CHIP
P 1V 8_CP U1_RT_1D_A DC
0 5%
ADC_TI_BOM1
CHIP
AD C _MAM_BOM2
E MP TY
100P F
A DC_TI_B OM1
P 1V 8_A UX _A DC_TIC
P 1V 8_A UX _A DC_MA M
CHIP
0402LF
18K
ADC_MAM_BOM2ADC_TI_BOM1
ADC_MAM_BOM2
5%
1%
0402LF
P 1V 8_CP U0_RT_1D_A DC
EMPTY
0.1UF
AD C _MAM_BOM2
AD C _MAM_BOM2
E MP TY
0402
0.1UF
25V
10%
X 7R
0402
A DC_TI_B OM1
ADC_MAM_BOM2
CO-LAYOUT
0402LF
P 1V 2_A UX _A DC
5%
5% EMPTY
0402
X 7R
10%
25V
0.1UF
A DC_TI_B OM1
P 5V _A UX _A DC_TIC
P 5V _A UX _A DC_MA M
CO-LAYOUT
ADC_MAM_BOM2
P 1V 8_A UX _A DC
1/16W
CHIP
EMPTY
CO-LAYOUT
0402
CHIP
10UF
C0805
SMB_ADC_SDA_R
A DC_TI_B OM1
0402
1/16W
0402LF
P V DD18_S 5_P 1_A DC
1%
CHIP
0402
0402
1/16W
CHIP
0402LF
5%
1/16W
18K
0
0402
CHIP
0402
0
9.09K
A DC_TI_B OM1
ADC_TI_BOM1
0402LF
ADC_TI_BOM1
1/16W
18K
X 7R
25V
0.1UF
X 7R
0402LF
ADC_TI_BOM1
P V DD18_S 5_P 1_A DC_TIC
P V DD18_S 5_P 0_A DC_TIC
P V DD_33_S 5_A DC_TIC
P 1V 8_CP U1_RT_1D_A DC_TIC
P 1V 8_CP U0_RT_1D_A DC_TIC
1%
1K
ADC_TI_BOM1
AD C 128_2_A0
A DC128_2_A 1
0402LF
E MP TY
1/16W
0402LF
CHIP
1/16W
1K
1K
EMPTY
1K
1%
P 1V 2_A UX _A DC_TIC
1/16W
E MP TY
0402
1%
1/16W
EMPTY
1/16W
SMB_ADC_SCL_R
0 5% CHIP
S MB _S E N_TIC_2_3V 3A UX _S CL
S MB _S E N_TIC_2_3V 3A UX _S DA
4.7K
1%
4.7K
S MB _S E N_TIC_2_3V 3A UX _S DA
A DC128_2_V RE F
A DC128_2_A 1
P 1V 8_A UX _A DC_TIC
P 5V _A UX _A DC_TIC
ADC_TI_BOM1
ADC_TI_BOM1
ADC_TI_BOM1
IC
SMLF
P 1V 8_CP U1_RT_1D_A DC_MA M
P V DD_33_S 5_A DC_MA M
1%
CHIP
0402LF
1/16W
18K
0402LF
1/16W
CHIP
18K
0402LF
5.11K
1/16W
5%
E MP TY
18K
0402LF
1%
CHIP
1%
5.11K
1%
1%
CHIP
18K
1%
0 5%
1/16W
0
2K
0402
X 6S
IND
0402
0
1/16W
CHIP
0402
0402
25V
0
CHIP
5.11K
CHIP
1/16W
1%
1%
0402LF
1/16W
5.11K
EMPTY
50V
5%
CHIP
5% EMPTY0
0
1/16W
0402LF
CHIP
CHIP
1%
0
100P F
X 7R
1%
EMPTY0 5%
50V
5%
0402
0.1UF
X 7R
10%
CHIP
1%
0402LF
1%
0.1UF
B LM18P G 300S N1D
IND
S MLF
10%
X 7R
0.1UF
VOLTAGE SENSOR (2/2)
P 1V 8_A UX _A DC_MA M
P 1V 2_A UX _A DC_MA M
P 1V 8_CP U0_RT_1D_A DC_MA M
P V DD18_S 5_P 1_A DC_MA M
P V DD18_S 5_P 0_A DC_MA M
0402LF CHIP
ADC128D818CIMTX/NOPB
ADC_TI_BOM1
10%
0402
10% S MB _S E N_TIC_2_3V 3A UX _S CL
TP _A DC128_2_INT
A DC128_2_A 0
CHIP
SMB_ADC_SDA_R
0402LF
ADC_TI_BOM1
0402LF
EMPTY
A DC_TI_B OM1
1%
5%
5%
ADC_TI_BOM1
0
0402
10%
0 5%
4.7K
CHIP5%
ADC_TI_BOM1
P V DD_33_S 5_A DC_MA M
P V DD_33_S 5_A DC_TIC
A DC_TI_B OM1
0.1UF
10%
X 7R
0 5%
10%
0402
S MB _S E N_MA M_2_3V 3A UX _S CL
1%
0402LF
5%0 EMPTYP 5V _A UX _A DC
CHIP
ADC_MAM_BOM2
1/16W
CHIP5%
100P F
50V
E MP TY
5%
ADC_TI_BOM1
100P F
50V
25V
5%
5.11K
1%
5%
50V
ADC_TI_BOM1
1%
P 1V 8_CP U0_RT_1D_A DC_MA M
100P F
50V
ADC_TI_BOM1
X 7R
10%
1/16W
CO-LAYOUT
P 1V 8_CP U1_RT_1D_A DC_TIC
50V
100P F
5%
ADC_TI_BOM1
0.1UF
25V
ADC_TI_BOM1
EMPTY
CO-LAYOUT
5%0
P V DD18_S 5_P 0_A DC
5.11K
0402
E MP TY
50V
5%
A DC_TI_B OM1
0402LF ADC_MAM_BOM2
25V
ADC_TI_BOM1
0 5% CHIP P V DD18_S 5_P 1_A DC_TIC
100P F
A DC_TI_B OM1
ADC_MAM_BOM2
L24
R1256
C1081
R1249
R1236
R1233
R1254
R1247
C1080
R1235
R1255
R1248
C1082
R1257
R1250
C1083
R1234
R1231
R1252
R1246
C1079
R1232
R1251
R1245
C1078
C1077
C1076
R1243
R1244
R1228
R1227
C1084
C1085
R1258
R1259
R1237
R1260
R1263
R1226
R1225
R1222
R1223
R1220
R1221
R1229
C1090
C1088
R1224
C1089
C1091
C1087
C1086
C1075
R1230
R1267
C1074
C1092
R1241R1239
R1242R1240
C1093
R1238
21
16
14
13
15
1
2
3
4
12
11
10
98
7
6
5
1
5
2
3
6
9
10
11
12
13
14
15
16 4
8
7
21
U50
U51
L25
CAD NOTE:
1 2
1 2
VDD
GND
SDA
SCL
AIN7
AIN6
AIN5
AIN4AIN3
AIN2
AIN1
AIN0
AIN8
AIN9
AIN10
AIN11||REF
INT#
GND
SCL
SDA
IN0
IN1
IN2
IN3
IN4
IN5
IN6
IN7
A1
A0
V+
VREF
2
1
2
1
2
1
2
1
2
1
2
1
21
2
1
2
1
21
2
1
2
1
21
21
2
1
2
1
2
1
2
1
21
21
2
1
2
1
21
21
2
1
2
1
2
1
2
1
21
21
2
1
2
1
2
1
21
21
2
1
2
1
2
1
2
1
21
2
1
21
21
21
21
2
1
2
1
2
1
R1268
2
1
2
1
2
1
2
1
2
1
2
1
2
1
2
1
2
1
2
1
21
21
2
1
21
21
2
1
2
1
1
SHEETDATE
23
7 3 2 16 5 4
E
A
B
C
E
D
C
B
A
7 6 5 4
D
DEPARTMENT
SIZE
PROJECT DOCUMENT NUMBER REV
REVIEWER
DESIGNER
OUT
OUT
OUT
OUT
OUT
OUT
OUT
OUT
OUT
OUT
OUT
OUT
OUT
OUT
OUT
OUT
IN
IN
IN
IN
IN
IN
IN
IN
IN
IN
BI
OUT
BI
OUT
IN
BI
IN
IN
IN
BI
IN
IN
IN
IN
IN
IN
IN
IN
BI
IN
OUT
OUT
C1095C1094
C



20220926 ADD R6504
Thu Aug 24 14:09:31 2023<NAME_2>
<NAME_1>
MB FABCGTI V02
259 OF 365
P12V_AUX
P12V_AUX
P12V_MEM_CPU1
P12V_MEM_CPU0
P 12V _ME M_CP U0
P 1V 8_A UX
P 3V 3_A UX
P 1V 8_A UX
P 3V 3_A UX
P 12V _ME M_CP U1
P 1V 8_A UX
P 1V 8_A UX
81
260
260
260
260
33
TP_P12V_AUX_CPU0_DIMM_ISEN_P
TP_P12V_AUX_CPU1_DIMM_ISEN_P TP_P12V_AUX_CPU1_DIMM_ISEN_N
TP_P12V_AUX_CPU0_DIMM_ISEN_N
SMLF
0.001 3W 1%
CHIP
SMLF
1%0.001
CHIP
3W
PW RGD_P12V_MEM_CPU0_R
SMLF
P W RG D_P 12V _ME M_R
1/16W
1%
16.9K
0402LF
IC
P W RG D_P 12V _ME M_CP U1
SMLF
B S S 138DW -7-F
1%
0402LF
CHIP
1/16W
P12V_MEM MOS SWITCH
P W RG D_P 12V _ME M_CP U1_E N_N
P W RG D_P 12V _ME M_CP U0_E N_N
P W RG D_P 12V _ME M_CP U1_E N
IC
CHIP
P W RG D_P 12V _ME M_CP U0_E N
1%
CHIP
1/16W
100K
0402LF
1%
1/16W
CHIP
100K
0402LF
0402LF
CHIP
1/16W
10K
5%
0402LF
10K
5%
CHIP
1/16W
P W RG D_P 12V _ME M_CP U0
10K
5%
0402LF
CHIP
1/16WCHIP
1/16W
5%
0402LF
10K
0402
5%
50V
1000PF
X7R
25V
10%
X 7R
0402
0.1UF
33
33
16.9K
IC
P W RG D_P 12V _ME M
10K
CHIP
1/16W
0402LF
S N74LV C1G 11DCK R
SMLF
B S S 138DW -7-F
P U_U38_6
PW RGD_P12V_MEM_CPU1_RP W RG D_P 12V _ME M_CP U1
P W RG D_P 12V _ME M_CP U0
1%
 2
1
C347
2
1
R1452
2
1
R1457
2
1
R1450
41
52
36
Q18
41
52
36
Q19
2
1
R1442
2
1
R1443
2
1
R1449
2
1
R1440
2
1
R1441
21 R13634
5
2
6
3
1
U38
21R1458
21R1459
21
21
4
3
4
3
R6504
21
R1838
21
R1837
4
3
4
3
GND
Y
VCC
C
B
A
D2D1
S2
G2G1
S1
D2D1
S2
G2G1
S1
2
1
2
1
1
SHEETDATE
23
7 3 2 16 5 4
E
A
B
C
E
D
C
B
A
7 6 5 4
D
DEPARTMENT
SIZE
PROJECT DOCUMENT NUMBER REV
REVIEWER
DESIGNER
OUT
OUT
IN
IN
OUT
C5014
C



85 OHM80 OHM50 OHM45 OHM
Thu Aug 24 14:09:32 2023<NAME_2>
<NAME_1>
MB FABCGTI V02
260 OF 365
T1_GND
T1_GND
T1_GND
T1_GND
T1_GND
T1_GND
T1_GND
T1_GND
T1_GND
T1_GND
T1_GND
T1_GND
T1_GND
T1_GND
T1_GND
T1_GND
T1_GND
T1_GND
T1_GND
T1_GND
T1_GND
T1_GND
T1_GND
T1_GND
T1_GND
T1_GND
T1_GND
T1_GND
T1_GND
T1_GND
T1_GND
T1_GND
T1_GND
T1_GND
T1_GND
T1_GND
T1_GND
T1_GND
T1_GND
T1_GND
T1_GND
T1_GND
T1_GND
T1_GND
T1_GND
T1_GND
T1_GND
T1_GND
TDR_SE_45_OHM_IN2
TDR_1
TDR_SE_45_OHM_TOP
TDR_SE_45_OHM_IN1
TDR_SE_45_OHM_IN3
TDR_SE_45_OHM_IN6
TDR_SE_45_OHM_BOT
TDR_SE_45_OHM_IN5
TDR_SE_45_OHM_IN4
TDR_SE_50_OHM_IN6
TDR_SE_50_OHM_IN4
TDR_SE_50_OHM_BOT
TDR_SE_50_OHM_IN5
TDR_SE_50_OHM_IN3
TDR_SE_50_OHM_IN1
TDR_SE_50_OHM_IN2
TDR_SE_50_OHM_TOP
TDR_DIFF_80_BOT_DP
TDR_DIFF_80_BOT_DN
TDR_DIFF_80_IN6_DP
TDR_DIFF_80_IN6_DN
TDR_DIFF_80_IN5_DP
TDR_DIFF_80_IN5_DN
TDR_DIFF_80_IN4_DP
TDR_DIFF_80_IN4_DN
TDR_DIFF_80_IN3_DP
TDR_DIFF_80_IN3_DN
TDR_DIFF_80_IN2_DP
TDR_DIFF_80_IN2_DN
TDR_DIFF_80_IN1_DP
TDR_DIFF_80_IN1_DN
TDR_DIFF_80_TOP_DP
TDR_DIFF_80_TOP_DN
TDR_DIFF_85_BOT_DP
TDR_DIFF_85_BOT_DN
TDR_DIFF_85_IN6_DP
TDR_DIFF_85_IN6_DN
TDR_DIFF_85_IN5_DN
TDR_DIFF_85_IN3_DP
TDR_DIFF_85_IN3_DN
TDR_DIFF_85_IN5_DP
TDR_DIFF_85_IN4_DN
TDR_DIFF_85_IN4_DP
TDR_DIFF_85_IN2_DP
TDR_DIFF_85_IN2_DN
TDR_DIFF_85_IN1_DP
TDR_DIFF_85_IN1_DN
TDR_DIFF_85_TOP_DP
TDR_DIFF_85_TOP_DN
TH2
TH2
TH2
TH2
TH2
TH2
TH2
TH2
TH2
TH2
TH2
TH2
TH
TP_TDR_4P_DIP
EMPTY
EMPTY
TH
TP_TDR_4P_DIP
TP_TDR_4P_DIP
TH
EMPTY
TP_TDR_4P_DIP
EMPTY
TH
TH
TP_TDR_4P_DIP
EMPTY
TH
EMPTY
TP_TDR_4P_DIP
TH2
TH2
TH2
TH2
TP_TDR_4P_DIP
TH
EMPTY
TP_TDR_4P_DIP
TH
EMPTY
TP_TDR_4P_DIP
TH
EMPTY
TP_TDR_4P_DIP
EMPTY
TH
EMPTY
TP_TDR_4P_DIP
TH
TP_TDR_4P_DIP
TH
EMPTY
TP_TDR_4P_DIP
TH
EMPTY
TH
TP_TDR_4P_DIP
EMPTY
TH
TP_TDR_4P_DIP
EMPTY
TH
EMPTY
TP_TDR_4P_DIP
TH
TP_TDR_4P_DIP
EMPTY
EMPTY
TH
TP_TDR_4P_DIP
EMPTY
TP_TDR_4P_DIP
TH
EMPTY
TH
TP_TDR_4P_DIP
TH
EMPTY
TP_TDR_4P_DIP
EMPTY
TH
TP_TDR_4P_DIP
TP_TDR_4P_DIP
TH
EMPTY
TH
EMPTY
TP_TDR_4P_DIP
EMPTY
TH
TP_TDR_4P_DIP
EMPTY
TH
TP_TDR_4P_DIP
EMPTY
TH
TP_TDR_4P_DIP
TP_TDR_4P_DIP
TH
EMPTY
EMPTY
TP_TDR_4P_DIP
TH
EMPTY
TH
TP_TDR_4P_DIP
EMPTY
TH
TP_TDR_4P_DIP
TH
EMPTY
TP_TDR_4P_DIP
4
1
3
2
4
1
3
2
4
1
3
2
4
1
3
2
4
1
3
2
4
1
3
2
4
1
3
2
4
1
3
2
4
1
3
2
4
1
3
2
4
1
3
2
4
1
3
2
4
1
3
2
4
1
3
2
4
1
3
2
4
1
3
2
4
1
3
2
4
1
3
2
4
1
3
2
4
1
3
2
4
1
3
2
4
1
3
2
4
1
3
2
4
1
3
2
4
1
3
2
4
1
3
2
3
2
1
3
2
1
3
2
1
3
2
1
4
1
3
2
4
1
3
2
4
1
3
2
4
1
3
2
4
1
3
2
4
1
3
2
3
2
1
3
2
1
3
2
1
3
2
1
3
2
1
3
2
1
3
2
1
3
2
1
3
2
1
3
2
1
3
2
1
3
2
1
TDR
TDR
TDR
TDR
TDR
TDR
TDR
TDR
TDR
TDR
TDR TDR
TDR
TDR
TDR
TDR
X11
X8012
X8007
X8008
X8001
X8002
X7
X8
X8009
X8010
X8011
X8027
X8028
X8003
X8004
X8005
X9
X10
X8025
X8026
X8006
X27
X28
X12
X1
X2
X3
X4
X5
X25
X26
X6
S1
P2S2
P1
S1
P2S2
P1
S1
P2S2
P1
S1
P2S2
P1
S1
P2 S2
P1
S1
P2 S2
P1
S1
P2S2
P1
S1
P2S2
P1
S1
P2S2
P1
S1
P2S2
P1
S1
P2S2
P1
S1
P2S2
P1
S1
P2S2
P1
S1
P2 S2
P1
S1
P2 S2
P1
S1
P2 S2
P1
S1
P2S2
P1
S1
P2S2
P1
S1
P2 S2
P1
S1
P2 S2
P1
S1
P2 S2
P1
S1
P2S2
P1
S1
P2S2
P1
S1
P2S2
P1
S1
P2 S2
P1
S1
P2 S2
P1
S1
P2 S2
P1
S1
P2 S2
P1
S1
P2 S2
P1
S1
P2 S2
P1
S1
P2 S2
P1
S1
P2 S2
P1
DB7
DB8
DB9
DB10
DB11
DB15
DB16
DB12
DB1
DB2
DB3
DB4
DB5
DB13
DB14
DB6
1
SHEETDATE
23
7 3 2 16 5 4
E
A
B
C
E
D
C
B
A
7 6 5 4
D
DEPARTMENT
SIZE
PROJECT DOCUMENT NUMBER REV
REVIEWER
DESIGNER
C



85 OHM NECK
Thu Aug 24 14:09:32 2023<NAME_2>
<NAME_1>
MB FABCGTI V02
261 OF 365
T1_GND
T1_GND
T1_GND
T1_GND
T1_GND
T1_GND
T1_GND
T1_GND
T1_GND
T1_GND
T1_GND
T1_GND
TDR_2
TP_TDR_4P_DIP
EMPTY
TP_TDR_4P_DIP
EMPTY
TH
TH
EMPTY
TP_TDR_4P_DIP
TH
TDR_DIFF_85_NECK_IN1_DN
TDR_DIFF_85_NECK_IN1_DP
TDR_DIFF_85_NECK_IN2_DP
TDR_DIFF_85_NECK_IN2_DN
TDR_DIFF_85_NECK_IN3_DN
TDR_DIFF_85_NECK_IN3_DP
TP_TDR_4P_DIP
TP_TDR_4P_DIP
EMPTY
TH
EMPTY
TH
TP_TDR_4P_DIP
TH
EMPTY
TP_TDR_4P_DIP
EMPTY
EMPTY
TH
TP_TDR_4P_DIP
TP_TDR_4P_DIP
EMPTY
TH
TH
TDR_DIFF_85_NECK_IN4_DP
TDR_DIFF_85_NECK_IN4_DN
TDR_DIFF_85_NECK_IN5_DP
TDR_DIFF_85_NECK_IN5_DN
TDR_DIFF_85_NECK_IN6_DN
TDR_DIFF_85_NECK_IN6_DP
TP_TDR_4P_DIP
TP_TDR_4P_DIP
TH
EMPTY
TH
TP_TDR_4P_DIP
EMPTY
TH
EMPTY
4
1
3
2
4
1
3
2
4
1
3
2
4
1
3
2
4
1
3
2
4
1
3
2
4
1
3
2
4
1
3
2
4
1
3
2
4
1
3
2
4
1
3
2
4
1
3
2
X9008
X9009
X9011
X9010
X9027
X9028
X9002
X9003
X9004
X9005
X9025
X9026
S1
P2 S2
P1
S1
P2 S2
P1
S1
P2 S2
P1
S1
P2S2
P1
S1
P2S2
P1
S1
P2 S2
P1
S1
P2S2
P1
S1
P2S2
P1
S1
P2S2
P1
S1
P2S2
P1
S1
P2 S2
P1
S1
P2 S2
P1
1
SHEETDATE
23
7 3 2 16 5 4
E
A
B
C
E
D
C
B
A
7 6 5 4
D
DEPARTMENT
SIZE
PROJECT DOCUMENT NUMBER REV
REVIEWER
DESIGNER
C



20211112 MODIFY FOR GT
EN>1.2V ON
EN<0.95V OFF
ADDRESS: 0X40(8-BIT) / 0X20(7-BIT)
VOUT SLEW RATE: 2V/MS
SOFT START TIME=6MS.
OV =14.333V
UV =10.091V
LATCH OFF MODE
FPH=220A
HOT SWAT CIRCUIT
ADDRESS 0X20
OCW=220AOCP=240A
Thu Aug 24 14:09:30 2023 262 OF 365
MB FABC V02GTI
<NAME_2>
<NAME_1>
P12V_AUX
AGND_HSC
HSC_VDD
AGND_HSC
AGND_HSC
HSC_VDD
AGND_HSC
HSC_VDD
AGND_HSC
AGND_HSC
AGND_HSC
AGND_HSC
AGND_HSC
AGND_HSC
P12V_AUX
AGND_HSC
P3V3_AUX
AGND_HSC
P12V_PSU
HSC BOM1
1UF
25V
264 265
268 189 243 254
264 265
264265
269268
151
151
26880
268 85
264 265
264 265
268 80
264 265
264 265
264 265
264 265
HSC_SS
HSC BOM1MB0_P12V_STBY_PWRGD
1/16W
1%
0402
CHIP
0402LF
HSC BOM1HSC BOM1
0.001UF
X7R
1%
10K
HSC_SCREF
X7R
HS C B OM1
120K
CHIP
1/16W
CHIP
0402LF
HS C B OM1
0.1%0.047UF
25V
1/16W
HS C B OM1
1%
0402LF
HSC BOM1
HSC BOM1
0402LF
1K
1%
1/16W
4.7K
HSC BOM1
C0402
IC
SS15P3S-M3/86A
HSC BOM1
HS C B OM1 HSC_ADDR1K
1%
HSC BOM1
HSC_VDD18
1/16W
C0402
HSC_ON
HSC BOM1
0402LF
HSC_EN
0
5%CHIP
5% 0402LF
1/16W
CHIP0402LF1%
HSC BOM1
1/16W
HSC_VIN_UVW_N
HSC_EN_R
1/16W0
HSC BOM1
CHIP
AUX_SW
IRQ_SML1_PMBUS_ALERT
CHIP0402LF5%
SMB_SML1_PMBUS_HSC_SDA
HSC BOM1
CHIP
SMB_SML1_PMBUS_HSC_R_SDA
SMB_SML1_PMBUS_HSC_L_SCLSMB_SML1_PMBUS_HSC_SCL
HSC BOM1
5%
0402LF
1/16W
CHIP
HSC BOM1
C0402
X7R
50V
HSC BOM1
0.01UF
4.99KHSC BOM1
CHIP
1/16W
0.1%
HSC BOM1HSC BOM1
1UF 75K
25V
X6S
X6S
CHIP0402LF
CHIP
1/16W
5%
1/16W
0402LF
1/16W
1%
HSC_VDD_R
HSC BOM1
HSC_ON_R
1K
1/16W
CHIP
10K
HSC BOM1
HSC BOM1
0402LF
33.2
0
C0402
25V
0402LF
IRQ_SML1_PMBUS_ALERT_N
C0402
0402LF
1UF
X6S
IC
CHIP
0402LF
16.9K
2K
X7R
50V
22
22
2K
1%
CHIP
HSC MP5990 (1/3)
IRQ_HSC_FAULT_N
HSC_MODE
HSC_D_OC_R
HSC_FAULT HSC_D_OC
HSC_VTEMP
HSC_OCREF
0
C0402
X6S
1/16W
CHIP
1/16W
0402LF
1%
0
EMPTY
HSC_IMON
0402LF
5%
0
25V
1UF
0.1%
HSC_VSENSE
HSC BOM1
HSC BOM1
0.01UF
75K
0.1%
1/16W
CHIP
HSC BOM1
0402LF
SMLF
1/16W
CHIP
0402LF
1%
CHIP1/16W
CHIP1/16W
HS C B OM1
0402LF
1%
0402LF
HS C B OM1
50V
C0402
0.1%
HSC_CS
1/16W
HS C B OM1
0402LF
HSC_VOSEN
1/16W
C0402
X7R
16V
0.068UF
HSC BOM1
CHIP
CHIP
1/16W
1%
HSC BOM1
6.19K
HSC_FLT_TYPE
0402LF
0402LF
CHIP
1/16W
0.1%
4.99K
MP5990GMA-1111-Z
SMLF
HSC BOM1
R3909
Anode_2
Cathode
Anode_1
15
36
35
34
33
32
31
30
29
28
27
249
14
43
42
8
7
6
5
4
3
2
1
45
17
19 16
12
25
11
13
38
22
41
21
39
44
18
40
26
37
2010
23
K
2
1
R2587R3936
PD111
PR1133
PR3937
PC2193
PR3935
R3934
R2588
PC2192
PC2191
PC2190
PR1131
R3933
PC2189
PU289
PR2106
R2586
PR3929
PR3930
PR3928
PC2103
PC2188
PR2149
R1714
R3925
PC2187PC2186
R3924
R1117
ADDR
VDD18
VDD33_2
VDD33_1
VINSEN
VIN10
FLT_TYPE
GND2
VIN1
VOUT4
VOSEN
VOUT10
VIN9
CS
IMON
VOUT6
SS
SCREF_OCWREF
OCREF
VTEMP
VIN6
VIN5
ON
VOUT8
PG||OCW#
VIN8
MODE
VOUT7VIN7
GOK
ALT#
VOUT9
VOUT5
D_OC
SCL
VIN_UVW#
SDA
GND1
VIN4
VIN3
EN
VIN2
VOUT1
VOUT2
VOUT3
2
1
2
1
21
2
1
2
1
21
21
2
1
2
1
2
1
2
1
2
1
21
2
1
2
1
21
21
21
2
1
2
1
2
1
2
1
21
2
1
2
1
21
2
1
21
2121
21
21
1
SHEETDATE
23
7 3 2 16 5 4
E
A
B
C
E
D
C
B
A
7 6 5 4
D
DEPARTMENT
SIZE
PROJECT DOCUMENT NUMBER REV
REVIEWER
DESIGNER
OUT
OUT
IN
IN
OUT
OUT
IN
IN
OUT
OUT
OUTIN
OUT
IN
BI
OUT
PR3931
PR3932
PR3926
PR3927
C



VOUT SLEW RATE: 2V/MS
20211112 MODIFY FOR GT
SOFT START TIME=6MS.
VOUT SLEW RATE: 2V/MS
SOFT START TIME=6MS.
HOT SWAT CIRCUIT
Thu Aug 24 14:09:08 2023
MB FABCGTI
263 OF 365
V02
<NAME_2>
<NAME_1>
AGND_HSC
AGND_HSC
HSC_VDD
AGND_HSC
P12V_PSU
AGND_HSC
AGND_HSC
AGND_HSC
AGND_HSC
P12V_PSU
AGND_HSC
P12V_AUX
P12V_AUX
HSC_VDD
263
264
1/16W
0.068UF
HSC_VTEMP
HSC_FAULT
HSC_SCREF_2HS C B OM1
HSC BOM1
1/16W
HSC BOM1
HSC BOM1
1% 0402LF
5%
CHIP
HSC_SCREF_1
HSC_CS_1
HS C B OM1
0402LF
HSC BOM1
264
HSC BOM1
264 265 263
264 265 263
264 265 263
265
263
263 264 265
264 265 263
264 265 263
264265
263
263265
263 264 265
263264265
263264265
264 265 263
263 264 265
263264
265
264265
263264
265
263 264 265
HSC_FAULT
HSC_VTEMP
16V
HSC BOM1
0.068UF
0402
0402LF
1/16W
HSC_D_OC_2 0
HSC BOM1
HSC_D_OC_R
CHIP
0402LF
HSC BOM1
HSC_IMON
1/16W
CHIP
HSC BOM1
HSC_CS_2
CHIP
5%
0
0402LF
0402LF
50V
0.1%
2K
HSC BOM1HSC BOM1
EMPTY
HSC BOM1
1/16W
0402LF
0
CHIP
5%
MP5991GLU-Z
HSC BOM1
HSC BOM1
CHIP
HSC_FLT_TYPE
CHIP
5%
HSC BOM1
HSC_D_OC_1 HSC_D_OC_R
HSC_FLT_TYPE_1
1/16W
5%
0
1/16W
0
0402LF
2K 2K
HSC_IMON
MP5991GLU-Z
SMLF
HSC BOM1
HSC_VDD_R_1
HSC_OCREF
0.1%
1/16W
EMPTY
0.1%
1/16W50V
CHIP HS C B OM1
1NF
HS C B OM1
0402LF
1UF
SMLF
0402
1NF
2K
IC
0402
C0402
25V
0
0402
X7R
120K
0402
CHIP
0
IC
X7R
0
1UF
CHIP
5%
0402
X7R
16V
HSC MP5990 (2/3)
HSC_NC1_2
HSC_SS
HSC_SCREF
HSC_MODE_2
HSC_OCREF
HSC_VDD_R_2
HSC_SS
HSC_ON
HSC_MODE_1
5%
CHIP
1/16W
X6S
CHIP
1/16W 0402LF
50V
220PF
HSC_NC1_1
0402LF
0402LF
HSC BOM1
25V
X6S
C0402
HSC BOM1
1%
1/16W
0402LF
CHIP
120K
HS C B OM1
HSC_SCREF
HSC_ON1/16W
50V
EMPTY
220PF 0.1%
HSC_FLT_TYPE_2
1/16W
5%
CHIP
HS C B OM1
HSC_FLT_TYPE
0402LF
PC2348
18
32
31
30
29
28
27
26
25
2
1
33
16
15
14
13
12
11
10
9
21
19
17
4
24
7
8
22
5
20
6
3
23
18
32
31
30
29
28
27
26
25
2
1
33
16
15
14
13
12
11
10
9
21
19
17
4
24
7
8
22
5
20
6
3
23
PR3919
PR3920
PC2184
PR3921
PR3922
PC2185
PU287
PR3918
PR3916
PR3914
PC2347
PR1134
PC2182
PR3910
PC1525
PR3917
PU288
PR1101PR3915
PR3912
PR3911
PC2181
PC2183
NC1
FLT_TYPE
SCREF_OCWREF
MODE
VOUT10
VOUT9
VOUT8
VOUT7
VOUT6
VOUT5
VIN9
VIN8
VIN7
VIN6
D_OC
VOUT4
VOUT3
VOUT2
VOUT1
VTEMP
GOK
SS
GND
VDD33
IMON
CS
OCREF
ON
VIN5
VIN4
VIN3
VIN2
VIN1
NC1
FLT_TYPE
SCREF_OCWREF
MODE
VOUT10
VOUT9
VOUT8
VOUT7
VOUT6
VOUT5
VIN9
VIN8
VIN7
VIN6
D_OC
VOUT4
VOUT3
VOUT2
VOUT1
VTEMP
GOK
SS
GND
VDD33
IMON
CS
OCREF
ON
VIN5
VIN4
VIN3
VIN2
VIN1
21
21
2
1
21
21
2
1
2
1
21
2
1
2
1
21
2
1
2
1
21
2
1
2
1
2
1
21
2
1
2
1
2121
1
SHEETDATE
23
7 3 2 16 5 4
E
A
B
C
E
D
C
B
A
7 6 5 4
D
DEPARTMENT
SIZE
PROJECT DOCUMENT NUMBER REV
REVIEWER
DESIGNER
IN
IN
OUT
IN
OUT
OUT
IN
OUT
IN
OUT
OUT
IN
OUT
IN
IN
IN
OUT
IN
C



VOUT SLEW RATE: 2V/MS
SOFT START TIME=6MS.
VOUT SLEW RATE: 2V/MS
SOFT START TIME=6MS.
20211116 MODIFY FOR GTHOT SWAT CIRCUIT
Thu Aug 24 14:09:08 2023
MB FABCGTI
264 OF 365
V02
<NAME_2>
<NAME_1>
AGND_HSC
AGND_HSC
AGND_HSC
P12V_PSU
HSC_VDD
AGND_HSC
P12V_PSU
AGND_HSC
AGND_HSC
AGND_HSC
AGND_HSC
P12V_AUX
P12V_AUX
HSC_VDD
264
MP5991GLU-Z
MP5991GLU-Z
HSC BOM1
0402LF
1/16W
0.1%
HSC BOM1
0402LF
HS C B OM1
265
263
263264
265
264 265 263
263 264 265
263264
265
264265
263
263 264 265
264 265 263
263264265
263264265
263264265
264 265 263
263 264 265
263264265
264 265 263
264 265 263
264 265 263
263 264 265
0402LF
HSC_CS_4
HSC_IMON
HSC BOM1
HSC BOM1HSC BOM1
50V 50V 1/16W
0402LF
HSC BOM1
0.1%
2K
C0402
EMPTY
1NF220PF
CHIP HSC_ON
HSC BOM1
HSC BOM1
X6S
25V
1UF
CHIP
1/16W
5%
HSC BOM1
0402
X7R
16V
0.068UF
0402LF CHIP
5%
CHIP
5%
0
HSC BOM1
0402LF
HSC_D_OC_3 HSC_D_OC_R
HSC_FLT_TYPEHSC_FLT_TYPE_3
SMLF
IC
HSC_VDD_R_3
1%120K
1/16W 0402LF CHIP HSC_ON
HSC BOM1
HSC_IMON
1/16W
HSC_MODE_3
HSC BOM1
1/16W
HSC_SCREF_3
1/16W CHIP
0402
CHIP
0.1%
2K
0402LF
CHIP
1/16W
0
5%
1/16W
SMLF
IC
EMPTY
0402
1UF
C0402
0
5%
CHIP
EMPTY
1/16W CHIP
0402
EMPTY CHIP
2K 2K
CHIP
0402
X7R
5%
1/16W
0
1/16W
0
HSC MP5990 (3/3)
HSC_NC1_3
HSC_FLT_TYPE
HSC_D_OC_R
HSC_SCREF
HSC_MODE_4
HSC_SCREF
HSC_OCREF
HSC_FAULT
HSC_SS
HSC_SCREF_4
HSC_VDD_R_4
HSC BOM1
HSC BOM1
0402LF
0402LF
5%
0X6S
25V
50V
HSC BOM1
50V
HSC_OCREF
220PF
0402
1NF 0.1%
HSC_CS_3
HS C B OM1
HS C B OM1
HSC BOM1
HSC_VTEMP
0402LF
0402LF1%120K
HSC BOM1
HS C B OM1
HSC_VTEMP
HSC_FAULT
HSC_NC1_4
HSC_FLT_TYPE_4
0
HS C B OM1
5%
0
1/16W
HSC_D_OC_4
0402LF CHIP
CHIP1/16W 0402LF
HS C B OM1
HSC_SS
HSC BOM1
16V
0.068UF
18
32
31
30
29
28
27
26
25
2
1
33
16
15
14
13
12
11
10
9
21
19
17
4
24
7
8
22
5
20
6
3
23
18
32
31
30
29
28
27
26
25
2
1
33
16
15
14
13
12
11
10
9
21
19
17
4
24
7
8
22
5
20
6
3
23
PR3992
PR3993
PC2226
PR3994
PR3995
PC2227
PR3990
PR3988
PR3986
PR3982
PC2224
PR3980
PC3272
PR3989
PR3991PR3987
PR3984
PR3981
PC2223
PC2225
NC1
FLT_TYPE
SCREF_OCWREF
MODE
VOUT10
VOUT9
VOUT8
VOUT7
VOUT6
VOUT5
VIN9
VIN8
VIN7
VIN6
D_OC
VOUT4
VOUT3
VOUT2
VOUT1
VTEMP
GOK
SS
GND
VDD33
IMON
CS
OCREF
ON
VIN5
VIN4
VIN3
VIN2
VIN1
NC1
FLT_TYPE
SCREF_OCWREF
MODE
VOUT10
VOUT9
VOUT8
VOUT7
VOUT6
VOUT5
VIN9
VIN8
VIN7
VIN6
D_OC
VOUT4
VOUT3
VOUT2
VOUT1
VTEMP
GOK
SS
GND
VDD33
IMON
CS
OCREF
ON
VIN5
VIN4
VIN3
VIN2
VIN1
21
21
2
1
21
21
2
1
2
1
21
2
1
2
1 PC2350
21
2
1
2
1
21
2
1
2
1
2
1 PC2349
21
2
1
2
1
2121
1
SHEETDATE
23
7 3 2 16 5 4
E
A
B
C
E
D
C
B
A
7 6 5 4
D
DEPARTMENT
SIZE
PROJECT DOCUMENT NUMBER REV
REVIEWER
DESIGNER
IN
OUT
IN
OUT
OUT
IN
IN
OUT
IN
OUT
OUT
IN
OUT
IN
IN
IN
OUT
IN
C
PU296
PU297



Thu Aug 24 10:15:57 2023<NAME_2>
<NAME_1>
MB FABCGTI V02
265 OF 365Blank
1
SHEETDATE
23
7 3 2 16 5 4
E
A
B
C
E
D
C
B
A
7 6 5 4
D
DEPARTMENT
SIZE
PROJECT DOCUMENT NUMBER REV
REVIEWER
DESIGNER
C



20220308 MODIFY FOR GT
LATCH OFF MODE
FPH=220AOCW=220A
RDS(ON)=0.76M OHMAT 4.5V, ID=300A
UV =10.091V
OV =14.333V
OCP=240A
HOT SWAT CIRCUIT
Thu Aug 24 14:09:31 2023<NAME_2>
<NAME_1>
MB FABCGTI V02
266 OF 365
P12V_HSC_SENSE2_P
P12V_AUX
P12V_MAIN_R
P12V_PSU
P12V_MAIN_R_0
267
267 268
267 267
267
267
268
268
267 268
267
267
267
267
268
267
268
268
267
267 268
267
267
267
267
268
267
267
267
267
267
267
267268
267
267
267
HSC BOM2
HSC BOM2
10
1/16W
CHIP
HSC BOM2
PSMNR58-30YLH
HSC BOM2
HSC BOM2
1%
SMLF
PSMNR58-30YLH
HSC BOM2
PSMNR58-30YLH
SMLF
P12V_HSC_GATE_G3
CHIP
1/16W
1%
P12V_HSC_GATE_G4
IC
HSC BOM2
HSC BOM2
HSC BOM2
1%
1/16W
P12V_HSC_GATE_G5
PSMNR58-30YLH
SMLF
HSC BOM2
CHIP
0402LF
1/16W
P12V_HSC_GATE_G6
SMLF
PSMNR58-30YLH
HSC BOM2
HSC BOM2
1/16W
1%
HSC BOM2
33NF
25V
10% 0402LF
P12V_HSC_GATE_RC
HS C B OM2
SS15P3S-M3/86A
IC
HSC BOM2
SMLF
HSC BOM2
0402LF
CHIP
1/16W
1%
10
HSC BOM2
HSC BOM2
PSMNR58-30YLH
1%
P12V_HSC_SENSE2_R1_P
CHIP
HSC BOM2
HSC BOM2
HSC BOM2
HSC BOM2
P12V_HSC_SENSE1_N
SMLF
HS C B OM2
4W
P12V_HSC_SENSE2_R4_P P12V_HSC_SENSE2_R4_N
0.0003
4W
SMLF
P12V_HSC_SENSE2_R2_P
0.0003
SMLF
SMLF
HSC BOM2
HSC BOM2
HSC BOM2
HSC BOM2 P12V_HSC_SENSE2_R4_N
10
10 1%
HSC BOM2
CHIP1%1
HSC BOM2
CHIP
1%1
HSC BOM2
100
10
10
10
10
CHIP
10
1%
1%
1
P12V_HSC_ADC_N
P12V_HSC_SENSE1_P
CHIP
1%
0402LF
P12V_HSC_SENSE2_R4_P
P12V_HSC_SENSE2_R3_P
P12V_HSC_SENSE2_R2_P
P12V_HSC_SENSE2_R1_P
P12V_HSC_ADC_P
CHIP
CHIP
CHIP
CHIP
1%
1%
1%
HSC BOM2
HSC BOM2
HSC BOM2
CHIP1%
HSC BOM2
HSC BOM2
CHIP
CHIP1
1%1
1
1%
0402LF
CHIP
10
1/16W
0402LF
SMLF
IC
10
0402LF
IC
0402LF
CHIP
10
1
CHIP 1%
0.0003
1%
1%
CHIP
4W
1 CHIP
CHIP
0402LF
10
1%
IC
EMPTY
IC
0402
1/16W
SMLF
PSMNR58-30YLH
CHIP
IC
1%
CHIP
CHIP
1%
1% CHIP
1%10 CHIP
PR6002 CHANGE TO CS+003DFR03
P12V HOTSWAP FOR MODULE(1/2)
P12V_HSC_SENSE2_R3_P
P12V_HSC_GATE2
P12V_HSC_GATE1
P12V_HSC_SENSE2_R1_P
P12V_HSC_SENSE1_N
P12V_HSC_GATE_G2
P12V_HSC_GATE_G1
1%
1/16W
HSC BOM2
1%
1%
P12V_HSC_SENSE2_R4_N
P12V_HSC_SENSE2_R3_N
HSC BOM2
HSC BOM2
HSC BOM2
HSC BOM2
P12V_HSC_SENSE2_R3_N
P12V_HSC_SENSE2_R2_N
CHIP
CHIP1%
P12V_HSC_SENSE2_N
P12V_HSC_SENSE2_R1_N
HSC BOM2
10
P12V_HSC_SENSE2_R4_P
P12V_HSC_SENSE2_R3_P
P12V_HSC_SENSE2_R2_P
P12V_HSC_SENSE2_R2_N
P12V_HSC_SENSE2_R1_N
0.003
2W
P12V_HSC_SENSE1_P
SMLF
P12V_HSC_SENSE2_R2_N
4W
SMLF
CHIP
0.0003
P12V_HSC_SENSE2_R3_N
P12V_HSC_SENSE2_R1_N
IC
MB0_CM_GATE_G0
10 1%10
E MP TY
50V10%E MP TY
C0402
1NF
PR2527
PR2526
PR2525
PR2524
PR2519
PR2518
PR2517
PR2516
PR2515
PR2514
Anode_2
Cathode
Anode_1
2B
2A
1B
1A
4
44
2B
2A
1B
1A
2B
2A
1B
1A
5
3
2
1
K
2
1
5
3
2
1
5
3
2
1
PR6002
PPQ7 PPQ8
PPQ9
PD17
PPQ2
PR2536
PPQ1
PR2535
PR6001
2B
2A
1B
1A
PR2532
PR2533
PR2534
PR2531
PPQ6
PR2530
PPQ5
PR2529PR2528
21
PR2510
21
PR2511
PR2512
PR2513
21
PR2520
PR2522
21
PR2521
PR2523
BOM NOTE:
1A 2A
1B 2B
D1
G1
S3 S2 S1
4
D1
G1
S3 S2 S1
4
D1
G1
S3 S2 S1
4
D1
G1
S3 S2 S1
4
D1
G1
S3 S2 S1
4
1A 2A
1B 2B
1A 2A
1B 2B
1A 2A
1B 2B
1A 2A
1B 2B
D1
G1
S3 S2 S1
4
D1
G1
S3 S2 S1
4
1
2 5
3
1
2 5
3
1
2 5
3
1
2 5
3
1
2 5
3
1
2 5
3
1
2 5
3
21
21
21
21
21
21
21
21
21
21
4 4
2
1
2
1 PR2537
2
1 PC1751
2
1
2
1
2
1
2B
2A
1B
1A
44
21
21
21
21
5
3
2
1
5
3
2
1
5
3
2
1
5
3
2
1
1
SHEETDATE
23
7 3 2 16 5 4
E
A
B
C
E
D
C
B
A
7 6 5 4
D
DEPARTMENT
SIZE
PROJECT DOCUMENT NUMBER REV
REVIEWER
DESIGNER
OUT
OUT
OUT
OUT
OUT
IN
OUT
OUT
OUT
OUT
OUT
OUT
IN
IN
IN
IN
IN
OUT
IN
IN
IN
IN
IN
OUT
IN
IN
IN
IN
OUT
IN
IN
IN
IN
IN
PR2538
PC1750
C



U
2ND SOURCE:AL000788001 (G788P81U(MSOP8))
MAIN SOURCE:AL007718001 (NCT7718W(MSOP))
PROCHOT
OC DETECT ON MODULE
20221005 ADD CO-LAY DESIGN
ADDRESS: 0X4C (7-BIT)
ADDRESS: 0X98 (8-BIT)
Q6001 CLOSE TO MOSFET
LTC4287=1.5V
LTC4282=1.0V
Thu Aug 24 14:09:31 2023<NAME_2>
<NAME_1>
MB FABCGTI V02
267 OF 365
P3V3_AUX
P3V3_AUX
P3V3_AUX
P3V3_AUX
P3V3_AUX
P3V3_AUX
P3V3_AUX
P3V3_AUX
P3V3_AUX
P12V_AUX
P12V_PSU
P3V3_AUX
P12V_AUX
P3V3_AUX
54.9K
SCONN21_91930-31121LF
MB0_P12V_STBY_PWRGD
SMB_SML1_PMBUS_HSC_R1_SCL
IRQ_SML1_PMBUS_ALERT_N
SMB_SML1_PMBUS_HSC_R1_SDA
268
243
263
0402LF
HSC_TYPE_ADC
CHIP
HSC_CSOUT
IRQ_HSC_FAULT_N
SMLF
80
269
85 263
HSC_EN269
263
269
272
1%
268
267
267
267
267
267
253 268
82
253 268
253 268
267
268
82
253 268
263 80
268
268
189254
151
151
263
267
267
SMLF
METR3904-G
HSC BOM2
P12V_HSC_TEMP_R
P12V_HSC_TEMP_E
1/16W
0402LF CHIP
1/16W
P12V_HSC_TEMP_D-
C0402
HSC BOM2
0402LF 1/16W
10.5K
HSC BOM2
CHIP
1/16W
1%
P 12V _HS C_TE MP _A LE RT_N
S MB _P 12V _HS C_TE MP _S DA
S MB _P 12V _HS C_TE MP _S CL
CHIP
5%
1/16W
HSC BOM2HSC BOM2
2.2K2.2K
1/16W
CHIP
HSC BOM2
HSC BOM2100NF
HSC BOM2
AP331AWG-7
EMPTY
EMPTY
0402LF
10K
1/16W
LM4040AIM3X-2.5/NOPB
0402LF
HSC BOM2
1%
1/16W
EMPTY 10K
OC_P2V5_COMP
HSC_OC_VOL
1%
1/16W
HSC BOM2
1/16W
5%
HSC BOM2
0402LF
HSC BOM2
EMPTY
HSC BOM2
EMPTY
0.1UF
A_HSC_LOW
A_HSC_HIGH
HSC BOM2
0402LF
EMPTY
1/16W
160K
HSC BOM2
1%
0402LF
EMPTY
1/16W
HSC BOM2
HSC BOM2
160K
1%
10K
EMPTY
HSC BOM2
1K
25V
1UF
0402
1/16W
1/16W
EMPTY
10K
HSC_CSOUT
P12V_PSU
P12V_HSC_SENSE1_P
P12V_HSC_SENSE1_N
P12V_HSC_SENSE2_P
P12V_HSC_SENSE2_N
P12V_HSC_ADC_P
0
EMPTY
A_HSC_LOW_DRAIN
S MB _P 12V _HS C_S DA
P 12V _HS C_TE MP _A LE RT_R_N
S MB _P 12V _HS C_S CL
S MB _P 12V _HS C_S DA
P12V_HSC_T_CRIT_N
P12V_HSC_ADC_N
HSC_CSOUT
P12V_HSC_T_CRIT_R_N
S MB _P 12V _HS C_S CL
HSC_D_OC
U142_VS
P12V HOTSWAP FOR MODULE(2/2)
0402LF
EMPTY
1/16W
10K
1%
EMPTY
33.2
C0402
50V
EMPTY
C0402
EMPTY
S MLF
NCT7718W
IC
0402LF
0402LF
5%0 CHIP
1/16W
0
0402LF
0
5%
1/16W
EMPTY
10K
1%
SMLF
EMPTY
10K
1%
1%
0402LF
CHIP
0402LF0402LF
0
0402LF
0603
5%
0402LF
0
0402LF
10%
0402
0.1UF
X7R
25V
10%
EMPTY
1%
10%
1/16W
IC
25V
C0402
0402LF
CHIP
HSC BOM2
HSC BOM2
2N7002K
EMPTY
0402LF
A_HSC_LOW_GATE
0402LF
CHIP
1/16W
0402LF
HSC BOM2
5%
LT6700CS6-1#TRPBF
SMLF
HSC BOM2
1/16W
EMPTY
0402LF
HSC BOM2
1%0402LF1/16W1M
EMPTY
HSC BOM2
SMLF
0402LF
HSC BOM2
160K
1%
1/16W
EMPTY
HSC BOM2
10%
50V
100NF
EMPTY
10%
HSC BOM2
HSC BOM2
50V
10%
EMPTY
C0402
HSC BOM2
SMLF
HSC_D_OC_R2
HSC BOM2
A_HSC_LOW_GATE
HSC BOM2
1%
100NF
IO
P12V_HSC_GATE1
P12V_HSC_GATE2
P12V_AUX
HSC BOM2
5%
1/16W
1%
HSC BOM2
10.5K
1/16W
CHIP5%
1/16W
0402LF
CHIP
5%0 CHIP
HSC BOM2
HSC BOM2
HSC BOM2
HSC BOM2
CHIP
1%
HS C B OM2
49.9
HS C B OM2
49.9
1% HS C B OM2
X 7R
10%
50V
1000P F
P12V_HSC_TEMP_D+
X 7R
10%
16V
0.1UF
HSC BOM2
1%
HSC BOM2
1/16W
C1786
G
S D
U8005
R353
R2626
R2627
R2628
C9003C6084
C8014
R354
R6239
R6233
R6231R6230
R2625
R2624
OUTPUT
IN-
IN+
GND VCC
4
1
3
3
2
1
G
5
6
1
4
3
2
G2
G1
21
20
19
18
17
16
15
14
13
12
11
10
9
8
7
6
5
4
3
2
1
1
4
7
8
5
3
2
6
C1787
52
S D
R9020
U8006
U6004U142
PJ38
U143
Q6001
SCL
SDA
ALERT#
GNDT_CRIT#
D-
D+
VDD
S
G
D
OUTB
INA+ OUTA
GND
INB-
VS
21
20
19
18
17
16
15
14
13
12
11
10
9
8
7
6
G2
G1
2
5
4
3
1
+
-
3
2-
1+
1
32
2
1
R9024
2
1
2
1
2
1
21
2
1
21
2
1
C8016
2
1
C8015
2
1
2
1
2
1
2
1
2
1
2
1
21
2
1
R6238
2
1
2
1
R6237
2
1
2
1
2
1
2
1
2
1
2
1
2
1
21
21
2
1
21
2
1
2
1
21
21
B
CE
1
SHEETDATE
23
7 3 2 16 5 4
E
A
B
C
E
D
C
B
A
7 6 5 4
D
DEPARTMENT
SIZE
PROJECT DOCUMENT NUMBER REV
REVIEWER
DESIGNER
OUT
OUT
OUT
IN
OUT
OUT
OUT
IN
IN
IN
IN
IN
OUT
IN
OUT
OUT
IN
OUT
OUT
IN
OUT
BI
IN
BI
OUT
IN
IN
R8111
R8110
R8108
R8109
R8107
R355
R6236
R6235
R6232
PC1789
C
R8112
21
R6234
R6210



20211208 ADD FS1
20211203 CHANGE JP4003 CONNECT
JUMPER 1-2
NOTE:NEED TO SET UV VOL
Thu Aug 24 14:09:30 2023<NAME_2>
<NAME_1>
MB FABCGTI V02
268 OF 365
I42
P12V_AUX P3V3_AUX
P12V_AUX
P12V_AUX
P12V_AUX
P3V3_AUX
P3V3_AUX
P12V_PSU
P3V3_AUX
P12V_AUX
AGND_HSC
P12V_AUX
P12V_AUX
P3V3_AUX
P3V3_AUX
151 268
151 268
269 80
269
80
263 268
269
269
269 80
269 80
241
U206_VS
267K
1/16W
25V
CONN3_210-HP1-030BR1
THLF
IO
SMB_SML1_PMBUS_HSC_R1_SDA
SMB_SML1_PMBUS_HSC_R1_SCL
10%
EMPTY LT6700CS6-1#TRPBF
10K
0402LF
1UF
25V
E MP TY
0402
0.1UF
10%
C0402
1/16W
1K
EMPTY
1%
SMLF
EMPTY
0402LF0402LF
FM_UV_ADR_TRIGGER_N
EMPTY
1/16W
5%
0402LF
CONN3_210-HP1-030BR1
VR_DDR1_POWER_STAGE
THLF
SMLF
LM4040AIM3X-2.5/NOPB
P12V_AUX_UV_TRIGGER
IC
AP331AWG-7
BSS138K
0402LF
EMPTY
IRQ_UV_DETECT_N
1/16W
A_P12V_STBY_FPH_GATE
1%
1K
EMPTY
A_P12V_STBY_ADR_TRIGGER
A_P12V_STBY_FP_TRIGGER
0402LF
EMPTY
26.7K
0402LF
EMPTY
1/16W
1/16W
EMPTY
50V
CHIP
33.2
C0402
17.8K
1%
1/16W
CHIP
0402LF
CHIP
1/16W
CHIP
SMLF
IRQ_UV_DETECT_R2_N
AP331AWG-7
EMPTY
C0402
X7R
10%
SMLFUV_ADR_P2V5_COMP
P12V_AUX_UV_ADR_TRIGGER
100NF
10%
CHIP
100NF
CHIP
1%
0402LF
1/16W
BSS138K
1%
1%
0402LF
0402LF
1K
1%
1%
EMPTY
IC
1%
EMPTY
1%
0402LF
1%
10K
0402LF
1%
100NFIC
10%
C0402
100NF
50V
17.8K
10K
1%
C0402
HSC_EN
50V
C0402
HSC Shared Circuit
IC
20A/125V
SMLF
IC
5.0SMDJ14A
IC
SMLF
5.0SMDJ14A
P12V_PSU_FUSE
SMLF
0
CHIP1/16W
2N7002K
IC
SMLF
10%
100NF
X7R
50V
C0402
IO
0402LFCHIP
1%
1/16W
82K
CHIP
31.6K
1%
0402LF
1/16W
VR_DDR1_POWER_STAGE
VR_DDR1_POWER_STAGE
0402LF
63.4K
1/16W
1%
0402LF
1/16W
1%
33K
0402
X7R
25V
10%
0.1UF
P12V_PSU_FUSE
50V
1/16W
1% 1M
SMLF
0402LF
UV_P2V5_COMP
5.11K
1%
1/16W
EMPTY
10% 10%
50V
100NF
IC
CHIP
1/16W
5.11K
CHIP
0402LF
EMPTY
0402LF
1%
1%
CHIP
LM4040AIM3X-2.5/NOPB
CHIP
C0402
10K
1/16W
1K
1/16W
1/16W
FM_UV_ADR_TRIGGER_N_R2 33.2 1%
100NF
50V
10%
X7R
EMPTY
0402LF1/16W1M
CHIP
0402LF
FM_UV_ADR_TRIGGER_N
1/16W
1%
1K
IRQ_UV_DETECT_N
1K
1%
1/16W
0402LF
CHIP
PDB_PRSNT_R_N
 G
S D
U290
C9004
R4620
R2227
OUTPUT
IN-
IN+
OUTPUT
IN-
IN+
GND VCC
GND VCC
3
2
1
3
2
1
4
1
3
4
1
3
3
2
1
5
6
1
4
3
2
G
3
2
1
G
52
52
S D
S D
2 1CA
CA
JP10
R9021
U8009
U8010
U8008
U8007
U206
2
1
R2233
2
1
R2230
U325
2
1
R2221
2
1
R2222
2
1
R2219
PR3002
C2179
R4901
JP4003
R3923
R2585
R3907
FS1
PD13PD15
3
2-
1+
+
-
+
-
3
2-
1+
OUTB
INA+ OUTA
GND
INB-
VS
1
2
3
S
G
D
1
2
3
2 1CA
CA
2
1
2
1
2
1
2
1
2
1
C8021
21R8124
2
1
C8022
21
2
1
C8020
2
1
2
1
2
1
2
1
21
2
1
C8019
21
R8117
2
1
2
1
2
1
2
1
2
1
2
1
2
1
21
2
1
21
2
1
1
SHEETDATE
23
7 3 2 16 5 4
E
A
B
C
E
D
C
B
A
7 6 5 4
D
DEPARTMENT
SIZE
PROJECT DOCUMENT NUMBER REV
REVIEWER
DESIGNER
OUT
IN
OUT
OUT
OUT
OUT
IN
OUT
BI
IN
R8125
C1561
R8120
R8119
R8118
R8113
C1797
C
R8123
R8121
R8122
C8017
R8114
R8115 C8018



RCS=10K OCP=3A
PCMC063T-3R3MN
DCR=30 MOHM
ISAT=12A @100C
7.3*6.6*3
ENABLE: VIH>1.27V
FCCM/FREQ.=600KHZ
R1
OVER CURRENT PROTECTION(IMAX*1.3)=3A
SLEW RATE=2.5A/US
WORK FREQUENCY=600KHZ
EFFICENCY>90%@TDC
VOUT=0.6(1+R1/R2)=1.8V
DESIGN SPECIFICATION
OUTPUT VOLTAGE=1.8V +/-5%
OUTPUT RIPPLE<30MV
TRANSIENT TOLERANCE<100MV
MAX CURRENT=2.0A
TDC=2.0A
R2
2ND
3RD
R&C TABLE
1ST
IC TABLE
3RD AL54J061000/TPS54J061RPGR/TI
2ND AL053317005/RS53317LR/REEDSEMI
1ST AL008626000/MPQ8626GD-Z/MPS
Thu Aug 24 14:09:33 2023<NAME_2>
<NAME_1>
MB FABCGTI V02
269 OF 365
P1V8_AUX
P3V3_AUX
P12V_AUX
P3V3_AUX
1%
10K
C0402
SW_P1V8_AUX_BT_R
C0402
SW_P1V8_AUX_PH
X7R
0.22UF
10%
25V2.2S W _P 1V 8_A UX _B T
3.3UH/6A
SMLF
IND
10%
X7R
100NF
C0402
50V
22UF
4V
C0805
X6S
20%
1/16W
CHIP
0402LF
CHIP
P1V8_AUX_REF
0402LF1/16W
3300PF
50V
0402LF
0402LF1/16W
P1V8_AUX_MODE
CHIP
0.1UF
C0805
X6S
16V
20%
C0402
22UF
MPQ8626GD-Z
IC
SMLF
C0402
25V
1UF
0402
10%
10%
330PF
0402
50V
X7R
1%
10K
22UF
4V 4V
22UF
20%
X6S
C0805
X6S
22UF
C0805
20%
4V
100NF
IND SMLF
BLM18SN220TN1D/8000MA
22UF
CCBU
P1V8_AUX_FB
P1V8_AUX_CS
20%
X6S
C0805
1%X7R 10K
10%
X6S
P1V8_AUX
P1V8_AUX_VCC
C0805
0402LF
25V
1/16W 5%
0402
PWRGD_P1V8_AUX_R
0
5%
1/16W
EMPTY
10%
25V
1UF
60.4K
CHIP 1%
X6S
10%
X6S
16V
SW_P12V_AUX_P1V8_AUX_FLT
P1V8_AUX_ENABLE
1/16W
CHIP
PWRGD_P3V3_AUX
50V
10%
X7R
0
20%
20K 1%
0402LF
0402LF CHIP 1%
PWRGD_P1V8_AUX
CHIP
1/16W
0402LF
33 27125514881
85
81
190
R214
PR8003
PC850PC867PC866
R6243
PC641
PC865
PR6007
PC6021
PC6019
PL6000
PR6010
PC384
PC6010
PU6000
PR6006
PC6008
PC6014PC6012
PL6002
PC6020
R6242
21
3
13
8
11
2
9
14
1
12
6
5
4
10
7
21 1 2
1 2SW1
CS
MODE
TRK_REF
SW2
PGND1
VCC
AGND
FB
BST
EN
PGND2
PGOODVIN
21
21
2
1C345
21
2
1
2
1
2
1
2
1
2
1
2
1
21
2
1
212
12
1
2
1
21
2
1
2
1
2
1
2
1
2
1
2
1
R6119
1
SHEETDATE
23
7 3 2 16 5 4
E
A
B
C
E
D
C
B
A
7 6 5 4
D
DEPARTMENT
SIZE
PROJECT DOCUMENT NUMBER REV
REVIEWER
DESIGNER
OUT
IN
PR6003
C



RCS=11.5K OCP=3A
3RD
R1
2ND
1ST
IC TABLE
MAX CURRENT=2.1A
OVER CURRENT PROTECTION(IMAX*1.3)=3A
SLEW RATE=2.5A/US
WORK FREQUENCY=600KHZ
EFFICENCY>90%@TDC
TRANSIENT TOLERANCE<100MV
OUTPUT VOLTAGE=1.2V +/-5%
DESIGN SPECIFICATION
TDC=1.6A
OUTPUT RIPPLE<30MV
FCCM/FREQ.=600KHZ
ENABLE: VIH>1.27V
VOUT=0.6(1+R1/R2)=1.2V
R2
DCR=20 MOHM
PCMC063T-2R2MN
ISAT=13.5A @100C
7.3*6.6*3
R&C TABLE
1ST AL008626000/MPQ8626GD-Z/MPS
2ND AL053317005/RS53317LR/REEDSEMI
3RD AL54J061000/TPS54J061RPGR/TI
Thu Aug 24 14:09:33 2023<NAME_2>
<NAME_1>
MB FABCGTI V02
270 OF 365
I15
I4
I36
I30
I8
I22
I14
I20
I1
I5
P3V3_AUX
P3V3_AUX
P12V_AUX
P1V2_AUX
81 255
27081148
255
SW _P1V2_AU X_BT_R
CHIP 1%0402LF
S W _P 1V 2_A UX _B T
PWRGD_P1V2_AUX_R
0402LF
10K
X7R
1/16W
P1V2_AUX_VCC
60.4K
0402LF 5%
P1V2_AUX_ENABLE
C0805
C0402
22UF
10%
X7R
16V
20%
X6S
C0805 C0402
1%
BLM18SN220TN1D/8000MA
50V
100NF
P1V2_AUX_REF
0
1/16W
10%
11.5K
1%
C0402
25V
CHIP
X6S
0
25V
0.1UF
X6S
16V
P1V2_AUX
1/16W
SW_P12V_AUX_P1V2_AUX_FLT
P1V2_AUX_CS
P1V2_AUX_MODE
CCBU
CHIP
1/16W
X6S
22UF
C0805
20%
4V
22UF
20%
X6S
10%
330PF
0402
50V
X7R
0402LF
IND SMLF
1%
10%
MPQ8626GD-Z
IC
SMLF
X6S
10%
25V
1UF
1%
22UF
20%
EMPTY
CHIP
CHIP
10K
50V
P1V2_AUX_FB
0
0402LF
1%
1/16W
0402
3300PF
10K
1/16W
CHIP
0402
10%
1UF
0402LF
0402LF
CHIP
5%
1/16W
0402LF
1/16W
PWRGD_P1V8_AUX_R
C0805
4V
PWRGD_P1V2_AUX
5%
4V
C0805
X6S
20%
22UF
C0805
22UF
4V
20%
X6S
100NF
50V
10%
X7R
C0402
2.2UH
SMLF
INDC0402
X 7R
10%
25V
0.22UF
SW_P1V2_AUX_PH
2.2
0402LF
CHIP
PC6023
PC6018PC6026PC6025PC6024
PR6008
PC852
PL6001
PC6022
PR6011
R6244
PC6017
PC6016
PU6001
PC6011
PR6005
PC6015
PC6009
PR6004
PC6013
PL6003
R6245
21
3
13
8
11
2
9
14
1
12
6
5
4
10
7
21
1 2
1 2
SW1
CS
MODE
TRK_REF
SW2
PGND1
VCC
AGND
FB
BST
EN
PGND2
PGOODVIN
21
21
2
1C6085
21
2
1
2
1
2
1
2
1
2
1
21
21
2
1
2
1
2
1
2
1
2
1
2
1
21
2
1
2
1
2
1
2
1
2
1
R6241
R6240
1
SHEETDATE
23
7 3 2 16 5 4
E
A
B
C
E
D
C
B
A
7 6 5 4
D
DEPARTMENT
SIZE
PROJECT DOCUMENT NUMBER REV
REVIEWER
DESIGNER
OUT
IN
PR8004
C



ADDRESS : 0X84 (8-BIT)
0X42 (7-BIT)
Thu Aug 24 14:09:34 2023<NAME_2>
<NAME_1>
MB FABCGTI V02
271 OF 365
P3V3_AUX
P3V3_AUX
236253
253236
268
POWER MONITOR WILL CHANGE TO AL000230001
POWER MONITOR (3/4)
IC
SMLF
ISL28022FRZ-T
1/16W
0402LF
5%
0
CHIP
4.7K
1%
1/16W
CHIP
0402LFX7R
0.1UF
25V
10%
0402
X7R
0402
10%
0.1UF
25V
33.2 1% CHIP
33.2
0402LF 1/16W
1% CHIP
1/16W 1% CHIP 0402LF4.7K
0402LFEMPTY1%4.7K 1/16W HSC_TYPE_ADC_A0
SMB_HSC_TYPE_ADC_SDA
NC_HSC_TYPE_VINP
HSC_TYPE_ADC_ALERT
NC_HSC_TYPE_NC0
NC_HSC_TYPE_NC1
NC_HSC_TYPE_NC2
NC_HSC_TYPE_NC3
NC_HSC_TYPE_NC4
NC_HSC_TYPE_NC5
SMB_HSC_TYPE_ADC_SCL
HSC_TYPE_ADC_A1
SMB_LM75_0_3V3AUX_SCL
SMB_LM75_0_3V3AUX_SDA
HSC_TYPE_ADC
NC_HSC_TYPE_VINM
R6250
R6254
R6251
13
12
9
11
TH
4
5
16
15
14
8
7
6
10
3
1
2
U6005
BOM NOTE:
TH_GND
GND
NC5
NC4
NC3
NC2
NC1
NC0
EXT_CLK||INT
VINM
VINP
VBUS
SDA||SMBDAT
SCL|||SMBCLK
A0
A1
VCC
21
2
1
2
1
2
1
21
2
1
21R6253
21R6252
1
SHEETDATE
23
7 3 2 16 5 4
E
A
B
C
E
D
C
B
A
7 6 5 4
D
DEPARTMENT
SIZE
PROJECT DOCUMENT NUMBER REV
REVIEWER
DESIGNER
IN
BI
IN
R6247
C6087
C6086
C



P/N SWAP
P/N SWAP
P/N SWAP
P/N SWAP
P/N SWAP
P/N SWAP
P/N SWAP
P/N SWAP
P/N SWAP
P/N SWAP
P/N SWAP
P/N SWAP
P5E_CPU0_P0_TX_C_DP/DN<0-15> LANE REVERSAL
CPU TO RETIMERCPU TO RETIMER
P/N SWAP
P/N SWAP
Thu Aug 24 14:09:34 2023<NAME_2>
<NAME_1>
MB FABCGTI V02
272 OF 365
63
63
63
63
SMLF
PT5161LRS
IC
PT5161LRS
IC
RETIMER_CPU0_P0(1)
SMLF
P5E_CPU0_P0_TX_C_DP<7:0>
P5E_CPU0_P0_TX_C_DN<7:0>
P5E_CPU0_P0_TX_C_DN<15:8>
P5E_CPU0_P0_TX_C_DP<15:8>
EV34
EL34
ED34
DU34
DK34
DC34
CT34
CJ34
EY35
EN35
EF35
DW35
DM35
DE35
CV35
CL35
CB34
BR34
BH34
BA34
AP34
AG34
Y34
N34
CD35
BU35
BK35
BC35
AT35
AJ35
AB35
R35
1
1
2
0
3
2
14
5
7
6
5
4
3
0
4
6
11
15
12
9
8
12
11
10
9
8
7
10
15
14
13
13
U6010
U6010
9/11
B_PERN15
B_PERP15
B_PERN14
B_PERP14
B_PERN13
B_PERP13
B_PERN12
B_PERP12
B_PERN11
B_PERP11
B_PERN10
B_PERP10
B_PERN9
B_PERP9
B_PERN8
B_PERP8
8/11
B_PERN7
B_PERP7
B_PERN6
B_PERP6
B_PERN5
B_PERP5
B_PERN4
B_PERP4
B_PERN3
B_PERP3
B_PERN2
B_PERP2
B_PERN1
B_PERP1
B_PERN0
B_PERP0
RX : B_PER[15:8]
RX : B_PER[7:0]
1
SHEETDATE
23
7 3 2 16 5 4
E
A
B
C
E
D
C
B
A
7 6 5 4
D
DEPARTMENT
SIZE
PROJECT DOCUMENT NUMBER REV
REVIEWER
DESIGNER
IN
IN
IN
IN
C



RETIMER TO CPU RETIMER TO CPU
P5E_CPU0_P0_RX_DP/DN<0-15> LANE REVERSAL
Thu Aug 24 14:09:34 2023<NAME_2>
<NAME_1>
MB FABCGTI V02
273 OF 365
24
24
24
24
PT5161LRSSMLF
PT5161LRS
SMLF
IC
RETIMER_CPU0_P0(2)
P5E_CPU0_P0_RX_DP<15:8>
P5E_CPU0_P0_RX_DN<15:8>
IC
P5E_CPU0_P0_RX_DP<7:0>
P5E_CPU0_P0_RX_DN<7:0>
EU26
EK26
EC26
DT26
DJ26
DB26
CR26
CH26
EW29
EM29
EE29
DV29
DL29
DD29
CU29
CK29
CA26
BP26
BG26
AY26
AN26
AF26
W26
M26
CC29
BT29
BJ29
BB29
AR29
AH29
AA29
P29
14
14
7
7
4
0
0
15
2
12
9
10
12
8
11
13
9
11
5
6
8
10
13
3
2
15
6
3
5
1
1
4
U6010U6010
7/11
A_PETN15
A_PETP15
A_PETN14
A_PETP14
A_PETN13
A_PETP13
A_PETN12
A_PETP12
A_PETN11
A_PETP11
A_PETN10
A_PETP10
A_PETN9
A_PETP9
A_PETN8
A_PETP8
6/11
A_PETN7
A_PETP7
A_PETN6
A_PETP6
A_PETN5
A_PETP5
A_PETN4
A_PETP4
A_PETN3
A_PETP3
A_PETN2
A_PETP2
A_PETN1
A_PETP1
A_PETN0
A_PETP0
TX : A_PET[15:8]
TX : A_PET[7:0]
1
SHEETDATE
23
7 3 2 16 5 4
E
A
B
C
E
D
C
B
A
7 6 5 4
D
DEPARTMENT
SIZE
PROJECT DOCUMENT NUMBER REV
REVIEWER
DESIGNER
OUT
OUT
OUT
OUT
C



EXAMAX TO RETIMEREXAMAX TO RETIMER
P5E_CPU0_P0_RX_BUF_DP/DN<0-15> LANE REVERSAL
Thu Aug 24 14:09:35 2023<NAME_2>
<NAME_1>
MB FABCGTI V02
274 OF 365
118
118
117
117
SMLF
IC
PT5161LRS
SMLF
RETIMER_CPU0_P0(3)
PT5161LRS
IC
P5E_CPU0_P0_RX_BUF_DN<7:0>
P5E_CPU0_P0_RX_BUF_DP<7:0>
P5E_CPU0_P0_RX_BUF_DN<15:8>
P5E_CPU0_P0_RX_BUF_DP<15:8>
CD1
BU1
BK1
BC1
AT1
AJ1
AB1
R1
CB2
BR2
BH2
BA2
AP2
AG2
Y2
N2
EY1
EN1
EF1
DW1
DM1
DE1
CV1
CL1
EV2
EL2
ED2
DU2
DK2
DC2
CT2
CJ2
15
9
10
11
13
14
12
8
8
9
10
11
12
14
15
13
7
6
5
4
3
2
1
0
0
2
3
4
5
6
7
1
U6010 U6010
1/11
A_PERN7
A_PERP7
A_PERN6
A_PERP6
A_PERN5
A_PERP5
A_PERN4
A_PERP4
A_PERN3
A_PERP3
A_PERN2
A_PERP2
A_PERN1
A_PERP1
A_PERN0
A_PERP0
2/11
A_PERN15
A_PERP15
A_PERN14
A_PERP14
A_PERN13
A_PERP13
A_PERN12
A_PERP12
A_PERN11
A_PERP11
A_PERN10
A_PERP10
A_PERN9
A_PERP9
A_PERN8
A_PERP8
RX : A_PER[7:0]
RX : A_PER[15:8]
1
SHEETDATE
23
7 3 2 16 5 4
E
A
B
C
E
D
C
B
A
7 6 5 4
D
DEPARTMENT
SIZE
PROJECT DOCUMENT NUMBER REV
REVIEWER
DESIGNER
IN
ININ
IN
C



RETIMER TO EXAMAX RETIMER TO EXAMAX
P5E_CPU0_P0_TX_BUF_DP/DN<0-15> LANE REVERSAL
Thu Aug 24 14:09:35 2023<NAME_2>
<NAME_1>
MB FABCGTI V02
275 OF 365
117
117
276
276 276
276
276
276
118
118276
276
P5E_CPU0_P0_TX_BUF_C_DN<15:8>
P5E_CPU0_P0_TX_BUF_C_DP<15:8>
D IFF BU S_0.22U F
D IFF BU S_0.22U F
D IFF BU S_0.22U F
D IFF BU S_0.22U F
D IFF BU S_0.22U F
D IFF BU S_0.22U F
P5E_CPU0_P0_TX_BUF_DN<15:8>
D IFF BU S_0.22U F
D IFF BU S_0.22U F
D IFF BU S_0.22U F
D IFF BU S_0.22U F
D IFF BU S_0.22U F
D IFF BU S_0.22U F
D IFF BU S_0.22U F
D IFF BU S_0.22U F
P5E_CPU0_P0_TX_BUF_DP<15:8>
D IFF BU S_0.22U F
RETIMER_CPU0_P0(4)
IC
SMLF
PT5161LRS SMLF
PT5161LRS
IC
P5E_CPU0_P0_TX_BUF_DP<7:0>
P5E_CPU0_P0_TX_BUF_DN<7:0>
C0201 20%
X 6S
6.3V
D IFF BU S_0.22U F
P5E_CPU0_P0_TX_BUF_DN<15:8>
P5E_CPU0_P0_TX_BUF_DP<15:8>
D IFF BU S_0.22U F
D IFF BU S_0.22U F
6.3V20%
D IFF BU S_0.22U F
C0201
X 6S
D IFF BU S_0.22U F
D IFF BU S_0.22U F
D IFF BU S_0.22U F
D IFF BU S_0.22U F
D IFF BU S_0.22U F
D IFF BU S_0.22U F
D IFF BU S_0.22U F
D IFF BU S_0.22U F
D IFF BU S_0.22U F
D IFF BU S_0.22U F
D IFF BU S_0.22U F
D IFF BU S_0.22U F
D IFF BU S_0.22U F
P5E_CPU0_P0_TX_BUF_C_DN<7:0>
P5E_CPU0_P0_TX_BUF_C_DP<7:0>P5E_CPU0_P0_TX_BUF_DP<7:0>
P5E_CPU0_P0_TX_BUF_DN<7:0>
2 1
2 1
2 1
2 1
2 1
2 1
2 1
2 1
2 1
2 1
2 1
2 1
2 1
2 1
2 1
2 1
2 1
2 1
2 1
2 1
2 1
2 1
2 1
2 1
2 1
2 1
2 1
2 1
2 1
2 1
2 1
2 1
EU7
EK7
EC7
DT7
DJ7
DB7
CR7
CH7
EW10
EM10
EE10
DV10
DL10
DD10
CU10
CK10
CA7
BP7
BG7
AY7
AN7
AF7
W7
M7
CC10
BT10
BJ10
BB10
AR10
AH10
AA10
P10
11
13
12
10
8
10
10
12
8
12
13
11
12
12
11
11
11
13
11
15
14
13
9
8
9
10
14
15
7
6
5
4
3
2
1
0
0
1
2
3
4
5
6
7
9
8
9
10
10
12
13
14
14
15
15
8
9
8
9
14
13
14
15
15
0
1
2
1
0
2
3
4
3
4
5
7
6
5
6
7
0
1
2
0
2
1
3
4
3
4
5
6
7
5
6
7
C6532
C6531
C6530
C6529
C6528
C6527
C6525
C6526
C6524
C6523
C6521
C6522
C6519
C6520
C6518
C6517
C6502
C6501
C6504
C6503
C6505
C6507
C6506
C6508
C6510
C6509
C6512
C6511
C6515
C6514
C6513
C6516
U6010U6010
11/11
B_PETN15
B_PETP15
B_PETN14
B_PETP14
B_PETN13
B_PETP13
B_PETN12
B_PETP12
B_PETN11
B_PETP11
B_PETN10
B_PETP10
B_PETN9
B_PETP9
B_PETN8
B_PETP8
10/11
B_PETN7
B_PETP7
B_PETN6
B_PETP6
B_PETN5
B_PETP5
B_PETN4
B_PETP4
B_PETN3
B_PETP3
B_PETN2
B_PETP2
B_PETN1
B_PETP1
B_PETN0
B_PETP0
TX : B_PET[15:8]
TX : B_PET[7:0]
2 1
2 1
2 1
2 1
2 1
2 1
2 1
2 1
2 1
2 1
2 1
2 1
2 1
2 1
2 1
2 1
2 1
2 1
2 1
2 1
2 1
2 1
2 1
2 1
2 1
2 1
2 1
2 1
2 1
2 1
2 1
2 1
1
SHEETDATE
23
7 3 2 16 5 4
E
A
B
C
E
D
C
B
A
7 6 5 4
D
DEPARTMENT
SIZE
PROJECT DOCUMENT NUMBER REV
REVIEWER
DESIGNER
OUT
OUT
OUT
OUT
IN
IN
OUT
OUT
OUT
OUT
IN
IN
C



CPU1 P0 RT ADDR: 0X48 (8-BIT) / 0X24 (7-BIT)
Thu Aug 24 14:09:54 2023<NAME_2>
<NAME_1>
MB FABCGTI V02
276 OF 365
P 1V 8_CP U0_RT_1D
P 1V 8_CP U0_RT_1D
P 1V 8_CP U0_RT_1DP 1V 8_CP U0_RT_1D
P 1V 8_CP U0_RT_1D
P 1V 8_CP U0_RT_1D
P 1V 8_CP U0_RT_1D
SMB_RT_CPU0_P0_ROM_MUX_1D_R_SCLSMB_RT_CPU0_P0_ROM_MUX_1D_SCL
1%49.9
0201LF1/20W CHIP
SMB_RT_CPU0_P0_ROM_MUX_1D_R_SDASMB_RT_CPU0_P0_ROM_MUX_1D_SDA
185186
185186
277
277
277
81 277
81 277
277
277
277
277
277
277
277
277
277
277
277
277
277
277
277
277
277
277
277
277
277
184
184
277
277
277
81 277
182
182
81 277
277
277
277
277
277
CHIP
200
1%
1/20W
0201LF
EMPTY
JTAG_TCK_RT_CPU0_P0
RST_RT_CPU0_P0_RESET_N
JTAG_TDO_RT_CPU0_P0
JTAG_TMS_RT_CPU0_P0
EMPTY
0201LF
EMPTY
0201LF
RST_RT_CPU0_P0_RESET_R_N
RST_RT_CPU0_P0_PERST_R_N
JTAG_TRST_RT_CPU0_P0_N
JTAG_TMS_RT_CPU0_P0
JTAG_TDO_RT_CPU0_P0
JTAG_TCK_RT_CPU0_P0
0201LF
0201LF
4.7K
1/20W
0201LF
EMPTY
1/20W
1/20W
0
5%
1/20W
4.7K
4.7K
0201LF
RXDET_BYP_RT_CPU0_P0
0201LF
4.7K
5%
1/20W
IC
PT5161LRS
JTAG_TEST_MODE_RT_CPU0_P0
TEST2_RT_CPU0_P0
TEST1_RT_CPU0_P0
TEST0_RT_CPU0_P0
GPIO3_RT_CPU0_P0
GPIO2_RT_CPU0_P0
EMPTY1/20W
5%
4.7K 4.7K
10K
1/20W
0201LF
RXDET_BYP_RT_CPU0_P0
0201LF
5%
4.7K
1/20W
EMPTY
EMPTY
0201LF0201LFMODE_RT_CPU0_P0
1%
1/20W
CHIP
1/20W
EMPTY
1K
0201LF
RETIMER_CPU0_P0(5)
SMLF
GPIO2_RT_CPU0_P0
GPIO3_RT_CPU0_P0
CLK_100M_RETIMER_CPU0_P0_DN
CLK_100M_RETIMER_CPU0_P0_DP
RT_CPU0_P0_ADDR1
RT_CPU0_P0_ADDR2
RT_CPU0_P0_ADDR3
SMB_RT_CPU0_P0_R2_SCL
SMB_RT_CPU0_P0_R2_SDA
TEST0_RT_CPU0_P0
TEST1_RT_CPU0_P0
TEST2_RT_CPU0_P0
CHIP
1K
1%
0201LF
CHIP
1/20W
CHIP
1/20W
0201LF
4.7K
5% 4.7K
1% 1%
EMPTY
1K
1/20W
EMPTY
0201LF
1%
0201LF
4.7K
0201LF
EMPTY
1/20W
4.7K
CHIP
0201LF0201LF
0201LF
RT_CPU0_P0_SCAN_MODE
5%
SMB_RT_CPU0_P0_R_SDA
SMB_RT_CPU0_P0_R_SCL
20K
RT_CPU0_P0_ADDR3
4.7K
5%
1/20W 1/20W
0201LF
4.7K
1/20W
0201LF
RT_CPU0_P0_ADDR2
RT_CPU0_P0_ADDR1
CHIPCHIP
1/20W
RST_RT_CPU0_P0_RESET_R_N
CHIP
0
CLK_100M_RETIMER_CPU0_P0_R_DN
CLK_100M_RETIMER_CPU0_P0_R_DP
1/20W
0
0201LF
5%
4.7K
EMPTY
0201LF
0201LF
1%
10K
4.7K
5% 5%
0201LF
1/20W
EMPTY
5%
1/20W
5%
EMPTY
0201LF
5%
4.7K
1/20W
5%
EMPTY
0201LF
1/20W
5%
1/20W
5%
4.7K
CHIP
0201LF
CHIP
1K
1%
EMPTY
1K
1/20W 1%
1K
0201LF
1/20W
CHIP
1%
10K
1%
10K
1/20W
CHIP
0201LF
RST_RT_CPU0_P0_PERST_R_N
CHIP
0201LF
1%
51.1
0201LF
1%
1/20W
EMPTYEMPTY
1/20W
51.1
5%1/20W
10K
1%
1/20W
CHIP
0201LF
1/20W
CHIP
CHIP
0201LF
0201LF
0201LF
1/20W
0
CHIP
RST_RT_CPU0_P0_PERST_N
MODE_RT_CPU0_P0
1%
CHIP 0201LF
CLKREQ_RT_CPU0_P0_N
RT_CPU0_P0_SCAN_MODE
5%
CHIP
0201LF
1K
1%
1/20W
1K
4.7K
JTAG_TDI_RT_CPU0_P0
JTAG_TEST_MODE_RT_CPU0_P0
5%
JTAG_TDI_RT_CPU0_P0
R970R971
FF30
FF27
FF24
E30
B28
B31
B25
B23
F34
FF33
E11
FF11
FJ16
FF18
B16
E18
F2
FJ9
E8
B12
FF8
B9
B6
B3
FJ31
FJ28
FJ25
FJ23
FJ6
FJ3
FF5
G35
U6010
CLOCK
3/11
EE_DAT
EE_CLK
CLKREQ_N
TEST2
TEST1
TEST0
T_SENSE
SMBDAT
SMBCLK
SMB_ADDR3
SMB_ADDR2
SMB_ADDR1
SCAN_MODE
RXDET_BYP
RESET_N
REFCLKP
REFCLKN
REFCLK_OUTP
REFCLK_OUTN
PERST_N
MODE
JTAG_TRST_N
JTAG_TMS
JTAG_TEST_MODE
JTAG_TDO
JTAG_TDI
JTAG_TCK
INT_N
GPIO3
GPIO2
GPIO1
GPIO0
MISC JTAG
TESTEEPROM
SMBUS
GPIO
2
1
2
1
2
1
2
1
R1446
2
1
R1365
2
1
21
2
1
R1369
2
1
R1370
21R1364
2
1
R974
2
1
2
1
2
1
2
1
2
1
2
1
R964
2
1
R967
2
1
R965
21
21
2
1
R998
2
1
R1001
2
1
R975
2
1
R985
2
1
R983
2
1
R997
2
1
R995
2
1
R984
21
21
21
21
21
21
2
1
2
1
2
1
R981
2
1
R978
2
1
R982
2
1
R980
2
1
R979
2
1
R972
1
SHEETDATE
23
7 3 2 16 5 4
E
A
B
C
E
D
C
B
A
7 6 5 4
D
DEPARTMENT
SIZE
PROJECT DOCUMENT NUMBER REV
REVIEWER
DESIGNER
IN
OUT
IN
IN
IN
IN
IN
OUT
OUT
OUT
OUT
OUT
OUT
OUT
IN
IN
IN
IN
IN
IN
IN
OUT
IN
BI
IN
OUT
BI
IN
IN
IN
IN
IN
IN
OUT
OUT
OUT
OUT
IN
IN
OUT
OUT
IN
R1438 R1439 R1445
R973
R1368
R968
R969
R966
R963
R953
R976
R977
R666
R667
R596
R595
R624R623
C



Thu Aug 24 14:09:54 2023<NAME_2>
<NAME_1>
MB FABCGTI V02
277 OF 365
P 1V 8_CP U0_RT0_1A _1D
P 1V 8_CP U0_RT_1D
P0V9_CPU0_RT0_2A_2D
P 0V 9_CP U0_RT_2D
P 1V 8_CP U0_RT0_1A
P0V9_CPU0_RT0_2A
1%
200
1/20W
0201LF
CHIP
EMPTY
1/20W
1K
1%
0201LF
RT_CPU0_P0_VQPS
RETIMER_CPU0_P0 POWER(6)
CHIP
PT5161LRS
1/20W
N C F_A1_C PU 0_P0_GN D
N C F_C PU 0_P0_GN D
IC
PT5161LRS
1/20W
5%
0
SMLF
0201LF
IC
SMLF
0
5%
CHIP
0201LF
FH34
FH2
FG35
FG1
FE34
FE2
D35
D1
C34
C2
A35
A1
V35
V1
U34
U2
T4
T32
T22
T13
L35
L1
K34
K2
J4
J22
H31
H19
H16
H12
FJ19
FJ12
FF21
FF14
FD35
FD1
FC9
FC6
FC3
FC28
FC25
FC23
FC19
FB34
FB2
FA32
FA15
ET35
ET1
ER34
ER2
EP4
EP32
EP22
EP13
EJ35
EJ1
EH34
EH2
EG4
EG32
EG22
EG13
EB35
EB1
EA34
EA2
E33
E27
E14
DY4
DY32
DY22
DY13
DR35
DR1
DP34
DP2
DN4
DN32
DN22
DN13
DH35
DH1
DG34
DG2
DF4
DF32
DF22
DF13
DA35
DA1
CY34
CY2
CW4
CW32
CW22
CW13
CP35
CP1
CN34
CN2
CM4
CM32
CM22
CM13
CG35
CG1
CF34
CF2
CE4
CE32
CE22
CE13
BY35
BY1
BW34
BW2
BV4
BV32
BV22
BV13
BN35
BN1
BM34
BM2
BL4
BL32
BL22
BL13
BF35
BF1
BE34
BE2
BD4
BD32
BD22
BD13
B19
AW35
AW1
AV34
AV2
AU4
AU32
AU22
AU13
AM35
AM1
AL34
AL2
AK4
AK32
AK22
AK13
AE35
AE1
AD34
AD2
AC4
AC32
AC22
AC13
G1
CW20
CW17
BL20
BL17
T20
T17
EP20
EP17
EG20
EG17
DY20
DY17
DN20
DN17
DF20
DF17
BD20
BD17
AU20
AU17
AK20
AK17
AC20
AC17
BV17
CM20
CM17
CE20
CE17
BV20
U6010
U6010
4/11
PWR_2A_20
PWR_2A_19
PWR_2A_18
PWR_2A_17
PWR_2A_16
PWR_2A_15
PWR_2A_14
PWR_2A_13
PWR_2A_12
PWR_2A_11
PWR_2A_10
PWR_2A_9
PWR_2A_8
PWR_2A_7
PWR_2A_6
PWR_2A_5
PWR_2A_4
PWR_2A_3
PWR_2A_2
PWR_2A_1
PWR_1D
PWR_2D_4
PWR_2D_3
PWR_2D_2
PWR_2D_1
PWR_1A_5
PWR_1A_4
PWR_1A_3
PWR_1A_2
PWR_1A_1
VQPS
5/11
GND151
GND150
GND149
GND148
GND147
GND146
GND145
GND144
GND143
GND142
GND141
GND140
GND139
GND138
GND137
GND136
GND135
GND134
GND133
GND132
GND131
GND130
GND129
GND128
GND127
GND126
GND125
GND124
GND123
GND122
GND121
GND120
GND119
GND118
GND117
GND116
GND115
GND114
GND113
GND112
GND111
GND110
GND109
GND108
GND107
GND106
GND105
GND104
GND103
GND102
GND101
GND100
GND99
GND98
GND97
GND96
GND95
GND94
GND93
GND92
GND91
GND90
GND89
GND88
GND87
GND86
GND85
GND84
GND83
NCF_GND12
NCF_GND11
NCF_GND10
NCF_GND9
NCF_GND8
NCF_GND7
NCF_GND6
NCF_GND5
NCF_GND4
NCF_GND3
NCF_GND2
NCF_GND1
GND82
GND81
GND80
GND79
GND78
GND77
GND76
GND75
GND74
GND73
GND72
GND71
GND70
GND69
GND68
GND67
GND66
GND65
GND64
GND63
GND62
GND61
GND60
GND59
GND58
GND57
GND56
GND55
GND54
GND53
GND52
GND51
GND50
GND49
GND48
GND47
GND46
GND45
GND44
GND43
GND42
GND41
GND40
GND39
GND38
GND37
GND36
GND35
GND34
GND33
GND32
GND31
GND30
GND29
GND28
GND27
GND26
GND25
GND24
GND23
GND22
GND21
GND20
GND19
GND18
GND17
GND16
GND15
GND14
GND13
GND12
GND11
GND10
GND9
GND8
GND7
GND6
GND5
GND4
GND3
GND2
GND1
0.9V 0.9V
1.8V
/1.8V
1.2V / 1.5V
2
1
R6808
2
1
2
1
2
1
1
SHEETDATE
23
7 3 2 16 5 4
E
A
B
C
E
D
C
B
A
7 6 5 4
D
DEPARTMENT
SIZE
PROJECT DOCUMENT NUMBER REV
REVIEWER
DESIGNER
R6809
R6820
R6821
C



RETIMER EEPRO ADDRESS: 0XA0 (8 BIT) / 0X50 (7 BIT)
Thu Aug 24 14:09:45 2023<NAME_2>
<NAME_1>
MB FABCGTI V02
278 OF 365
P 1V 8_CP U0_RT_1D
185186
185186
SMB_RT_CPU0_P0_ROM_SDASMB_RT_CPU0_P0_ROM_R_SDA
1%33.2
SMB_RT_CPU0_P0_ROM_SCLSMB_RT_CPU0_P0_ROM_R_SCL
1/20W CHIP 0201LF
M24M02-DRMN6TP
U11_E2
X 7S
C0201
SMLF
0.1UF
0201LF
CHIP
10%
IC
RETIMER_CPU0_P0(7)
1%
10V
1/20W
1K
7
4
8
5
6 3
2
1
U11
DU1
DU2
E2
VSSSDA
SCL
WC_N
VCC
2
1
2
1 C7510
21
21
1
SHEETDATE
23
7 3 2 16 5 4
E
A
B
C
E
D
C
B
A
7 6 5 4
D
DEPARTMENT
SIZE
PROJECT DOCUMENT NUMBER REV
REVIEWER
DESIGNER
BI
IN R6822R669
R668
C



Thu Aug 24 14:09:55 2023<NAME_2>
<NAME_1>
MB FABCGTI V02
279 OF 365
P0V9_CPU0_RT_2D
P0V9_CPU0_RT0_2A_2D
P 1V 8_CP U0_RT_1D
P 1V 8_CP U0_RT0_1A
P 1V 8_CP U0_RT0_1A _1D
P0V9_CPU0_RT0_2A
X 6S
C0805
20%
4V
100UF
C0805
X 6S
20%
4V
100UF
4V
X 6S
100UF
20%
C0805
X 6S
4V
100UF
20%
C0805
100UF
C0805
X 6S
4V
20%
X 6S
20%
100UF
C0805
4V
20%
X 6S
4V
C0805
100UF
C0201
4V
20%
X6S
20%20%
4V
470UF
20%
2.5V
S P CA P
S MLF
C0805 C0805 C0805 C0805
22UF
4V
20%
X 6S
C0402
C0201
10V 10V 10V 20%
0.1UF0.1UF0.1UF
10%
10V
0201
1UF
IND
47UF
X6S X6S
47UF
4V
47UF
20%
47UF
X6S
4V
C0805
47UF
4V20%2.5V
S P CA P
2.5V
S P CA P
S MLF
10UF
0.1UF
X7S
C0201
X7S
C0201
0.1UF
10V
C0201
10%
10V
0.1UF
X7S
02010201
0.1UF
10V 10V
6.3V
X 6S
20%
6.3V
4.7UF
20%
X 6S
02010201
X7S
10%
10V
X7S
X 6S
6.3V 6.3V
20%
X7S
10%
10V4V4V
4V
1UF
20%
0201
20%
4V
X 6S
1UF
20%
10%
0.1UF
0.1UF
C0201
10%
X7S
0.1UF
10V
0603LF
10%
C0201
0201
0.1UF
10%
X7S
C0201
10%
0.1UF
10V
1UF
4V
X7S
20%
R961 AND R962 COLAY 1/4W
0
20%
4V
0201
1UF
X 6S
20%
4V
1UF
4V
20%
X 6S
C0402
20% 20%
4.7UF
20%
4V
X 6S
C0402
20%
20%
6.3V
100NH/16A
SMLF
4V
BLM21SN300SN1D/5A
10UF
6.3V
22UF
4V
10%
5%
0
X 6S
X7S
RETIMER_CPU0_P0 DECAPS(8)
IND
0
5%0402LF
0402LF
0
5%
1/16W
1/16W
1/16W
EMPTY
IND
SMLF
BLM15PD121SN1D/1300MA
X 6S
X7S
1/4W
0603LF
5%
EMPTY
0201
X 6S
10V
1UF
20%
22UF
X 6S X 6SX7S
10%
C0402
10UF
6.3V
EMPTY
X 6S
20%
6.3V
10UF
X 6S
20%
20%
20%
X7S
20%
4.7UF
X 6S
C0402
10UF
20%
X 6S
C0402
4V
X 6S
C0402
20%
22UF
4V
22UF
C0201
1UF
4V
1UF
4V
X 6S
1UF
0402 020102010402
4V
0402LF
EMPTY
C0201
10%
10V
X7S
C0201C0201
X7S
C0402 C0402
X 6S
20%
4.7UF
20%
0201
4.7UF
1UF
4V
20%
0201
L26/R960 COLAY WITH R951/R952
0402
SMLF
1UF 0.1UF
10V10V4V6.3V
10UF
6.3V
X 6S
0402
0.1UF
C0201
0.1UF
10%
X 6S
0
1UF
4V
X 6S
0201
10%
10V
0.1UF 0.1UF
20%
22UF
CHIP
X 6SX 6S
C0201
10%
10V
X 6S
10V
X7S
C0201
10%
4V
0201
X 6S
20%
1UF1UF
0201
4V
X 6S
20%
5%
10V
C0201
X7SX7S
C0201
10%
10V
0.1UF 0.1UF
10%
X 6SX 6S
0402
1UF
20%
4V6.3V
20%
10UF
6.3V
4.7UF 0.1UF
X 6S
C0201 C0201
S P CA P
2.5V
S MLF
20%
470UF
2.5V
S MLF
S P CA P
20%
470UF
4V
100UF
C0805
X6S
20%
20%
1UF
0201
20%
C0402
20%
22UF
4V
C0402
X7S
6.3V
20%
X 6S
C0402
20%
C0201
X 6S
C0402 0402
X 6S
20% 10%
S MLF
470UF
4V
47UF470UF
20%
X6S X6SX7SX 6S
C0805
4.7UF
6.3V
X 6S
0402
X 6S
0.1UF
X 6S
20%
C0402
X7S
10% 10%
C0201
C504
L26
C7036C7035C7034C7033C7032
C7010
C7000 C7002
C511C506
C510
C502
C505C503
C513
2121
2 1
L12L11
CAD NOTE:
CAD NOTE:
1 21 2
12
2
1
2
1
2
1
2
1
2
1
2
1
2
1 C7009
2
1 C7008
2
1
2
1 C7001
2
1
2
1
2
1
2
1
2
1
2
1
2
1
R960
2
1
2
1
2
1
2
1
2
1
2
1
2
1
2
1
2
1
2
1
2
1
2
1
2
1
2
1
2
1
2
1
2
1
2
1
2
1
2
1
2
1
2
1
2
1
2
1
2
1
2
1
2
1
2
1
2
1
2
1
2
1
2
1
2
1
2
1
2
1
2
1
2
1
2
1
2
1
2
1
2
1
2
1
2
1
2
1
2
1
2
1
2
1
2
1
2
1
2
1
2
1
2
1
2
1
2
1 C514
2
1 C512
2
1
2
1 C507
2
1
2
1
2
1
21
2
1
2
1
2
1
21R951
21R952
1
SHEETDATE
23
7 3 2 16 5 4
E
A
B
C
E
D
C
B
A
7 6 5 4
D
DEPARTMENT
SIZE
PROJECT DOCUMENT NUMBER REV
REVIEWER
DESIGNER
C7003
C566C583
C545C542
C540C578C524
C567C584
C522C528C569
C568C575C565C586
C563 C574C559
C564C560C556C550
C526C521
C543C558
C529C525
C581C577
C572C557
C573C570
C585C523C582C541
C571C554C579
C562C539
C561
C555
C580C576
C544C538
C520C519C517C515
R962
R961
C516
C



Thu Aug 24 10:16:08 2023<NAME_2>
<NAME_1>
MB FABCGTI V02
280 OF 365RETIMER_CPU0_P0(9)
1
SHEETDATE
23
7 3 2 16 5 4
E
A
B
C
E
D
C
B
A
7 6 5 4
D
DEPARTMENT
SIZE
PROJECT DOCUMENT NUMBER REV
REVIEWER
DESIGNER
C



Thu Aug 24 10:16:09 2023<NAME_2>
<NAME_1>
MB FABCGTI V02
281 OF 365RETIMER_CPU0_P0(10)
1
SHEETDATE
23
7 3 2 16 5 4
E
A
B
C
E
D
C
B
A
7 6 5 4
D
DEPARTMENT
SIZE
PROJECT DOCUMENT NUMBER REV
REVIEWER
DESIGNER
C



Thu Aug 24 10:16:10 2023<NAME_2>
<NAME_1>
MB FABCGTI V02
282 OF 365BLANK
1
SHEETDATE
23
7 3 2 16 5 4
E
A
B
C
E
D
C
B
A
7 6 5 4
D
DEPARTMENT
SIZE
PROJECT DOCUMENT NUMBER REV
REVIEWER
DESIGNER
C



P/N SWAP
P/N SWAP
P/N SWAP
P/N SWAP
P/N SWAP
P/N SWAP
P/N SWAP
P/N SWAP P/N SWAP
CPU TO RETIMERCPU TO RETIMER
P5E_CPU0_P1_TX_C_DP/DN<0-15> LANE REVERSAL
P/N SWAP
P/N SWAP
P/N SWAP
P/N SWAP
P/N SWAP
Thu Aug 24 14:09:37 2023<NAME_2>
<NAME_1>
MB FABCGTI V02
283 OF 365
63
63
63
63
IC
RETIMER_CPU0_P1(1)
SMLF
PT5161LRS
PT5161LRS
IC
SMLF
P5E_CPU0_P1_TX_C_DN<7:0>
P5E_CPU0_P1_TX_C_DP<7:0>
P5E_CPU0_P1_TX_C_DN<15:8>
P5E_CPU0_P1_TX_C_DP<15:8>
EV34
EL34
ED34
DU34
DK34
DC34
CT34
CJ34
EY35
EN35
EF35
DW35
DM35
DE35
CV35
CL35
CB34
BR34
BH34
BA34
AP34
AG34
Y34
N34
CD35
BU35
BK35
BC35
AT35
AJ35
AB35
R35
13
13
12
12
1
3
6
3
6
10
8
9
10
11
2
4
0
0
5
8
9
11
7
7
4
5
15
2
1
14
14
15
U6011
U6011
9/11
B_PERN15
B_PERP15
B_PERN14
B_PERP14
B_PERN13
B_PERP13
B_PERN12
B_PERP12
B_PERN11
B_PERP11
B_PERN10
B_PERP10
B_PERN9
B_PERP9
B_PERN8
B_PERP8
8/11
B_PERN7
B_PERP7
B_PERN6
B_PERP6
B_PERN5
B_PERP5
B_PERN4
B_PERP4
B_PERN3
B_PERP3
B_PERN2
B_PERP2
B_PERN1
B_PERP1
B_PERN0
B_PERP0
RX : B_PER[15:8]
RX : B_PER[7:0]
1
SHEETDATE
23
7 3 2 16 5 4
E
A
B
C
E
D
C
B
A
7 6 5 4
D
DEPARTMENT
SIZE
PROJECT DOCUMENT NUMBER REV
REVIEWER
DESIGNER
IN
IN
IN
IN
C



RETIMER TO CPURETIMER TO CPU
P5E_CPU0_P1_RX_DP/DN<0-15> LANE REVERSAL
Thu Aug 24 14:09:37 2023<NAME_2>
<NAME_1>
MB FABCGTI V02
284 OF 365
24
24
24
24
SMLF
PT5161LRS
P5E_CPU0_P1_RX_DN<7:0>
P5E_CPU0_P1_RX_DP<7:0>
PT5161LRS
RETIMER_CPU0_P1(2)
SMLF
ICIC
P5E_CPU0_P1_RX_DP<15:8>
P5E_CPU0_P1_RX_DN<15:8>
EU26
EK26
EC26
DT26
DJ26
DB26
CR26
CH26
EW29
EM29
EE29
DV29
DL29
DD29
CU29
CK29
CA26
BP26
BG26
AY26
AN26
AF26
W26
M26
CC29
BT29
BJ29
BB29
AR29
AH29
AA29
P29 15
3
2
5
4
7
5
7
13
13
11
10
10
15
11
8
8
6
4
1
0
3
2
1
0
9
12
9
6
12
14
14
U6011U6011
7/11
A_PETN15
A_PETP15
A_PETN14
A_PETP14
A_PETN13
A_PETP13
A_PETN12
A_PETP12
A_PETN11
A_PETP11
A_PETN10
A_PETP10
A_PETN9
A_PETP9
A_PETN8
A_PETP8
6/11
A_PETN7
A_PETP7
A_PETN6
A_PETP6
A_PETN5
A_PETP5
A_PETN4
A_PETP4
A_PETN3
A_PETP3
A_PETN2
A_PETP2
A_PETN1
A_PETP1
A_PETN0
A_PETP0
TX : A_PET[15:8]
TX : A_PET[7:0]
1
SHEETDATE
23
7 3 2 16 5 4
E
A
B
C
E
D
C
B
A
7 6 5 4
D
DEPARTMENT
SIZE
PROJECT DOCUMENT NUMBER REV
REVIEWER
DESIGNER
OUT
OUT
OUT
OUT
C



P5E_CPU0_P1_RX_BUF_DP/DN<0-15>
EXAMAX TO RETIMER EXAMAX TO RETIMER
Thu Aug 24 14:09:37 2023<NAME_2>
<NAME_1>
MB FABCGTI V02
285 OF 365
118
118
117
117
P5E_CPU0_P1_RX_BUF_DN<7:0>
P5E_CPU0_P1_RX_BUF_DP<7:0>
P5E_CPU0_P1_RX_BUF_DN<15:8>
P5E_CPU0_P1_RX_BUF_DP<15:8>
PT5161LRS
IC
SMLF
IC
SMLF
PT5161LRS
RETIMER_CPU0_P1(3)
EY1
EN1
EF1
DW1
DM1
DE1
CV1
CL1
EV2
EL2
ED2
DU2
DK2
DC2
CT2
CJ2
CD1
BU1
BK1
BC1
AT1
AJ1
AB1
R1
CB2
BR2
BH2
BA2
AP2
AG2
Y2
N2
15
3
0
7
6
5
4
2
1
4
5
6
0
3
2
1
7
15
14
13
12
11
10
9
8
8
9
10
11
12
13
14
U6011U6011
2/11
A_PERN15
A_PERP15
A_PERN14
A_PERP14
A_PERN13
A_PERP13
A_PERN12
A_PERP12
A_PERN11
A_PERP11
A_PERN10
A_PERP10
A_PERN9
A_PERP9
A_PERN8
A_PERP8
1/11
A_PERN7
A_PERP7
A_PERN6
A_PERP6
A_PERN5
A_PERP5
A_PERN4
A_PERP4
A_PERN3
A_PERP3
A_PERN2
A_PERP2
A_PERN1
A_PERP1
A_PERN0
A_PERP0
RX : A_PER[15:8]
RX : A_PER[7:0]
1
SHEETDATE
23
7 3 2 16 5 4
E
A
B
C
E
D
C
B
A
7 6 5 4
D
DEPARTMENT
SIZE
PROJECT DOCUMENT NUMBER REV
REVIEWER
DESIGNER
IN
IN
IN
IN
C



P5E_CPU0_P1_TX_BUF_DP/DN<0-15> LANE REVERSAL
RETIMER TO EXAMAX RETIMER TO EXAMAX
Thu Aug 24 14:09:37 2023<NAME_2>
<NAME_1>
MB FABCGTI V02
286 OF 365
287
287 118
118287
287 117
117
287
287
287
287
P5E_CPU0_P1_TX_BUF_DN<7:0>
P5E_CPU0_P1_TX_BUF_DP<7:0> P5E_CPU0_P1_TX_BUF_C_DP<7:0>
P5E_CPU0_P1_TX_BUF_C_DN<7:0>
D IFF BU S_0.22U F
D IFF BU S_0.22U F
D IFF BU S_0.22U F
D IFF BU S_0.22U F
D IFF BU S_0.22U F
D IFF BU S_0.22U F
D IFF BU S_0.22U F
D IFF BU S_0.22U F
D IFF BU S_0.22U F
D IFF BU S_0.22U F
D IFF BU S_0.22U F
D IFF BU S_0.22U F
D IFF BU S_0.22U F
D IFF BU S_0.22U F
D IFF BU S_0.22U F
20% 6.3V
X 6S
C0201
D IFF BU S_0.22U FP5E_CPU0_P1_TX_BUF_DN<15:8>
P5E_CPU0_P1_TX_BUF_DP<15:8> P5E_CPU0_P1_TX_BUF_C_DP<15:8>
P5E_CPU0_P1_TX_BUF_C_DN<15:8>
D IFF BU S_0.22U F
D IFF BU S_0.22U F
D IFF BU S_0.22U F
D IFF BU S_0.22U F
D IFF BU S_0.22U F
D IFF BU S_0.22U F
D IFF BU S_0.22U F
D IFF BU S_0.22U F
D IFF BU S_0.22U F
D IFF BU S_0.22U F
D IFF BU S_0.22U F
D IFF BU S_0.22U F
D IFF BU S_0.22U F
6.3VC0201
X 6S
20%
D IFF BU S_0.22U F
D IFF BU S_0.22U F
D IFF BU S_0.22U F
PT5161LRS
P5E_CPU0_P1_TX_BUF_DN<7:0>
SMLF
PT5161LRS
P5E_CPU0_P1_TX_BUF_DP<7:0>
P5E_CPU0_P1_TX_BUF_DN<15:8>
P5E_CPU0_P1_TX_BUF_DP<15:8>
SMLF
IC
RETIMER_CPU0_P1(4)
IC
2 1
2 1
2 1
2 1
2 1
2 1
2 1
2 1
2 1
2 1
2 1
2 1
2 1
2 1
2 1
2 1
2 1
2 1
2 1
2 1
2 1
2 1
2 1
2 1
2 1
2 1
2 1
2 1
2 1
2 1
2 1
2 1
EU7
EK7
EC7
DT7
DJ7
DB7
CR7
CH7
EW10
EM10
EE10
DV10
DL10
DD10
CU10
CK10
CA7
BP7
BG7
AY7
AN7
AF7
W7
M7
CC10
BT10
BJ10
BB10
AR10
AH10
AA10
P10
7
6
5
4
3
2
1
0
7
6
5
4
3
2
1
0
7
7
5
6
6
5
4
2
3
4
3
2
1
0
1
0
15
14
15
14
11
12
13
13
12
9
10
11
10
9
8
8
15
14
15
14
13
12
13
12
11
10
9
10
9
8
8
11
7
3
6
5
4
2
1
0
0
1
2
3
4
5
6
7
15
14
13
12
11
10
9
8
14
13
12
11
10
9
8
15
U6011
C6549
C6550
C6552
C6551
C6554
C6553
C6555
C6556
C6557
C6558
C6559
C6560
C6561
C6562
C6563
C6564
C6534
C6533
C6535
C6536
U6011
C6537
C6538
C6539
C6540
C6542
C6541
C6544
C6543
C6546
C6545
C6547
C6548
10/11
B_PETN7
B_PETP7
B_PETN6
B_PETP6
B_PETN5
B_PETP5
B_PETN4
B_PETP4
B_PETN3
B_PETP3
B_PETN2
B_PETP2
B_PETN1
B_PETP1
B_PETN0
B_PETP0
11/11
B_PETN15
B_PETP15
B_PETN14
B_PETP14
B_PETN13
B_PETP13
B_PETN12
B_PETP12
B_PETN11
B_PETP11
B_PETN10
B_PETP10
B_PETN9
B_PETP9
B_PETN8
B_PETP8
TX : B_PET[7:0]
TX : B_PET[15:8]
2 1
2 1
2 1
2 1
2 1
2 1
2 1
2 1
2 1
2 1
2 1
2 1
2 1
2 1
2 1
2 1
2 1
2 1
2 1
2 1
2 1
2 1
2 1
2 1
2 1
2 1
2 1
2 1
2 1
2 1
2 1
2 1
1
SHEETDATE
23
7 3 2 16 5 4
E
A
B
C
E
D
C
B
A
7 6 5 4
D
DEPARTMENT
SIZE
PROJECT DOCUMENT NUMBER REV
REVIEWER
DESIGNER
OUT
OUT
IN
IN OUT
OUT
IN
OUT
OUT
OUT
OUT IN
C



CPU1 P0 RT ADDR: 0X48 (8-BIT) / 0X24 (7-BIT)
Thu Aug 24 14:09:50 2023<NAME_2>
<NAME_1>
MB FABCGTI V02
287 OF 365
P 1V 8_CP U0_RT_1D
P 1V 8_CP U0_RT_1D
P 1V 8_CP U0_RT_1D
P 1V 8_CP U0_RT_1D
P 1V 8_CP U0_RT_1D
P 1V 8_CP U0_RT_1D
P 1V 8_CP U0_RT_1D
SMB_RT_CPU0_P1_ROM_MUX_1D_R_SCLSMB_RT_CPU0_P1_ROM_MUX_1D_SCL
1%49.9
CHIP1/20W 0201LF
SMB_RT_CPU0_P1_ROM_MUX_1D_R_SDASMB_RT_CPU0_P1_ROM_MUX_1D_SDA
185186
185186
288
288
288
288
288
288
288
288
288
182
182
288
288
288
288
184
288
288
288
288
81 288
81 288
288
288
184
288
288
288
81 288
81 288
288
288
288
288
288
288
288
288
288
288
1/20W
200
1%
CHIP
0201LF
RST_RT_CPU0_P1_RESET_N
0201LF
0201LF
10K
1%
1/20W
CHIP
1/20W
EMPTY
1K
1%
0201LF
0 5%
RT_CPU0_P1_ADDR3
RT_CPU0_P1_SCAN_MODE
GPIO2_RT_CPU0_P1
GPIO3_RT_CPU0_P1
RXDET_BYP_RT_CPU0_P1
SMB_RT_CPU0_P1_R2_SDA
RT_CPU0_P1_ADDR2
TEST0_RT_CPU0_P1
GPIO2_RT_CPU0_P1
GPIO3_RT_CPU0_P1
CHIP
1/20W
51.1
1%
51.1
1%
RETIMER_CPU0_P1(5)
0201LF
1/20W
EMPTY
0201LF
CLK_100M_RETIMER_CPU0_P1_DN
EMPTY
CHIP 0201LF
CLK_100M_RETIMER_CPU0_P1_R_DP
CLK_100M_RETIMER_CPU0_P1_R_DN
TEST1_RT_CPU0_P1
IC
TEST1_RT_CPU0_P1
TEST0_RT_CPU0_P1
MODE_RT_CPU0_P1
SMB_RT_CPU0_P1_R_SDA
TEST2_RT_CPU0_P1
JTAG_TEST_MODE_RT_CPU0_P1
RT_CPU0_P1_ADDR2
RT_CPU0_P1_ADDR1
RST_RT_CPU0_P1_RESET_R_N
RST_RT_CPU0_P1_PERST_R_N
RT_CPU0_P1_ADDR3
PT5161LRS
SMLF
RT_CPU0_P1_ADDR1
SMB_RT_CPU0_P1_R2_SCLSMB_RT_CPU0_P1_R_SCL
1/20W
0201LF
EMPTY
4.7K
5%
1%
1/20W
0201LF
CHIP
10K
1/20W
10K
0201LF
1%
CHIP
0201LF
EMPTY
1K
1%
1/20W
1/20W
CHIP
0201LF
1K
1%
0201LF
1%
EMPTY
1K
1/20W
0201LF
CHIP
1/20W
1K
1%
1/20W
1%
0201LF
20K
CHIP
1%
EMPTY
0201LF
1/20W
1K
1/20W
4.7K
5%
CHIP
0201LF
0201LF
4.7K
5%
1/20W
EMPTY
0201LF
5%
4.7K
1/20W
EMPTY
0201LF
5%
4.7K
EMPTY
1/20W1/20W
4.7K
5%
EMPTY
0201LF
4.7K
0201LF
1/20W
CHIP
5%
CHIP
1/20W
5%
4.7K
0201LF
4.7K
1/20W
CHIP
0201LF
5%
1/20W 0201LFCHIP
5%
1/20W
0201LF
EMPTY
4.7K4.7K
1/20W
EMPTY
0201LF
5%
5%
4.7K
1/20W
CHIP
0201LF
10K
1%
CHIP
0201LF
1/20W
0201LF
CHIP
1/20W
1%
10K
EMPTY
5%
0201LF
1/20W
4.7K
TEST2_RT_CPU0_P1
CLK_100M_RETIMER_CPU0_P1_DP
0201LF1/20W
0 5%
CHIP1K
0
CHIP4.7K
0
0201LF
0201LF
JTAG_TCK_RT_CPU0_P1
JTAG_TDO_RT_CPU0_P1
RST_RT_CPU0_P1_PERST_R_N
RST_RT_CPU0_P1_RESET_R_N
RT_CPU0_P1_SCAN_MODE
RXDET_BYP_RT_CPU0_P1
MODE_RT_CPU0_P1
RST_RT_CPU0_P1_PERST_N
0201LF
CHIP
1/20W
4.7K
5%
JTAG_TEST_MODE_RT_CPU0_P1
JTAG_TRST_RT_CPU0_P1_N
JTAG_TDI_RT_CPU0_P1
JTAG_TMS_RT_CPU0_P1
CLKREQ_RT_CPU0_P1_N
1/20W
5%1K
1%
0201LF
4.7K
5%
1/20W
EMPTY
1/20W
5%
4.7K
0201LF
1/20W
EMPTY
4.7K
EMPTY
0201LF
0201LF
EMPTY
0201LF
JTAG_TDI_RT_CPU0_P1
JTAG_TCK_RT_CPU0_P1
JTAG_TDO_RT_CPU0_P1
JTAG_TMS_RT_CPU0_P1
R1020 R1019
FF30
FF27
FF24
E30
B28
B31
B25
B23
F34
FF33
E11
FF11
FJ16
FF18
B16
E18
F2
FJ9
E8
B12
FF8
B9
B6
B3
FJ31
FJ28
FJ25
FJ23
FJ6
FJ3
FF5
G35
U6011
CLOCK
3/11
EE_DAT
EE_CLK
CLKREQ_N
TEST2
TEST1
TEST0
T_SENSE
SMBDAT
SMBCLK
SMB_ADDR3
SMB_ADDR2
SMB_ADDR1
SCAN_MODE
RXDET_BYP
RESET_N
REFCLKP
REFCLKN
REFCLK_OUTP
REFCLK_OUTN
PERST_N
MODE
JTAG_TRST_N
JTAG_TMS
JTAG_TEST_MODE
JTAG_TDO
JTAG_TDI
JTAG_TCK
INT_N
GPIO3
GPIO2
GPIO1
GPIO0
MISC JTAG
TESTEEPROM
SMBUS
GPIO
2
1
R1473
2
1
2
1
R1392
2
1
2
1
2
1
2
1
R1397
2
1
R1398
21
21R1391
2
1
R1023
2
1
2
1
2
1
2
1
2
1
2
1
R1013
2
1
R1016
2
1
R1014
21
21
2
1
R1039
2
1
R1006
2
1
R1024
2
1
R1034
2
1
R1032
2
1
R1037
2
1
R1035
2
1
R1033
21
21
21
21
2
1
R1030
2
1
R1027
2
1
R1031
2
1
R1029
2
1
R1028
2
1
R1021
21
2
1
2
1
21
1
SHEETDATE
23
7 3 2 16 5 4
E
A
B
C
E
D
C
B
A
7 6 5 4
D
DEPARTMENT
SIZE
PROJECT DOCUMENT NUMBER REV
REVIEWER
DESIGNER
IN
IN
IN
IN
OUT
OUT
OUT
IN
IN
IN
IN
OUT
OUT
OUT
OUT
OUT
OUT
OUT
IN
IN
IN
IN
IN
IN
OUT
IN
BI
IN
IN
IN
OUT
BI
IN
IN
IN
IN
OUT
OUT
OUT
OUT
IN
IN
R1472R1471R1470
R1022
R1395
R1017
R1018
R1015
R1004
R1012
R1025
R1026
R676
R677
R611
R630R629
R612
C



Thu Aug 24 14:09:55 2023<NAME_2>
<NAME_1>
MB FABCGTI V02
288 OF 365
P 1V 8_CP U0_RT_1D
P0V9_CPU0_RT1_2A
P0V9_CPU0_RT1_2A_2D
P 1V 8_CP U0_RT1_1A _1D
P 1V 8_CP U0_RT1_1A
P 0V 9_CP U0_RT_2D
CHIP
1/20W
1%
200
0201LF
1/20W
0201LF
1%
1K
EMPTY
RT_CPU0_P1_VQPS
0201LF
0
5%
1/20W
CHIP
0
0201LF
CHIP
5%
1/20W
RETIMER_CPU0_P1 POWER(6)
PT5161LRS
IC
SMLF
IC
SMLF
PT5161LRS
N C F_A1_C PU 0_P1_GN D
N C F_C PU 0_P1_GN D
FH34
FH2
FG35
FG1
FE34
FE2
D35
D1
C34
C2
A35
A1
V35
V1
U34
U2
T4
T32
T22
T13
L35
L1
K34
K2
J4
J22
H31
H19
H16
H12
FJ19
FJ12
FF21
FF14
FD35
FD1
FC9
FC6
FC3
FC28
FC25
FC23
FC19
FB34
FB2
FA32
FA15
ET35
ET1
ER34
ER2
EP4
EP32
EP22
EP13
EJ35
EJ1
EH34
EH2
EG4
EG32
EG22
EG13
EB35
EB1
EA34
EA2
E33
E27
E14
DY4
DY32
DY22
DY13
DR35
DR1
DP34
DP2
DN4
DN32
DN22
DN13
DH35
DH1
DG34
DG2
DF4
DF32
DF22
DF13
DA35
DA1
CY34
CY2
CW4
CW32
CW22
CW13
CP35
CP1
CN34
CN2
CM4
CM32
CM22
CM13
CG35
CG1
CF34
CF2
CE4
CE32
CE22
CE13
BY35
BY1
BW34
BW2
BV4
BV32
BV22
BV13
BN35
BN1
BM34
BM2
BL4
BL32
BL22
BL13
BF35
BF1
BE34
BE2
BD4
BD32
BD22
BD13
B19
AW35
AW1
AV34
AV2
AU4
AU32
AU22
AU13
AM35
AM1
AL34
AL2
AK4
AK32
AK22
AK13
AE35
AE1
AD34
AD2
AC4
AC32
AC22
AC13
G1
CW20
CW17
BL20
BL17
T20
T17
EP20
EP17
EG20
EG17
DY20
DY17
DN20
DN17
DF20
DF17
BD20
BD17
AU20
AU17
AK20
AK17
AC20
AC17
BV17
CM20
CM17
CE20
CE17
BV20
U6011
U6011
4/11
PWR_2A_20
PWR_2A_19
PWR_2A_18
PWR_2A_17
PWR_2A_16
PWR_2A_15
PWR_2A_14
PWR_2A_13
PWR_2A_12
PWR_2A_11
PWR_2A_10
PWR_2A_9
PWR_2A_8
PWR_2A_7
PWR_2A_6
PWR_2A_5
PWR_2A_4
PWR_2A_3
PWR_2A_2
PWR_2A_1
PWR_1D
PWR_2D_4
PWR_2D_3
PWR_2D_2
PWR_2D_1
PWR_1A_5
PWR_1A_4
PWR_1A_3
PWR_1A_2
PWR_1A_1
VQPS
5/11
GND151
GND150
GND149
GND148
GND147
GND146
GND145
GND144
GND143
GND142
GND141
GND140
GND139
GND138
GND137
GND136
GND135
GND134
GND133
GND132
GND131
GND130
GND129
GND128
GND127
GND126
GND125
GND124
GND123
GND122
GND121
GND120
GND119
GND118
GND117
GND116
GND115
GND114
GND113
GND112
GND111
GND110
GND109
GND108
GND107
GND106
GND105
GND104
GND103
GND102
GND101
GND100
GND99
GND98
GND97
GND96
GND95
GND94
GND93
GND92
GND91
GND90
GND89
GND88
GND87
GND86
GND85
GND84
GND83
NCF_GND12
NCF_GND11
NCF_GND10
NCF_GND9
NCF_GND8
NCF_GND7
NCF_GND6
NCF_GND5
NCF_GND4
NCF_GND3
NCF_GND2
NCF_GND1
GND82
GND81
GND80
GND79
GND78
GND77
GND76
GND75
GND74
GND73
GND72
GND71
GND70
GND69
GND68
GND67
GND66
GND65
GND64
GND63
GND62
GND61
GND60
GND59
GND58
GND57
GND56
GND55
GND54
GND53
GND52
GND51
GND50
GND49
GND48
GND47
GND46
GND45
GND44
GND43
GND42
GND41
GND40
GND39
GND38
GND37
GND36
GND35
GND34
GND33
GND32
GND31
GND30
GND29
GND28
GND27
GND26
GND25
GND24
GND23
GND22
GND21
GND20
GND19
GND18
GND17
GND16
GND15
GND14
GND13
GND12
GND11
GND10
GND9
GND8
GND7
GND6
GND5
GND4
GND3
GND2
GND1
0.9V 0.9V
1.8V
/1.8V
1.2V / 1.5V
2
1
R1040
2
1
2
1
2
1
1
SHEETDATE
23
7 3 2 16 5 4
E
A
B
C
E
D
C
B
A
7 6 5 4
D
DEPARTMENT
SIZE
PROJECT DOCUMENT NUMBER REV
REVIEWER
DESIGNER
R1041
R1043
R1042
C



RETIMER EEPRO ADDRESS: 0XA0 (8 BIT) / 0X50 (7 BIT)
Thu Aug 24 14:09:46 2023<NAME_2>
<NAME_1>
MB FABCGTI V02
289 OF 365
P 1V 8_CP U0_RT_1D
185186
185186
SMB_RT_CPU0_P1_ROM_SDASMB_RT_CPU0_P1_ROM_R_SDA
1%33.2
SMB_RT_CPU0_P1_ROM_SCLSMB_RT_CPU0_P1_ROM_R_SCL
CHIP1/20W 0201LF
0201LF
1K
CHIP
1%
1/20W
C0201
X 7S
10%
10V
0.1UF
IC
U15_E2
RETIMER_CPU0_P1(7)
M24M02-DRMN6TP
SMLF
7
4
8
5
6 3
2
1
U15
DU1
DU2
E2
VSSSDA
SCL
WC_N
VCC
2
1 C664
2
1
21
21
1
SHEETDATE
23
7 3 2 16 5 4
E
A
B
C
E
D
C
B
A
7 6 5 4
D
DEPARTMENT
SIZE
PROJECT DOCUMENT NUMBER REV
REVIEWER
DESIGNER
IN
BI R1044R679
R678
C



Thu Aug 24 14:09:55 2023<NAME_2>
<NAME_1>
MB FABCGTI V02
290 OF 365
P0V9_CPU0_RT1_2A_2D
P 1V 8_CP U0_RT1_1A _1D
P 1V 8_CP U0_RT1_1A
P0V9_CPU0_RT_2D
P 1V 8_CP U0_RT_1D
P0V9_CPU0_RT1_2A
100UF
C0805
20%
X 6S
4V
C0805
X 6S
20%
4V
100UF
X 6S
100UF
4V
C0805
20%
20%
100UF
C0805
X 6S
4V
C0805
100UF
4V
X 6S
20%
C0805
X 6S
20%
4V
100UF
20%
X 6S
100UF
C0805
4V
20%
X 6S
0201
20%
4V
1UF 0.1UF
10%
X7S
C0201
0.1UF
470UF
1UF
X7S
C0201
470UF
20%
S MLF
2.5V
S P CA P S P CA P
2.5V
20%
S MLF
C0805
X6S
4V
100UF
20%
4V
10%
10V10V10V
X7S X7S X7S X7S
10% 10% 10%
C0201C0201C0201
0201
20%
C0402
4.7UF
6.3V
X 6S
10V
10%
4V
EMPTY
1/4W
1/16W
BLM15PD121SN1D/1300MA
0402
10V
0201
X 6S
20%
4V
1UF
20%
4V
1UF
4V
0.1UF
1UF
4V
1UF
4V 10V
0.1UF
X 6S
10V
10%
C0201
X7S
10%
10V
0.1UF
0201
20%20%20%
0201
X 6S
0.1UF
X7S
C0201
10V
0.1UF
4V6.3V
20%20%20%
BLM21SN300SN1D/5A
C0402 C0201
20%
4V
1UF 1UF
10V
X7S
C0201
SMLF
C0402
20%
10UF
22UF
C0201
C0201
20%
C0402
X 6S
20%
0603LF
0.1UF 0.1UF
10V
0.1UF
EMPTY
L28/R1008 COLAY WITH R1002/R1003
1UF 1UF
10V 10V
X 6S
C0402
X 6S
10%
X 6S
1UF4.7UF
10UF
X 6S
20%
4V
22UF22UF
C0402
X 6S
4V 4V
22UF
20%
20%
4V
1UF
X 6S
20%
10UF
6.3V
4.7UF
X 6S
C0201 C0201
X7S
10%10%
10V10V20%20%20%
20%
10%
0.1UF
X 6S
20%
10V
10%
X7S X7S
0201
X 6S
0201
X 6S
R1010 AND R1011 COLAY
0603LF
0
10%10%
C0402
6.3V
C0201
0.1UF
10V
0.1UF0.1UF0.1UF
1UF
4V
X7S
0402
4.7UF
4V
X 6S
20%
22UF
10UF
6.3V
X 6S
6.3V
C0402
20%
IND
22UF
4V
C0201
SMLF
IND
0
5%0402LF
0402LF
1/16W
0402LF
EMPTY
1/16W
0
5%
EMPTY
RETIMER_CPU0_P1 DECAPS(8)
5%
0
0201
X 6S
X7S
0.1UF
10%
10V
0
5%
20%
X 6S
10V
1/4W
5%
X7S
X 6S
IND
SMLF
X 6S
4V
6.3V
C0402 0402
X 6S
4.7UF
0201
C0402
X 6S
20%
X7S X7S
10%
C0201
X7S
10V
0201
X 6S
6.3V
X 6S
100NH/16A
C0402
1UF
10UF
C0402
22UF
10%X 6S
10%
X7S
0402
X 6S
20%
6.3V
0.1UF 0.1UF 0.1UF
10V
10%
C0201C0201
10%
4V
4.7UF
6.3V
X 6S
C0402
10UF
4V
20%
X 6S
20%
6.3V
1UF
X 6S
X 6S
4V
0402C0402
X7S
X7S
1UF
4V
C0201 C0201
X 6S
20%
0201
0.1UF
C0201
0201
X 6S
20%
0201
X 6S
20%
CHIP
0.1UF
0201
X 6S
0402
10UF
6.3V
20%
20%
020102010201
20%
4V4V
1UF
4.7UF
6.3V
X 6S
0402
X 6S
20%
6.3V
C589
L28
C7013
C596C591
C594
C587
C590C588
C598
2121
2 1
L14L13
CAD NOTE:
CAD NOTE:
1 21 2
12
2
1
2
1 C7012
2
1 C7011
2
1
2
1
2
1
2
1
2
1
2
1
R1008
2
1
2
1
2
1
2
1
2
1
2
1
2
1
2
1
2
1
2
1
2
1
2
1
2
1
2
1
2
1
2
1
2
1
2
1
2
1
2
1
2
1
2
1
2
1
2
1
2
1
2
1
2
1
2
1
2
1
2
1
2
1
2
1
2
1
2
1
2
1
2
1
2
1
2
1
2
1
2
1
2
1
2
1
2
1
21
2
1
2
1
2
1
2
1
2
1
2
1
2
1
2
1
2
1 C599
2
1 C597
2
1
2
1
2
1
2
1 C595
2
1
2
1
2
1
2
1
2
1
21R1002
21R1003
1
SHEETDATE
23
7 3 2 16 5 4
E
A
B
C
E
D
C
B
A
7 6 5 4
D
DEPARTMENT
SIZE
PROJECT DOCUMENT NUMBER REV
REVIEWER
DESIGNER
C660
C659C658
C624C621
C652
C622
C614
C619C615C610C608
C648C661C656
C655C651C646
C630C663C634C637C633
C636C632
C628C625
C613C620
C650C631
C653C649C638C644
C654C647
C627C635
C643C607
C657C616
C645C626
C618C609
C662
R1011
C623C617
C606C603C602C600
R1010
C601
C



Thu Aug 24 10:16:17 2023<NAME_2>
<NAME_1>
MB FABCGTI V02
291 OF 365RETIMER_CPU0_P1(9)
1
SHEETDATE
23
7 3 2 16 5 4
E
A
B
C
E
D
C
B
A
7 6 5 4
D
DEPARTMENT
SIZE
PROJECT DOCUMENT NUMBER REV
REVIEWER
DESIGNER
C



Thu Aug 24 10:16:18 2023<NAME_2>
<NAME_1>
MB FABCGTI V02
292 OF 365RETIMER_CPU0_P1(10)
1
SHEETDATE
23
7 3 2 16 5 4
E
A
B
C
E
D
C
B
A
7 6 5 4
D
DEPARTMENT
SIZE
PROJECT DOCUMENT NUMBER REV
REVIEWER
DESIGNER
C



Thu Aug 24 10:16:19 2023<NAME_2>
<NAME_1>
MB FABCGTI V02
293 OF 365BLANK
1
SHEETDATE
23
7 3 2 16 5 4
E
A
B
C
E
D
C
B
A
7 6 5 4
D
DEPARTMENT
SIZE
PROJECT DOCUMENT NUMBER REV
REVIEWER
DESIGNER
C



P/N SWAP
P/N SWAP
P/N SWAP
P/N SWAP
P/N SWAP
P/N SWAP
P/N SWAP
P/N SWAP
P/N SWAP
P/N SWAP
P/N SWAP
P/N SWAP
P/N SWAP
P/N SWAP
P/N SWAP
CPU TO RETIMER CPU TO RETIMER
P5E_CPU0_P2_TX_C_DP/DN<0-15> LANE REVERSAL
Thu Aug 24 14:09:38 2023<NAME_2>
<NAME_1>
MB FABCGTI V02
294 OF 365
64
64
64
64
P5E_CPU0_P2_TX_C_DP<15:8>
IC
PT5161LRS
SMLF
RETIMER_CPU0_P2(1)
PT5161LRS
SMLF
IC
P5E_CPU0_P2_TX_C_DN<7:0>
P5E_CPU0_P2_TX_C_DP<7:0>
P5E_CPU0_P2_TX_C_DN<15:8>
CB34
BR34
BH34
BA34
AP34
AG34
Y34
N34
CD35
BU35
BK35
BC35
AT35
AJ35
AB35
R35
EV34
EL34
ED34
DU34
DK34
DC34
CT34
CJ34
EY35
EN35
EF35
DW35
DM35
DE35
CV35
CL35
8
10
11
12
13
15
1
1
6
5
3
2
3
4
5
6
15
14
9
13
12
11
10
9
8
14
7
2
0
0
4
7
U6012
U6012
8/11
B_PERN7
B_PERP7
B_PERN6
B_PERP6
B_PERN5
B_PERP5
B_PERN4
B_PERP4
B_PERN3
B_PERP3
B_PERN2
B_PERP2
B_PERN1
B_PERP1
B_PERN0
B_PERP0
9/11
B_PERN15
B_PERP15
B_PERN14
B_PERP14
B_PERN13
B_PERP13
B_PERN12
B_PERP12
B_PERN11
B_PERP11
B_PERN10
B_PERP10
B_PERN9
B_PERP9
B_PERN8
B_PERP8
RX : B_PER[7:0]
RX : B_PER[15:8]
1
SHEETDATE
23
7 3 2 16 5 4
E
A
B
C
E
D
C
B
A
7 6 5 4
D
DEPARTMENT
SIZE
PROJECT DOCUMENT NUMBER REV
REVIEWER
DESIGNER
IN
IN
IN
IN
C



RETIMER TO CPURETIMER TO CPU
P5E_CPU0_P2_RX_DP/DN<0-15> LANE REVERSAL
Thu Aug 24 14:09:38 2023<NAME_2>
<NAME_1>
MB FABCGTI V02
295 OF 365
25
25
25
25
P5E_CPU0_P2_RX_DN<7:0>
P5E_CPU0_P2_RX_DP<7:0>
RETIMER_CPU0_P2(2)
IC
SMLF
PT5161LRS
IC
PT5161LRS
SMLF
P5E_CPU0_P2_RX_DN<15:8>
P5E_CPU0_P2_RX_DP<15:8>
EU26
EK26
EC26
DT26
DJ26
DB26
CR26
CH26
EW29
EM29
EE29
DV29
DL29
DD29
CU29
CK29
CA26
BP26
BG26
AY26
AN26
AF26
W26
M26
CC29
BT29
BJ29
BB29
AR29
AH29
AA29
P29
14
14
13
13
12
10
12
10
9
8
8
11
2
2
7
7
6
6
5
5
4
4
3
3
1
1
0
0
9
11
15
15
U6012
U6012
7/11
A_PETN15
A_PETP15
A_PETN14
A_PETP14
A_PETN13
A_PETP13
A_PETN12
A_PETP12
A_PETN11
A_PETP11
A_PETN10
A_PETP10
A_PETN9
A_PETP9
A_PETN8
A_PETP8
6/11
A_PETN7
A_PETP7
A_PETN6
A_PETP6
A_PETN5
A_PETP5
A_PETN4
A_PETP4
A_PETN3
A_PETP3
A_PETN2
A_PETP2
A_PETN1
A_PETP1
A_PETN0
A_PETP0
TX : A_PET[15:8]
TX : A_PET[7:0]
1
SHEETDATE
23
7 3 2 16 5 4
E
A
B
C
E
D
C
B
A
7 6 5 4
D
DEPARTMENT
SIZE
PROJECT DOCUMENT NUMBER REV
REVIEWER
DESIGNER
OUT
OUT
OUT
OUT
C



P5E_CPU0_P2_RX_BUF_DP/DN <0-15> LANE REVERSAL
EXAMAX TO RETIMER EXAMAX TO RETIMER
Thu Aug 24 14:09:38 2023<NAME_2>
<NAME_1>
MB FABCGTI V02
296 OF 365
116
116
115
115
SMLF
P5E_CPU0_P2_RX_BUF_DN<7:0>
P5E_CPU0_P2_RX_BUF_DP<7:0>
P5E_CPU0_P2_RX_BUF_DN<15:8>
P5E_CPU0_P2_RX_BUF_DP<15:8>
PT5161LRS
SMLF
IC IC
PT5161LRS
RETIMER_CPU0_P2(3)
EY1
EN1
EF1
DW1
DM1
DE1
CV1
CL1
EV2
EL2
ED2
DU2
DK2
DC2
CT2
CJ2
CD1
BU1
BK1
BC1
AT1
AJ1
AB1
R1
CB2
BR2
BH2
BA2
AP2
AG2
Y2
N2 7
6
5
4
3
2
1
0
0
1
2
3
4
5
6
7
15
14
13
12
11
10
9
8
8
9
10
11
12
13
14
15
U6012U6012
2/11
A_PERN15
A_PERP15
A_PERN14
A_PERP14
A_PERN13
A_PERP13
A_PERN12
A_PERP12
A_PERN11
A_PERP11
A_PERN10
A_PERP10
A_PERN9
A_PERP9
A_PERN8
A_PERP8
1/11
A_PERN7
A_PERP7
A_PERN6
A_PERP6
A_PERN5
A_PERP5
A_PERN4
A_PERP4
A_PERN3
A_PERP3
A_PERN2
A_PERP2
A_PERN1
A_PERP1
A_PERN0
A_PERP0
RX : A_PER[15:8]
RX : A_PER[7:0]
1
SHEETDATE
23
7 3 2 16 5 4
E
A
B
C
E
D
C
B
A
7 6 5 4
D
DEPARTMENT
SIZE
PROJECT DOCUMENT NUMBER REV
REVIEWER
DESIGNER
IN
IN
IN
IN
C



P5E_CPU0_P2_TX_BUF_DP/DN <0-15> LANE REVERSAL
RETIMER TO EXAMAXRETIMER TO EXAMAX
Thu Aug 24 14:09:38 2023<NAME_2>
<NAME_1>
MB FABCGTI V02
297 OF 365
298
298
116
116
298
298
115
115
298
298 298
298
P5E_CPU0_P2_TX_BUF_DN<7:0>
P5E_CPU0_P2_TX_BUF_DP<7:0>
P5E_CPU0_P2_TX_BUF_C_DN<7:0>
P5E_CPU0_P2_TX_BUF_C_DP<7:0>
D IFF BU S_0.22U F
D IFF BU S_0.22U F
D IFF BU S_0.22U F
D IFF BU S_0.22U F
D IFF BU S_0.22U F
D IFF BU S_0.22U F
D IFF BU S_0.22U F
D IFF BU S_0.22U F
D IFF BU S_0.22U F
D IFF BU S_0.22U F
D IFF BU S_0.22U F
D IFF BU S_0.22U F
D IFF BU S_0.22U F
D IFF BU S_0.22U F
6.3V20%
X 6S
C0201
D IFF BU S_0.22U F
D IFF BU S_0.22U F
P5E_CPU0_P2_TX_BUF_DP<15:8>
P5E_CPU0_P2_TX_BUF_DN<15:8>
P5E_CPU0_P2_TX_BUF_C_DP<15:8>
P5E_CPU0_P2_TX_BUF_C_DN<15:8>
D IFF BU S_0.22U F
D IFF BU S_0.22U F
D IFF BU S_0.22U F
D IFF BU S_0.22U F
D IFF BU S_0.22U F
D IFF BU S_0.22U F
D IFF BU S_0.22U F
D IFF BU S_0.22U F
D IFF BU S_0.22U F
D IFF BU S_0.22U F
D IFF BU S_0.22U F
D IFF BU S_0.22U F
D IFF BU S_0.22U F
D IFF BU S_0.22U F
6.3VC0201
X 6S
20%
D IFF BU S_0.22U F
D IFF BU S_0.22U F
P5E_CPU0_P2_TX_BUF_DN<15:8>
P5E_CPU0_P2_TX_BUF_DP<15:8>
RETIMER_CPU0_P2(4)
PT5161LRS
SMLF
IC
P5E_CPU0_P2_TX_BUF_DP<7:0>
P5E_CPU0_P2_TX_BUF_DN<7:0>
SMLF
IC
PT5161LRS
2 1
2 1
2 1
2 1
2 1
2 1
2 1
2 1
2 1
2 1
2 1
2 1
2 1
2 1
2 1
2 1
2 1
2 1
2 1
2 1
2 1
2 1
2 1
2 1
2 1
2 1
2 1
2 1
2 1
2 1
2 1
2 1
EU7
EK7
EC7
DT7
DJ7
DB7
CR7
CH7
EW10
EM10
EE10
DV10
DL10
DD10
CU10
CK10
CA7
BP7
BG7
AY7
AN7
AF7
W7
M7
CC10
BT10
BJ10
BB10
AR10
AH10
AA10
P10
7
6
5
7
6
4
3
4
5
3
2
0
1
2
1
0
7
7
6
6
5
5
4
4
3
3
2
2
1
0
1
0
15
14
13
15
14
13
12
11
10
12
11
9
8
10
9
8
15
15
14
13
14
13
12
11
12
10
11
10
9
8
9
8
5
7
15
8
9
10
11
12
13
14
8
9
10
11
12
13
14
15
7
2
3
4
6
0
1
0
1
2
3
4
5
6
U6012
C6582
C6581
C6583
C6584
C6585
C6586
C6587
C6588
C6589
C6590
C6591
C6592
C6593
C6594
C6595
C6596
C6565
C6566
U6012
C6569
C6568
C6567
C6570
C6571
C6572
C6574
C6573
C6576
C6575
C6578
C6577
C6579
C6580
10/11
B_PETN7
B_PETP7
B_PETN6
B_PETP6
B_PETN5
B_PETP5
B_PETN4
B_PETP4
B_PETN3
B_PETP3
B_PETN2
B_PETP2
B_PETN1
B_PETP1
B_PETN0
B_PETP0
11/11
B_PETN15
B_PETP15
B_PETN14
B_PETP14
B_PETN13
B_PETP13
B_PETN12
B_PETP12
B_PETN11
B_PETP11
B_PETN10
B_PETP10
B_PETN9
B_PETP9
B_PETN8
B_PETP8
TX : B_PET[7:0]
TX : B_PET[15:8]
2 1
2 1
2 1
2 1
2 1
2 1
2 1
2 1
2 1
2 1
2 1
2 1
2 1
2 1
2 1
2 1
2 1
2 1
2 1
2 1
2 1
2 1
2 1
2 1
2 1
2 1
2 1
2 1
2 1
2 1
2 1
2 1
1
SHEETDATE
23
7 3 2 16 5 4
E
A
B
C
E
D
C
B
A
7 6 5 4
D
DEPARTMENT
SIZE
PROJECT DOCUMENT NUMBER REV
REVIEWER
DESIGNER
OUT
OUT
IN
IN OUT
OUTIN
OUT
OUT
OUT
OUT
IN
C



CPU1 P0 RT ADDR: 0X48 (8-BIT) / 0X24 (7-BIT)
Thu Aug 24 14:09:43 2023<NAME_2>
<NAME_1>
MB FABCGTI V02
298 OF 365
P 1V 8_CP U0_RT_1D
P 1V 8_CP U0_RT_1D
P 1V 8_CP U0_RT_1D
P 1V 8_CP U0_RT_1D
P 1V 8_CP U0_RT_1D
P 1V 8_CP U0_RT_1D
P 1V 8_CP U0_RT_1D
SMB_RT_CPU0_P2_ROM_MUX_1D_R_SDASMB_RT_CPU0_P2_ROM_MUX_1D_SDA
SMB_RT_CPU0_P2_ROM_MUX_1D_R_SCLSMB_RT_CPU0_P2_ROM_MUX_1D_SCL
1%49.9
0201LFCHIP1/20W
185186
185186
299
299
299
299
299
299
299
299
299
299
299
81 299
81 299
299
299
299
299
299
299
299
299
299
299
184
182
299
299
299
299
299
299
299
299
299
184
299
81 299
81 299
182
299
200
1%
1/20W
CHIP
0201LF
JTAG_TDI_RT_CPU0_P2
JTAG_TMS_RT_CPU0_P2
JTAG_TCK_RT_CPU0_P2
RST_RT_CPU0_P2_RESET_N
JTAG_TDO_RT_CPU0_P2
RST_RT_CPU0_P2_PERST_N
CLKREQ_RT_CPU0_P2_N
RT_CPU0_P2_SCAN_MODE
RXDET_BYP_RT_CPU0_P2
MODE_RT_CPU0_P2
4.7K
5%
1/20W
EMPTY
0201LF
1/20W
5%
EMPTY
4.7K
0201LF
EMPTY
0201LF
1/20W
1%
1K 4.7K
0201LF
5%
EMPTY
1/20W
1K
JTAG_TEST_MODE_RT_CPU0_P2
JTAG_TDI_RT_CPU0_P2
CHIP
0201LF
5%
4.7K
1/20W
CHIP
0201LF
4.7K
0
JTAG_TRST_RT_CPU0_P2_N
JTAG_TMS_RT_CPU0_P2
JTAG_TDO_RT_CPU0_P2
0201LF
RST_RT_CPU0_P2_RESET_R_N
RST_RT_CPU0_P2_PERST_R_N
0201LF
CHIP 0201LF
0201LF
1%
CHIP
1/20W
10K
1%
1/20W
EMPTY
1K
0201LF
RXDET_BYP_RT_CPU0_P2
RT_CPU0_P2_SCAN_MODE
GPIO2_RT_CPU0_P2
GPIO3_RT_CPU0_P2
0201LF
PT5161LRS
SMLF
MODE_RT_CPU0_P2
JTAG_TEST_MODE_RT_CPU0_P2
TEST2_RT_CPU0_P2
TEST1_RT_CPU0_P2
TEST0_RT_CPU0_P2
GPIO3_RT_CPU0_P2
SMB_RT_CPU0_P2_R_SDA
SMB_RT_CPU0_P2_R2_SCL
CLK_100M_RETIMER_CPU0_P2_DP
CLK_100M_RETIMER_CPU0_P2_DN
1%1%
IC
0201LF
EMPTY
RETIMER_CPU0_P2(5)
51.1
1/20W
EMPTY
0201LF
1/20W
51.1
CHIP
0201LF
0 5%
CHIP
CLK_100M_RETIMER_CPU0_P2_R_DN
TEST2_RT_CPU0_P2
0201LF
TEST0_RT_CPU0_P2
RT_CPU0_P2_ADDR3
RT_CPU0_P2_ADDR2
TEST1_RT_CPU0_P2
RT_CPU0_P2_ADDR3
RT_CPU0_P2_ADDR1
RT_CPU0_P2_ADDR1
RT_CPU0_P2_ADDR2
SMB_RT_CPU0_P2_R_SCL
SMB_RT_CPU0_P2_R2_SDA
GPIO2_RT_CPU0_P2
RST_RT_CPU0_P2_PERST_R_N
RST_RT_CPU0_P2_RESET_R_N
0201LF
1/20W
EMPTY
4.7K
5%
1/20W
10K
0201LF
1%
CHIP
0201LF
CHIP
10K
1/20W
1%
EMPTY
0201LF
1K
1%
1/20W
CHIP
1/20W
1%
1K
0201LF
0201LF
EMPTY
1/20W
1K
1%
1/20W
CHIP
1K
1%
0201LF
0201LF
CHIP
1/20W
1%
20K
1/20W
1%
EMPTY
1K
0201LF
0
4.7K
CHIP
5%
1/20W
0201LF
0201LF
4.7K
5%
1/20W
EMPTY
0201LF
5%
4.7K
1/20W
EMPTY
0201LF
5%
4.7K
EMPTY
1/20W1/20W
EMPTY
0201LF
4.7K
5%
1/20W
CHIP
0201LF
4.7K
5%1/20W
CHIP
5%
4.7K
0201LF
4.7K
CHIP
0201LF
5%
1/20W
0201LF
5%0
1/20W CHIP
4.7K
5%
1/20W
0201LF
EMPTY
1/20W
EMPTY
0201LF
4.7K
5%
10K
1%
CHIP
0201LF
1/20W
0201LF
1/20W
5%
4.7K
EMPTY
5%
4.7K
1/20W
CHIP
0201LF
CHIP
1/20W
1%
10K
CLK_100M_RETIMER_CPU0_P2_R_DP
1/20W
JTAG_TCK_RT_CPU0_P2
R1061R1062
FF30
FF27
FF24
E30
B28
B31
B25
B23
F34
FF33
E11
FF11
FJ16
FF18
B16
E18
F2
FJ9
E8
B12
FF8
B9
B6
B3
FJ31
FJ28
FJ25
FJ23
FJ6
FJ3
FF5
G35
U6012
CLOCK
3/11
EE_DAT
EE_CLK
CLKREQ_N
TEST2
TEST1
TEST0
T_SENSE
SMBDAT
SMBCLK
SMB_ADDR3
SMB_ADDR2
SMB_ADDR1
SCAN_MODE
RXDET_BYP
RESET_N
REFCLKP
REFCLKN
REFCLK_OUTP
REFCLK_OUTN
PERST_N
MODE
JTAG_TRST_N
JTAG_TMS
JTAG_TEST_MODE
JTAG_TDO
JTAG_TDI
JTAG_TCK
INT_N
GPIO3
GPIO2
GPIO1
GPIO0
MISC JTAG
TESTEEPROM
SMBUS
GPIO
2
1
R1479
2
1
R1401
2
1
2
1
2
1
2
1
21
2
1
R1405
2
1
R1406
21R1400
2
1
R1065
2
1
2
1
2
1
2
1
2
1
2
1
R1055
2
1
R1058
2
1
R1056
21
21
2
1
R1080
2
1
R1048
2
1
R1066
2
1
R1077
2
1
R1075
2
1
R1079
2
1
R1078
2
1
R1076
21
21
21
21
21
21
2
1
2
1
2
1
R1073
2
1
R1069
2
1
R1072
2
1
R1063
2
1
R1074
2
1
R1070
1
SHEETDATE
23
7 3 2 16 5 4
E
A
B
C
E
D
C
B
A
7 6 5 4
D
DEPARTMENT
SIZE
PROJECT DOCUMENT NUMBER REV
REVIEWER
DESIGNER
IN
OUT
IN
IN
OUT
OUT
IN
IN
IN
IN
IN
OUT
OUT
OUT
OUT
OUT
OUT
OUT
IN
IN
IN
IN
IN
IN
OUT
IN
BI
IN
IN
IN
OUT
BI
IN
IN
IN
IN
OUT
OUT
OUT
OUT
IN
IN
R1478R1477R1476
R1064
R1404
R1059
R1060
R1057
R1047
R1054
R1068
R1067
R680
R681
R614
R613
R634R631
C



Thu Aug 24 14:09:55 2023<NAME_2>
<NAME_1>
MB FABCGTI V02
299 OF 365
200
P 1V 8_CP U0_RT_1D
P0V9_CPU0_RT2_2A_2D
P0V9_CPU0_RT2_2A
P 1V 8_CP U0_RT2_1A _1D
P 1V 8_CP U0_RT2_1A
P 0V 9_CP U0_RT_2D
CHIP
0201LF
1/20W
1%
0201LF
1%
1K
EMPTY
1/20W
RT_CPU0_P2_VQPS
0201LF
0
1/20W
CHIP
5%
1/20W
0
0201LF
5%
CHIP
SMLF
PT5161LRS
PT5161LRS
SMLF
IC
IC
RETIMER_CPU0_P2 POWER(6)
N C F_A1_C PU 0_P2_GN D
N C F_C PU 0_P2_GN D
FH34
FH2
FG35
FG1
FE34
FE2
D35
D1
C34
C2
A35
A1
V35
V1
U34
U2
T4
T32
T22
T13
L35
L1
K34
K2
J4
J22
H31
H19
H16
H12
FJ19
FJ12
FF21
FF14
FD35
FD1
FC9
FC6
FC3
FC28
FC25
FC23
FC19
FB34
FB2
FA32
FA15
ET35
ET1
ER34
ER2
EP4
EP32
EP22
EP13
EJ35
EJ1
EH34
EH2
EG4
EG32
EG22
EG13
EB35
EB1
EA34
EA2
E33
E27
E14
DY4
DY32
DY22
DY13
DR35
DR1
DP34
DP2
DN4
DN32
DN22
DN13
DH35
DH1
DG34
DG2
DF4
DF32
DF22
DF13
DA35
DA1
CY34
CY2
CW4
CW32
CW22
CW13
CP35
CP1
CN34
CN2
CM4
CM32
CM22
CM13
CG35
CG1
CF34
CF2
CE4
CE32
CE22
CE13
BY35
BY1
BW34
BW2
BV4
BV32
BV22
BV13
BN35
BN1
BM34
BM2
BL4
BL32
BL22
BL13
BF35
BF1
BE34
BE2
BD4
BD32
BD22
BD13
B19
AW35
AW1
AV34
AV2
AU4
AU32
AU22
AU13
AM35
AM1
AL34
AL2
AK4
AK32
AK22
AK13
AE35
AE1
AD34
AD2
AC4
AC32
AC22
AC13
G1
CW20
CW17
BL20
BL17
T20
T17
EP20
EP17
EG20
EG17
DY20
DY17
DN20
DN17
DF20
DF17
BD20
BD17
AU20
AU17
AK20
AK17
AC20
AC17
BV17
CM20
CM17
CE20
CE17
BV20
U6012
U6012
4/11
PWR_2A_20
PWR_2A_19
PWR_2A_18
PWR_2A_17
PWR_2A_16
PWR_2A_15
PWR_2A_14
PWR_2A_13
PWR_2A_12
PWR_2A_11
PWR_2A_10
PWR_2A_9
PWR_2A_8
PWR_2A_7
PWR_2A_6
PWR_2A_5
PWR_2A_4
PWR_2A_3
PWR_2A_2
PWR_2A_1
PWR_1D
PWR_2D_4
PWR_2D_3
PWR_2D_2
PWR_2D_1
PWR_1A_5
PWR_1A_4
PWR_1A_3
PWR_1A_2
PWR_1A_1
VQPS
5/11
GND151
GND150
GND149
GND148
GND147
GND146
GND145
GND144
GND143
GND142
GND141
GND140
GND139
GND138
GND137
GND136
GND135
GND134
GND133
GND132
GND131
GND130
GND129
GND128
GND127
GND126
GND125
GND124
GND123
GND122
GND121
GND120
GND119
GND118
GND117
GND116
GND115
GND114
GND113
GND112
GND111
GND110
GND109
GND108
GND107
GND106
GND105
GND104
GND103
GND102
GND101
GND100
GND99
GND98
GND97
GND96
GND95
GND94
GND93
GND92
GND91
GND90
GND89
GND88
GND87
GND86
GND85
GND84
GND83
NCF_GND12
NCF_GND11
NCF_GND10
NCF_GND9
NCF_GND8
NCF_GND7
NCF_GND6
NCF_GND5
NCF_GND4
NCF_GND3
NCF_GND2
NCF_GND1
GND82
GND81
GND80
GND79
GND78
GND77
GND76
GND75
GND74
GND73
GND72
GND71
GND70
GND69
GND68
GND67
GND66
GND65
GND64
GND63
GND62
GND61
GND60
GND59
GND58
GND57
GND56
GND55
GND54
GND53
GND52
GND51
GND50
GND49
GND48
GND47
GND46
GND45
GND44
GND43
GND42
GND41
GND40
GND39
GND38
GND37
GND36
GND35
GND34
GND33
GND32
GND31
GND30
GND29
GND28
GND27
GND26
GND25
GND24
GND23
GND22
GND21
GND20
GND19
GND18
GND17
GND16
GND15
GND14
GND13
GND12
GND11
GND10
GND9
GND8
GND7
GND6
GND5
GND4
GND3
GND2
GND1
0.9V 0.9V
1.8V
/1.8V
1.2V / 1.5V
2
1
R1081
2
1
2
1
2
1
1
SHEETDATE
23
7 3 2 16 5 4
E
A
B
C
E
D
C
B
A
7 6 5 4
D
DEPARTMENT
SIZE
PROJECT DOCUMENT NUMBER REV
REVIEWER
DESIGNER
R1082
R1084
R1083
C



RETIMER EEPRO ADDRESS: 0XA0 (8 BIT) / 0X50 (7 BIT)
Thu Aug 24 14:09:46 2023<NAME_2>
<NAME_1>
MB FABCGTI V02
300 OF 365
P 1V 8_CP U0_RT_1D
185186
185186
SMB_RT_CPU0_P2_ROM_SDASMB_RT_CPU0_P2_ROM_R_SDA
1%33.2
SMB_RT_CPU0_P2_ROM_SCLSMB_RT_CPU0_P2_ROM_R_SCL
1/20W 0201LFCHIP
0201LF
CHIP
1/20W
1%
1K
0.1UF
10%
10V
X 7S
C0201
U16_E2
RETIMER_CPU0_P2(7)
IC
SMLF
M24M02-DRMN6TP
7
4
8
5
6 3
2
1
U16
DU1
DU2
E2
VSSSDA
SCL
WC_N
VCC
2
1 C989
2
1
21
21
1
SHEETDATE
23
7 3 2 16 5 4
E
A
B
C
E
D
C
B
A
7 6 5 4
D
DEPARTMENT
SIZE
PROJECT DOCUMENT NUMBER REV
REVIEWER
DESIGNER
BI
IN R1085R683
R682
C



Thu Aug 24 14:09:56 2023<NAME_2>
<NAME_1>
MB FABCGTI V02
301 OF 365
P0V9_CPU0_RT2_2A_2D
P 1V 8_CP U0_RT_1D
P0V9_CPU0_RT_2D
P 1V 8_CP U0_RT2_1A
P 1V 8_CP U0_RT2_1A _1D
P0V9_CPU0_RT2_2A
C0805
X 6S
20%
4V
100UF100UF
X 6S
4V
C0805
20%
X 6S
100UF
20%
4V
C0805
4V
X 6S
100UF
20%
C0805
C0805
100UF
20%
X 6S
4V
4V
100UF
C0805
X 6S
20%
100UF
4V
20%
C0805
X 6S
C0201
470UF
20%
S MLF
2.5V
S P CA P
0.1UF
2.5V
S MLF
S P CA P
20%
470UF
4V
100UF
C0805
X6S
20%
C0201
0.1UF
10V
0402
0.1UF
10V
10%
X7S
1UF
4V
0201
X 6S
20%
1UF
20%
4V
1UF
X 6S
0201
0201
10%
20%
4V
0201
1UF
20%
0201
4V
X 6S X7S
C0201
X7S
10V
0.1UF
20%
10UF
CHIP
X7S
C0201
1UF
20%
1UF
C0402
0.1UF
4V
X 6S
4V
4V
4.7UF
C0402
X 6S
10V
0402
6.3V
4.7UF
6.3V
0.1UF
10%
20%
X 6S X 6S
20%
0402
20%
10%
X7S X7S
X 6S
5%
0603LF
0.1UF
6.3V
10V
22UF
X 6S
C0402C0402
20%
10UF
6.3V
20%
10UF
X 6S
20%
22UF
4V
X 6S
20%
4V
X 6S
20%
4V
C0402
4V
02010402
4V
C0201
X7S
10V
10%
0201
X 6S
0.1UF
4V
1UF4.7UF10UF
X 6S
BLM21SN300SN1D/5A
0402
C0201
X7S
C0201
X7S
10%
10V
0.1UF0.1UF
10V
22UF
20%
X 6S
C0402
20%
SMLF
BLM15PD121SN1D/1300MA
IND
SMLF
L29/R1050 COLAY WITH R1045/R1046
1/16W
0
5%
EMPTY
0402LF
IND
R1051 AND R1053 COLAY
RETIMER_CPU0_P2 DECAPS(8)
10V
X7S
C0201
C0402
X 6S
20%
X7S
C0201
10V
0.1UF
10%
X7S
4V
X 6SX 6S
4V
X 6S
1UF
X 6S
X7S
C0201
10%
10V
C0201
IND
SMLF
X 6S
C0402
X 6S
0
1/4W
0603LF
5%
1/4W
EMPTY
0
X7S
0402
10%
0.1UF
X7S
C0201
EMPTY1/16W
5%0402LF
1/16W EMPTY
0
0402LF 5%
C0402
X 6S
20%
6.3V
10UF
0.1UF
4.7UF
6.3V
C0201
1UF
10V
10% 10%
20%
4V
22UF
4.7UF
20%
6.3V
10UF
6.3V
20%
10V
0.1UF
20%20%20% 10%
6.3V 4V
0.1UF
0
10V
X7S
C0402
20%
X 6S
0201
1UF
X 6S
0201
X 6S
20%
6.3V
22UF
4V
20%
X 6S
C0402
10V
C0201
10%
100NH/16A
0.1UF
C0201
10%
X 6S
X7S
22UF
20%
C0402 C0402
X 6S
C0402
22UF
0201
6.3V
X 6S
X 6S
10%
X7S
20%
1UF
X 6S
20%
X 6S
20%20%
0402
10UF
0201
4V
1UF
6.3V6.3V
20%
1UF
4V
X 6S
4V
20%20%
0201
10%
X 6S
C0201
1UF 0.1UF
10V
10%
0.1UF
0201
20%
4.7UF
1UF
C0201
10V
0.1UF
10V
10%
0201
1UF
4V
20%
0201
0.1UF
10V
10%
C0201 C0201
X 6S
0201
X7S
10V
20%
4V
X 6S
4.7UF
6.3V
X 6S
1UF
4V
0201
10%
X7S
C0201
0.1UF
10V
10%
X7S
C0201
C667
L29
C7016
C672C669C665
C670
C676
C668C666
2121
2 1
L21L18
CAD NOTE:
CAD NOTE:
1 21 2
12
2
1
2
1 C7015
2
1 C7014
2
1
2
1
2
1
2
1
2
1
R1050
2
1
2
1
2
1
2
1
2
1
2
1
2
1
2
1
2
1
2
1
2
1
2
1
2
1
2
1
2
1
2
1
2
1
2
1
2
1
2
1
2
1
2
1
2
1
2
1
2
1
2
1
2
1
2
1
2
1
2
1
2
1
2
1
2
1
2
1
2
1
2
1
2
1
2
1
2
1
2
1
2
1
2
1
2
1
2
1
2
1
2
1
2
1
2
1
2
1
2
1
21
2
1
2
1
2
1
2
1
2
1
2
1 C677
2
1 C673
2
1
2
1 C671
2
1
2
1
2
1
2
1
21R1045
21R1046
1
SHEETDATE
23
7 3 2 16 5 4
E
A
B
C
E
D
C
B
A
7 6 5 4
D
DEPARTMENT
SIZE
PROJECT DOCUMENT NUMBER REV
REVIEWER
DESIGNER
C985C972
C793C787
C803
C789C785C782C780C980C976C971C805C801
C973C986
C779C786
C968C804
C983
C799C974C988
C783C978C977
C969C966
C970C967
C979C975C792
C802C798
C981
C795
C796
C788C781C797
C784C800C987C790
C794C791
C984C982
R1053
R1051
C778C777C776C774
C775
C



Thu Aug 24 10:16:26 2023<NAME_2>
<NAME_1>
MB FABCGTI V02
302 OF 365RETIMER_CPU0_P2(9)
1
SHEETDATE
23
7 3 2 16 5 4
E
A
B
C
E
D
C
B
A
7 6 5 4
D
DEPARTMENT
SIZE
PROJECT DOCUMENT NUMBER REV
REVIEWER
DESIGNER
C



Thu Aug 24 10:16:27 2023<NAME_2>
<NAME_1>
MB FABCGTI V02
303 OF 365RETIMER_CPU0_P2(10)
1
SHEETDATE
23
7 3 2 16 5 4
E
A
B
C
E
D
C
B
A
7 6 5 4
D
DEPARTMENT
SIZE
PROJECT DOCUMENT NUMBER REV
REVIEWER
DESIGNER
C



Thu Aug 24 10:16:28 2023<NAME_2>
<NAME_1>
MB FABCGTI V02
304 OF 365BLANK
1
SHEETDATE
23
7 3 2 16 5 4
E
A
B
C
E
D
C
B
A
7 6 5 4
D
DEPARTMENT
SIZE
PROJECT DOCUMENT NUMBER REV
REVIEWER
DESIGNER
C



P/N SWAP
P/N SWAP
P/N SWAP
P/N SWAP
P/N SWAP
P/N SWAP
P/N SWAP
P/N SWAPP/N SWAP
P/N SWAP
P/N SWAP
P/N SWAP
P/N SWAP
P/N SWAP
P5E_CPU0_P3_TX_C_DP/DN<0-15> LANE REVERSAL
CPU TO RETIMER CPU TO RETIMER
Thu Aug 24 14:09:39 2023<NAME_2>
<NAME_1>
MB FABCGTI V02
305 OF 365
64
64
64
64
P5E_CPU0_P3_TX_C_DN<7:0>
SMLF
SMLF
PT5161LRS
PT5161LRS
RETIMER_CPU0_P3(1)
IC
IC
P5E_CPU0_P3_TX_C_DN<15:8>
P5E_CPU0_P3_TX_C_DP<15:8>
P5E_CPU0_P3_TX_C_DP<7:0>
EV34
EL34
ED34
DU34
DK34
DC34
CT34
CJ34
EY35
EN35
EF35
DW35
DM35
DE35
CV35
CL35
CB34
BR34
BH34
BA34
AP34
AG34
Y34
N34
CD35
BU35
BK35
BC35
AT35
AJ35
AB35
R35
12
10
11
8
11
13
8
10
12
0
0
6
7
7
1
3
2
4
5
2
1
6
5
4
15
15
9
13
14
14
9
3
U6013
U6013
9/11
B_PERN15
B_PERP15
B_PERN14
B_PERP14
B_PERN13
B_PERP13
B_PERN12
B_PERP12
B_PERN11
B_PERP11
B_PERN10
B_PERP10
B_PERN9
B_PERP9
B_PERN8
B_PERP8
8/11
B_PERN7
B_PERP7
B_PERN6
B_PERP6
B_PERN5
B_PERP5
B_PERN4
B_PERP4
B_PERN3
B_PERP3
B_PERN2
B_PERP2
B_PERN1
B_PERP1
B_PERN0
B_PERP0
RX : B_PER[15:8]
RX : B_PER[7:0]
1
SHEETDATE
23
7 3 2 16 5 4
E
A
B
C
E
D
C
B
A
7 6 5 4
D
DEPARTMENT
SIZE
PROJECT DOCUMENT NUMBER REV
REVIEWER
DESIGNER
IN
IN
IN
IN
C



P5E_CPU0_P3_RX_DP/DN<0-15> LANE REVERSAL
RETIMER TO CPURETIMER TO CPU
Thu Aug 24 14:09:39 2023<NAME_2>
<NAME_1>
MB FABCGTI V02
306 OF 365
25
25 25
25
PT5161LRS
IC
SMLF
SMLF
PT5161LRS
RETIMER_CPU0_P3(2)
P5E_CPU0_P3_RX_DP<15:8>
P5E_CPU0_P3_RX_DN<15:8> P5E_CPU0_P3_RX_DP<7:0>
P5E_CPU0_P3_RX_DN<7:0>
IC
EU26
EK26
EC26
DT26
DJ26
DB26
CR26
CH26
EW29
EM29
EE29
DV29
DL29
DD29
CU29
CK29
CA26
BP26
BG26
AY26
AN26
AF26
W26
M26
CC29
BT29
BJ29
BB29
AR29
AH29
AA29
P29
14
14
6
1
0
1
2
3
0
4
5
7
5
7
8
8
9
9
10
10
11
11
12
12
13
13
15
3
2
4
6
15
U6013
U6013
7/11
A_PETN15
A_PETP15
A_PETN14
A_PETP14
A_PETN13
A_PETP13
A_PETN12
A_PETP12
A_PETN11
A_PETP11
A_PETN10
A_PETP10
A_PETN9
A_PETP9
A_PETN8
A_PETP8
6/11
A_PETN7
A_PETP7
A_PETN6
A_PETP6
A_PETN5
A_PETP5
A_PETN4
A_PETP4
A_PETN3
A_PETP3
A_PETN2
A_PETP2
A_PETN1
A_PETP1
A_PETN0
A_PETP0
TX : A_PET[15:8]
TX : A_PET[7:0]
1
SHEETDATE
23
7 3 2 16 5 4
E
A
B
C
E
D
C
B
A
7 6 5 4
D
DEPARTMENT
SIZE
PROJECT DOCUMENT NUMBER REV
REVIEWER
DESIGNER
OUT
OUT
OUT
OUT
C



EXAMAX TO RETIMEREXAMAX TO RETIMER
P5E_CPU0_P3_RX_BUF_DP/DN<0-15> LANE REVERSAL
Thu Aug 24 14:09:39 2023<NAME_2>
<NAME_1>
MB FABCGTI V02
307 OF 365
115 116
115 116
P5E_CPU0_P3_RX_BUF_DN<15:8> P5E_CPU0_P3_RX_BUF_DN<7:0>
RETIMER_CPU0_P3(3)
SMLF
IC
PT5161LRSPT5161LRS
IC
SMLF
P5E_CPU0_P3_RX_BUF_DP<15:8> P5E_CPU0_P3_RX_BUF_DP<7:0>
EY1
EN1
EF1
DW1
DM1
DE1
CV1
CL1
EV2
EL2
ED2
DU2
DK2
DC2
CT2
CJ2
CD1
BU1
BK1
BC1
AT1
AJ1
AB1
R1
CB2
BR2
BH2
BA2
AP2
AG2
Y2
N2
15
15 7
7
12
14
14
13
12
11
10
9
8
8
9
11
13
10
0
1
2
3
4
5
6
2
3
4
5
6
0
1
U6013U6013
2/11
A_PERN15
A_PERP15
A_PERN14
A_PERP14
A_PERN13
A_PERP13
A_PERN12
A_PERP12
A_PERN11
A_PERP11
A_PERN10
A_PERP10
A_PERN9
A_PERP9
A_PERN8
A_PERP8
1/11
A_PERN7
A_PERP7
A_PERN6
A_PERP6
A_PERN5
A_PERP5
A_PERN4
A_PERP4
A_PERN3
A_PERP3
A_PERN2
A_PERP2
A_PERN1
A_PERP1
A_PERN0
A_PERP0
RX : A_PER[15:8]
RX : A_PER[7:0]
1
SHEETDATE
23
7 3 2 16 5 4
E
A
B
C
E
D
C
B
A
7 6 5 4
D
DEPARTMENT
SIZE
PROJECT DOCUMENT NUMBER REV
REVIEWER
DESIGNER
IN
IN
IN
IN
C



P5E_CPU0_P3_TX_BUF_DP/PD<0-15> LANE REVERSAL
RETIMER TO EXAMAXRETIMER TO EXAMAX
Thu Aug 24 14:09:39 2023<NAME_2>
<NAME_1>
MB FABCGTI V02
308 OF 365
309
309 116
116309
309 115
115
309
309
309
309
6.3V
D IFF BU S_0.22U F
D IFF BU S_0.22U F
P5E_CPU0_P3_TX_BUF_DN<7:0>
P5E_CPU0_P3_TX_BUF_DP<7:0> P5E_CPU0_P3_TX_BUF_C_DP<7:0>
P5E_CPU0_P3_TX_BUF_C_DN<7:0>
D IFF BU S_0.22U F
D IFF BU S_0.22U F
D IFF BU S_0.22U F
D IFF BU S_0.22U F
D IFF BU S_0.22U F
D IFF BU S_0.22U F
D IFF BU S_0.22U F
D IFF BU S_0.22U F
D IFF BU S_0.22U F
D IFF BU S_0.22U F
D IFF BU S_0.22U F
D IFF BU S_0.22U F
D IFF BU S_0.22U F
C0201
X 6S
6.3V20%
D IFF BU S_0.22U FP5E_CPU0_P3_TX_BUF_DN<15:8>
P5E_CPU0_P3_TX_BUF_DP<15:8> P5E_CPU0_P3_TX_BUF_C_DP<15:8>
P5E_CPU0_P3_TX_BUF_C_DN<15:8>
D IFF BU S_0.22U F
D IFF BU S_0.22U F
D IFF BU S_0.22U F
D IFF BU S_0.22U F
D IFF BU S_0.22U F
D IFF BU S_0.22U F
D IFF BU S_0.22U F
D IFF BU S_0.22U F
D IFF BU S_0.22U F
D IFF BU S_0.22U F
D IFF BU S_0.22U F
D IFF BU S_0.22U F
D IFF BU S_0.22U F
D IFF BU S_0.22U F
D IFF BU S_0.22U F
D IFF BU S_0.22U F
20%
X 6S
C0201
P5E_CPU0_P3_TX_BUF_DP<15:8>
P5E_CPU0_P3_TX_BUF_DN<15:8>
RETIMER_CPU0_P3(4)
SMLF
ICIC
SMLF
PT5161LRS
P5E_CPU0_P3_TX_BUF_DP<7:0>
PT5161LRS
P5E_CPU0_P3_TX_BUF_DN<7:0>
2 1
2 1
2 1
2 1
2 1
2 1
2 1
2 1
2 1
2 1
2 1
2 1
2 1
2 1
2 1
2 1
2 1
2 1
2 1
2 1
2 1
2 1
2 1
2 1
2 1
2 1
2 1
2 1
2 1
2 1
2 1
2 1
EU7
EK7
EC7
DT7
DJ7
DB7
CR7
CH7
EW10
EM10
EE10
DV10
DL10
DD10
CU10
CK10
CA7
BP7
BG7
AY7
AN7
AF7
W7
M7
CC10
BT10
BJ10
BB10
AR10
AH10
AA10
P10
7
7 7
7
5
6
4
3
2
1
0
6
4
5
3
2
1
0
6
5
4
3
2
6
5
4
3
2
1
0
0
1
15
14
15
14
11
12
13
13
12
11
10
9
10
9
8
8
15
14
15
14
13
12
11
13
12
11
10
9
10
9
8
8
8
15
14
12
13
10
11
9
8
9
10
11
12
13
14
15 7
0
1
2
3
4
5
6
0
1
2
3
4
5
6
7
U6013
C6613
C6614
C6616
C6615
C6617
C6619
C6618
C6620
C6622
C6621
C6624
C6623
C6627
C6626
C6625
C6628
U6013
C6597
C6598
C6599
C6600
C6601
C6602
C6603
C6604
C6605
C6606
C6607
C6608
C6609
C6610
C6612
C6611
10/11
B_PETN7
B_PETP7
B_PETN6
B_PETP6
B_PETN5
B_PETP5
B_PETN4
B_PETP4
B_PETN3
B_PETP3
B_PETN2
B_PETP2
B_PETN1
B_PETP1
B_PETN0
B_PETP0
11/11
B_PETN15
B_PETP15
B_PETN14
B_PETP14
B_PETN13
B_PETP13
B_PETN12
B_PETP12
B_PETN11
B_PETP11
B_PETN10
B_PETP10
B_PETN9
B_PETP9
B_PETN8
B_PETP8
TX : B_PET[7:0]
TX : B_PET[15:8]
2 1
2 1
2 1
2 1
2 1
2 1
2 1
2 1
2 1
2 1
2 1
2 1
2 1
2 1
2 1
2 1
2 1
2 1
2 1
2 1
2 1
2 1
2 1
2 1
2 1
2 1
2 1
2 1
2 1
2 1
2 1
2 1
1
SHEETDATE
23
7 3 2 16 5 4
E
A
B
C
E
D
C
B
A
7 6 5 4
D
DEPARTMENT
SIZE
PROJECT DOCUMENT NUMBER REV
REVIEWER
DESIGNER
OUT
OUT
IN
IN OUT
OUT
IN
OUT
OUT
OUT
OUT IN
C



CPU1 P0 RT ADDR: 0X48 (8-BIT) / 0X24 (7-BIT)
Thu Aug 24 14:09:43 2023<NAME_2>
<NAME_1>
MB FABCGTI V02
309 OF 365
P 1V 8_CP U0_RT_1D
P 1V 8_CP U0_RT_1D
P 1V 8_CP U0_RT_1D
P 1V 8_CP U0_RT_1DP 1V 8_CP U0_RT_1D
P 1V 8_CP U0_RT_1D
P 1V 8_CP U0_RT_1D
SMB_RT_CPU0_P3_ROM_MUX_1D_R_SCLSMB_RT_CPU0_P3_ROM_MUX_1D_SCL
1%49.9
1/20W CHIP 0201LF
SMB_RT_CPU0_P3_ROM_MUX_1D_R_SDASMB_RT_CPU0_P3_ROM_MUX_1D_SDA
185186
185186
81 310
310
310
310
310
81 310
81 310
310
310
310
310
310
310
310
310
310
182
182
310
310
184
184
310
310
310
310
310
310
310
310
310
81 310
310
310
310
310
310
310
310
310
200
1%
1/20W
CHIP
0201LF
RST_RT_CPU0_P3_RESET_N RST_RT_CPU0_P3_RESET_R_N
CHIP
1%
0201LF
10K
1/20W
1K
EMPTY
1/20W
1%
0201LF
RXDET_BYP_RT_CPU0_P3
0201LF
RT_CPU0_P3_SCAN_MODE
GPIO2_RT_CPU0_P3
CLK_100M_RETIMER_CPU0_P3_DP
0
1/20W
GPIO3_RT_CPU0_P3
1/20W
5%
4.7K
EMPTY
0201LF
CHIP
1/20W
1%
10K
0201LF
10K
1%
CHIP
1/20W
0201LF
5%
4.7K
1/20W
CHIP
1/20W
EMPTY
0201LF
4.7K
5%
4.7K
5%
1/20W
0201LF
EMPTY
5%
CHIP1/20W 0201LF
0
CHIP
1/20W
0201LF
4.7K
5%
0201LF
1/20W
5%
4.7K
CHIP
0201LF
CHIP
1/20W
5%
4.7K
4.7K
1/20W
EMPTY
0201LF
5%
4.7K
0201LF
5%
EMPTY
1/20W
4.7K
0201LF
5%
1/20W
EMPTY
4.7K
5%
1/20W
EMPTY
0201LF
4.7K
CHIP
5%
1/20W
0201LF
1%
1K
0201LF
1/20W
EMPTY
0201LF
1%
20K
1/20W
CHIP
1%
1/20W
CHIP
0201LF
1K
EMPTY
0201LF
1/20W
1K
1%
CHIP
1K
1%
1/20W
0201LF
EMPTY
1K
0201LF
1%
1/20W
0201LF
CHIP
1/20W
1%
10K
0201LF
CHIP
10K
1/20W
1%
1/20W
5%
4.7K
EMPTY
0201LF
RST_RT_CPU0_P3_RESET_R_N
RST_RT_CPU0_P3_PERST_R_N
MODE_RT_CPU0_P3
JTAG_TEST_MODE_RT_CPU0_P3
PT5161LRS
TEST2_RT_CPU0_P3
TEST1_RT_CPU0_P3
RT_CPU0_P3_ADDR1
RT_CPU0_P3_ADDR2
RT_CPU0_P3_ADDR3
RT_CPU0_P3_ADDR3
TEST0_RT_CPU0_P3
0201LF
CLK_100M_RETIMER_CPU0_P3_R_DP
5%
CLK_100M_RETIMER_CPU0_P3_R_DN CLK_100M_RETIMER_CPU0_P3_DN
1/20W
EMPTY
51.1
1%
51.1
EMPTY
0201LF 0201LF
0201LF
1%
1/20W
IC
SMLF
RETIMER_CPU0_P3(5)
CHIP
CHIP
RT_CPU0_P3_ADDR1
RT_CPU0_P3_ADDR2
SMB_RT_CPU0_P3_R2_SDA
SMB_RT_CPU0_P3_R2_SCL
SMB_RT_CPU0_P3_R_SDA
SMB_RT_CPU0_P3_R_SCL
TEST2_RT_CPU0_P3
TEST1_RT_CPU0_P3
TEST0_RT_CPU0_P3
GPIO3_RT_CPU0_P3
GPIO2_RT_CPU0_P3
MODE_RT_CPU0_P3
0
JTAG_TDO_RT_CPU0_P3
CHIP
0201LF
0201LF
JTAG_TMS_RT_CPU0_P3
JTAG_TDI_RT_CPU0_P3
0 0201LF
0201LF
RST_RT_CPU0_P3_PERST_R_N
CLKREQ_RT_CPU0_P3_N
1K CHIP
5%
4.7K
1/20W
CHIP
0201LF
JTAG_TCK_RT_CPU0_P3
RT_CPU0_P3_SCAN_MODE
RXDET_BYP_RT_CPU0_P3
JTAG_TEST_MODE_RT_CPU0_P3
JTAG_TRST_RT_CPU0_P3_N
4.7K
4.7K
0201LF
5%
EMPTY
1/20W
EMPTY
0201LF
1/20W
1%
1K
1/20W
5%
EMPTY
4.7K
0201LF
4.7K
5%
1/20W
EMPTY
0201LF
JTAG_TMS_RT_CPU0_P3
JTAG_TDI_RT_CPU0_P3
JTAG_TCK_RT_CPU0_P3
JTAG_TDO_RT_CPU0_P3
RST_RT_CPU0_P3_PERST_N
R1104 R1103
FF30
FF27
FF24
E30
B28
B31
B25
B23
F34
FF33
E11
FF11
FJ16
FF18
B16
E18
F2
FJ9
E8
B12
FF8
B9
B6
B3
FJ31
FJ28
FJ25
FJ23
FJ6
FJ3
FF5
G35
U6013
CLOCK
3/11
EE_DAT
EE_CLK
CLKREQ_N
TEST2
TEST1
TEST0
T_SENSE
SMBDAT
SMBCLK
SMB_ADDR3
SMB_ADDR2
SMB_ADDR1
SCAN_MODE
RXDET_BYP
RESET_N
REFCLKP
REFCLKN
REFCLK_OUTP
REFCLK_OUTN
PERST_N
MODE
JTAG_TRST_N
JTAG_TMS
JTAG_TEST_MODE
JTAG_TDO
JTAG_TDI
JTAG_TCK
INT_N
GPIO3
GPIO2
GPIO1
GPIO0
MISC JTAG
TESTEEPROM
SMBUS
GPIO
2
1
R1485
2
1
2
1
R1409
2
1
2
1
2
1
21
2
1
R1413
2
1
R1414
21R1408
2
1
R1107
2
1
2
1
2
1
2
1
2
1
2
1
R1097
2
1
R1100
2
1
R1098
21
21
2
1
R1122
2
1
R1091
2
1
R1108
2
1
R1119
2
1
R1116
2
1
R1121
2
1
R1120
2
1
R1118
21
21
21
21
21
2
1
2
1
21
2
1
R1114
2
1
R1111
2
1
R1115
2
1
R1113
2
1
R1112
2
1
R1105
1
SHEETDATE
23
7 3 2 16 5 4
E
A
B
C
E
D
C
B
A
7 6 5 4
D
DEPARTMENT
SIZE
PROJECT DOCUMENT NUMBER REV
REVIEWER
DESIGNER
IN
IN
IN
IN
OUT
OUT
OUT
IN
IN
IN
IN
IN
OUT
OUT
OUT
OUT
OUT
OUT
OUT
IN
IN
IN
IN
IN
OUT
IN
BI
IN
IN
IN
IN
OUT
BI
IN
IN
IN
IN
OUT
OUT
OUT
OUT
IN
R1484R1483R1482
R1106
R1412
R1101
R1102
R1099
R1088
R1096
R1110
R1109
R684
R686
R615
R636R635
R616
C



Thu Aug 24 14:09:56 2023<NAME_2>
<NAME_1>
MB FABCGTI V02
310 OF 365
P0V9_CPU0_RT3_2A_2D
P0V9_CPU0_RT3_2A
P 1V 8_CP U0_RT3_1A
P 0V 9_CP U0_RT_2D
P 1V 8_CP U0_RT3_1A _1D
P 1V 8_CP U0_RT_1D
IC
SMLF
PT5161LRS
IC
PT5161LRS
SMLF
RETIMER_CPU0_P3 POWER(6)
N C F_A1_C PU 0_P3_GN D
N C F_C PU 0_P3_GN D
1/20W
0
0201LF
5%
CHIP
0201LF
0
1/20W
CHIP
5%
RT_CPU0_P3_VQPS
0201LF
EMPTY
1/20W
1%
1K
1/20W
0201LF
CHIP
1%
200
FH34
FH2
FG35
FG1
FE34
FE2
D35
D1
C34
C2
A35
A1
V35
V1
U34
U2
T4
T32
T22
T13
L35
L1
K34
K2
J4
J22
H31
H19
H16
H12
FJ19
FJ12
FF21
FF14
FD35
FD1
FC9
FC6
FC3
FC28
FC25
FC23
FC19
FB34
FB2
FA32
FA15
ET35
ET1
ER34
ER2
EP4
EP32
EP22
EP13
EJ35
EJ1
EH34
EH2
EG4
EG32
EG22
EG13
EB35
EB1
EA34
EA2
E33
E27
E14
DY4
DY32
DY22
DY13
DR35
DR1
DP34
DP2
DN4
DN32
DN22
DN13
DH35
DH1
DG34
DG2
DF4
DF32
DF22
DF13
DA35
DA1
CY34
CY2
CW4
CW32
CW22
CW13
CP35
CP1
CN34
CN2
CM4
CM32
CM22
CM13
CG35
CG1
CF34
CF2
CE4
CE32
CE22
CE13
BY35
BY1
BW34
BW2
BV4
BV32
BV22
BV13
BN35
BN1
BM34
BM2
BL4
BL32
BL22
BL13
BF35
BF1
BE34
BE2
BD4
BD32
BD22
BD13
B19
AW35
AW1
AV34
AV2
AU4
AU32
AU22
AU13
AM35
AM1
AL34
AL2
AK4
AK32
AK22
AK13
AE35
AE1
AD34
AD2
AC4
AC32
AC22
AC13
G1
CW20
CW17
BL20
BL17
T20
T17
EP20
EP17
EG20
EG17
DY20
DY17
DN20
DN17
DF20
DF17
BD20
BD17
AU20
AU17
AK20
AK17
AC20
AC17
BV17
CM20
CM17
CE20
CE17
BV20
U6013
U6013
4/11
PWR_2A_20
PWR_2A_19
PWR_2A_18
PWR_2A_17
PWR_2A_16
PWR_2A_15
PWR_2A_14
PWR_2A_13
PWR_2A_12
PWR_2A_11
PWR_2A_10
PWR_2A_9
PWR_2A_8
PWR_2A_7
PWR_2A_6
PWR_2A_5
PWR_2A_4
PWR_2A_3
PWR_2A_2
PWR_2A_1
PWR_1D
PWR_2D_4
PWR_2D_3
PWR_2D_2
PWR_2D_1
PWR_1A_5
PWR_1A_4
PWR_1A_3
PWR_1A_2
PWR_1A_1
VQPS
5/11
GND151
GND150
GND149
GND148
GND147
GND146
GND145
GND144
GND143
GND142
GND141
GND140
GND139
GND138
GND137
GND136
GND135
GND134
GND133
GND132
GND131
GND130
GND129
GND128
GND127
GND126
GND125
GND124
GND123
GND122
GND121
GND120
GND119
GND118
GND117
GND116
GND115
GND114
GND113
GND112
GND111
GND110
GND109
GND108
GND107
GND106
GND105
GND104
GND103
GND102
GND101
GND100
GND99
GND98
GND97
GND96
GND95
GND94
GND93
GND92
GND91
GND90
GND89
GND88
GND87
GND86
GND85
GND84
GND83
NCF_GND12
NCF_GND11
NCF_GND10
NCF_GND9
NCF_GND8
NCF_GND7
NCF_GND6
NCF_GND5
NCF_GND4
NCF_GND3
NCF_GND2
NCF_GND1
GND82
GND81
GND80
GND79
GND78
GND77
GND76
GND75
GND74
GND73
GND72
GND71
GND70
GND69
GND68
GND67
GND66
GND65
GND64
GND63
GND62
GND61
GND60
GND59
GND58
GND57
GND56
GND55
GND54
GND53
GND52
GND51
GND50
GND49
GND48
GND47
GND46
GND45
GND44
GND43
GND42
GND41
GND40
GND39
GND38
GND37
GND36
GND35
GND34
GND33
GND32
GND31
GND30
GND29
GND28
GND27
GND26
GND25
GND24
GND23
GND22
GND21
GND20
GND19
GND18
GND17
GND16
GND15
GND14
GND13
GND12
GND11
GND10
GND9
GND8
GND7
GND6
GND5
GND4
GND3
GND2
GND1
0.9V 0.9V
1.8V
/1.8V
1.2V / 1.5V
2
1
R1123
2
1
2
1
2
1
1
SHEETDATE
23
7 3 2 16 5 4
E
A
B
C
E
D
C
B
A
7 6 5 4
D
DEPARTMENT
SIZE
PROJECT DOCUMENT NUMBER REV
REVIEWER
DESIGNER
R1124
R1126
R1125
C



RETIMER EEPRO ADDRESS: 0XA0 (8 BIT) / 0X50 (7 BIT)
Thu Aug 24 14:09:46 2023<NAME_2>
<NAME_1>
MB FABCGTI V02
311 OF 365
P 1V 8_CP U0_RT_1D
185186
185186
SMB_RT_CPU0_P3_ROM_SDASMB_RT_CPU0_P3_ROM_R_SDA
1%33.2
SMB_RT_CPU0_P3_ROM_SCLSMB_RT_CPU0_P3_ROM_R_SCL
0201LF1/20W CHIP
1K
1%
1/20W
CHIP
0201LF
0.1UF
C0201
X 7S
10%
10V
M24M02-DRMN6TP
IC
SMLF
U17_E2
RETIMER_CPU0_P3(7)
7
4
8
5
6 3
2
1
U17
DU1
DU2
E2
VSSSDA
SCL
WC_N
VCC
2
1 C1057
2
1
21
21
1
SHEETDATE
23
7 3 2 16 5 4
E
A
B
C
E
D
C
B
A
7 6 5 4
D
DEPARTMENT
SIZE
PROJECT DOCUMENT NUMBER REV
REVIEWER
DESIGNER
IN
BI R1127R688
R687
C



Thu Aug 24 14:09:56 2023<NAME_2>
<NAME_1>
MB FABCGTI V02
312 OF 365
P0V9_CPU0_RT3_2A_2D
P0V9_CPU0_RT_2D
P 1V 8_CP U0_RT_1D
P 1V 8_CP U0_RT3_1A
P 1V 8_CP U0_RT3_1A _1D
P0V9_CPU0_RT3_2A
100UF
4V
20%
X 6S
C0805
100UF
4V
X 6S
C0805
20%
100UF
4V
X 6S
20%
C0805
C0805
X 6S
4V
20%
100UF
C0805
4V
100UF
X 6S
20%
4V
100UF
20%
X 6S
C0805
X 6S
4V
C0805
100UF
20%
0201 0201
S P CA P
2.5V
S MLF
20%
470UF 470UF
20%
S P CA P
S MLF
2.5V 20%
X6S
C0805
100UF
4V0.1UF
C0201C0201
X7S
10%
0201
20%
C0402
X 6S
20%
4V
4.7UF
6.3V
0402
X 6S
20%
22UF
10V
X 6S
20%
0402C0402
X 6S
20%
4V
20%
X 6S
0201
X 6S
0.1UF
10V
10%
C0201 C0201
10%
0.1UF
10V
10%
10V
0.1UF0.1UF
X7S
1UF
20%
0201
X 6S
1UF
4V4V
20%
X 6S
0201
X7S
C0201
10%
X7S
10V
0.1UF
10V
10%
6.3V
X 6S
0201
X 6S
4.7UF
20%20%
10UF
10V
0.1UF
4V
20%
4V
X 6S
1UF
20%
X 6S
0402
0.1UF
10V
1UF
X 6S
X 6S
C0201
4V
4V
X 6S
02010201
4V
1UF
X 6S
20%
10UF
X 6S
C0402
X 6S
20%
X 6S
X7S
1UF
6.3V
6.3V
C0201 C0201
X7S
10%
0.1UF
10V
10%
10V10V
0.1UF4V 0.1UF
X7S
X7S X7S
C0201
10V
0.1UF0.1UF
6.3V
20%
C0201
10V
X7S
C0201
0
10UF
10V
10%
4V
IND
22UF
X 6S
20%
5%
5%
BLM21SN300SN1D/5A
X 6S
20%
SMLF
R1094 AND R1095 COLAY
0.1UF4V
RETIMER_CPU0_P3 DECAPS(8)
0603LF1/4W
5%0
0
EMPTY
1/4W
5%
0603LF
X7S
EMPTY
20%
0201
X 6S
C0201
X7S
10%
10V
X 6S
20%
6.3V
X 6S
0402
10% 10%
X7S
10%
0.1UF
C0201
X7S
10V
10%
0.1UF
X 6S X 6S
20%
20%
10V
10%
C0201
IND
C0402
X 6S
C0201
X7S
C0201
X7S
10%
X 6S
1UF
10V
X7SX7SX7S
4V
0.1UF
0
1UF
0
0402LF
1/16W
0402LF
1/16W
5%
IND
SMLF
BLM15PD121SN1D/1300MA
0402LF
EMPTY
1/16W
EMPTY
X 6S
20%
10UF
22UF
4.7UF
C0402
C0402
20%
4V
20%
6.3V
1UF
4V
X 6S
20%
C0402C0402
1UF
SMLF
100NH/16A
22UF
X 6S
10UF
6.3V
X 6S
C0402
1UF
4V
20%
6.3V
20%
20%
4.7UF
10%
20%
X 6S
0201
0402
L30/R1093 COLAY WITH R1086/R1087
0201
0.1UF
10V
0.1UF
0402
X 6S
0402
X 6S
4.7UF
6.3V
X 6S
0201 C0201
6.3V
C0402
10UF
10UF
20%
4.7UF
4V 4V 4V 6.3V
20%20%20%
22UF 22UF 22UF
6.3V
4.7UF
X 6S
20%
20%
4V4V
C0402 C0402 C0402
1UF
0201
1UF1UF
4V
20%20%
0.1UF
1UF
X7S
1UF
4V
10V
10%
X 6S
02010201
10% 10%
10V
20%
1UF
C0201
0.1UF
CHIP
10%
C0201 C0201
6.3V
C0402
4V
0201
X7S
C0201
C992
C7019
C997C994C990
C996C993C991
C999
2121
2 1
L23L22
CAD NOTE:
CAD NOTE:
1 21 2
L30
12
2
1
2
1 C7018
2
1 C7017
2
1
2
1
2
1
2
1
2
1
R1093
2
1
2
1
2
1
2
1
2
1
2
1
2
1
2
1
2
1
2
1
2
1
2
1
2
1
2
1
2
1
2
1
2
1
2
1
2
1
2
1
2
1
2
1
2
1
2
1
2
1
2
1
2
1
2
1
2
1
2
1
2
1
2
1
2
1
2
1
2
1
2
1
2
1
2
1
2
1
2
1
2
1
2
1
2
1
2
1
21
2
1
2
1
2
1
2
1
2
1
2
1
2
1 C1000
2
1
2
1
2
1
2
1
2
1 C998
2
1
2
1 C995
2
1
2
1
2
1
2
1
2
1
21R1086
21R1087
1
SHEETDATE
23
7 3 2 16 5 4
E
A
B
C
E
D
C
B
A
7 6 5 4
D
DEPARTMENT
SIZE
PROJECT DOCUMENT NUMBER REV
REVIEWER
DESIGNER
C1053C1051
C1020C1018
C1045
C1040
C1048C1012C1009C1007
C1049C1037C1041C1030
C1016C1038C1032 C1044
C1026C1033C1029
C1028
C1025C1022
C1017C1013C1050C1046
C1019
C1047C1043C1011C1008
C1056C1054
C1015C1039
C1034
C1006C1031
C1035C1055C1052C1010
C1036C1023
C1027C1024
R1095
C1021C1014
C1005C1004C1003C1001
R1094
C1002
C



Thu Aug 24 10:16:35 2023<NAME_2>
<NAME_1>
MB FABCGTI V02
313 OF 365RETIMER_CPU0_P3(9)
1
SHEETDATE
23
7 3 2 16 5 4
E
A
B
C
E
D
C
B
A
7 6 5 4
D
DEPARTMENT
SIZE
PROJECT DOCUMENT NUMBER REV
REVIEWER
DESIGNER
C



Thu Aug 24 10:16:36 2023<NAME_2>
<NAME_1>
MB FABCGTI V02
314 OF 365RETIMER_CPU0_P3(10)
1
SHEETDATE
23
7 3 2 16 5 4
E
A
B
C
E
D
C
B
A
7 6 5 4
D
DEPARTMENT
SIZE
PROJECT DOCUMENT NUMBER REV
REVIEWER
DESIGNER
C



Thu Aug 24 10:16:37 2023<NAME_2>
<NAME_1>
MB FABCGTI V02
315 OF 365BLANK
1
SHEETDATE
23
7 3 2 16 5 4
E
A
B
C
E
D
C
B
A
7 6 5 4
D
DEPARTMENT
SIZE
PROJECT DOCUMENT NUMBER REV
REVIEWER
DESIGNER
C



P/N SWAP
P/N SWAP
P/N SWAP
P5E_CPU1_P0_TX_C_DP/DN<0-15> LANE REVERSAL
P/N SWAP
P/N SWAP
P/N SWAP
P/N SWAP
P/N SWAP
P/N SWAP
P/N SWAP
P/N SWAP
P/N SWAP
P/N SWAP
P/N SWAP
CPU TO RETIMER CPU TO RETIMER
Thu Aug 24 14:09:39 2023<NAME_2>
<NAME_1>
MB FABCGTI V02
316 OF 365
65
65
65
65
IC
PT5161LRS
SMLF
IC
PT5161LRS
SMLF
RETIMER_CPU1_P0(1)
P5E_CPU1_P0_TX_C_DP<7:0>
P5E_CPU1_P0_TX_C_DN<7:0>
P5E_CPU1_P0_TX_C_DN<15:8>
P5E_CPU1_P0_TX_C_DP<15:8>
EV34
EL34
ED34
DU34
DK34
DC34
CT34
CJ34
EY35
EN35
EF35
DW35
DM35
DE35
CV35
CL35
CB34
BR34
BH34
BA34
AP34
AG34
Y34
N34
CD35
BU35
BK35
BC35
AT35
AJ35
AB35
R35
13
14
13
15
15
6
12
11
10
9
8
8
9
10
11
12
14
6
5
4
3
2
0
0
2
3
4
5
7
7
1
1
U6014
U6014
9/11
B_PERN15
B_PERP15
B_PERN14
B_PERP14
B_PERN13
B_PERP13
B_PERN12
B_PERP12
B_PERN11
B_PERP11
B_PERN10
B_PERP10
B_PERN9
B_PERP9
B_PERN8
B_PERP8
8/11
B_PERN7
B_PERP7
B_PERN6
B_PERP6
B_PERN5
B_PERP5
B_PERN4
B_PERP4
B_PERN3
B_PERP3
B_PERN2
B_PERP2
B_PERN1
B_PERP1
B_PERN0
B_PERP0
RX : B_PER[15:8]
RX : B_PER[7:0]
1
SHEETDATE
23
7 3 2 16 5 4
E
A
B
C
E
D
C
B
A
7 6 5 4
D
DEPARTMENT
SIZE
PROJECT DOCUMENT NUMBER REV
REVIEWER
DESIGNER
IN
IN
IN
IN
C



P5E_CPU1_P0_RX_DP/DN<0-15> LANE REVERSAL
RETIMER TO CPURETIMER TO CPU
Thu Aug 24 14:09:40 2023<NAME_2>
<NAME_1>
MB FABCGTI V02
317 OF 365
51
51
51
51
P5E_CPU1_P0_RX_DN<7:0>
P5E_CPU1_P0_RX_DP<7:0>
PT5161LRS
RETIMER_CPU1_P0(2)
IC
SMLF
PT5161LRS
IC
SMLF
P5E_CPU1_P0_RX_DP<15:8>
P5E_CPU1_P0_RX_DN<15:8>
EU26
EK26
EC26
DT26
DJ26
DB26
CR26
CH26
EW29
EM29
EE29
DV29
DL29
DD29
CU29
CK29
CA26
BP26
BG26
AY26
AN26
AF26
W26
M26
CC29
BT29
BJ29
BB29
AR29
AH29
AA29
P29
1
1
7
3
4
3
2
5
8
6
4
6
5
2
0
15
15
13
12
12
13
11
10
9
9
10
11
8
0
7
14
14
U6014
U6014
7/11
A_PETN15
A_PETP15
A_PETN14
A_PETP14
A_PETN13
A_PETP13
A_PETN12
A_PETP12
A_PETN11
A_PETP11
A_PETN10
A_PETP10
A_PETN9
A_PETP9
A_PETN8
A_PETP8
6/11
A_PETN7
A_PETP7
A_PETN6
A_PETP6
A_PETN5
A_PETP5
A_PETN4
A_PETP4
A_PETN3
A_PETP3
A_PETN2
A_PETP2
A_PETN1
A_PETP1
A_PETN0
A_PETP0
TX : A_PET[15:8]
TX : A_PET[7:0]
1
SHEETDATE
23
7 3 2 16 5 4
E
A
B
C
E
D
C
B
A
7 6 5 4
D
DEPARTMENT
SIZE
PROJECT DOCUMENT NUMBER REV
REVIEWER
DESIGNER
OUT
OUT
OUT
OUT
C



EXAMAX TO RETIMEREXAMAX TO RETIMER
P5E_CPU1_P0_RX_BUF_DP/DN<0-15> LANE REVERSAL
Thu Aug 24 14:09:36 2023<NAME_2>
<NAME_1>
MB FABCGTI V02
318 OF 365
122
122
121
121
P5E_CPU1_P0_RX_BUF_DN<7:0>
P5E_CPU1_P0_RX_BUF_DP<7:0>
P5E_CPU1_P0_RX_BUF_DN<15:8>
P5E_CPU1_P0_RX_BUF_DP<15:8>
SMLF
IC
PT5161LRS PT5161LRS
IC
SMLF
RETIMER_CPU1_P0(3)
EY1
EN1
EF1
DW1
DM1
DE1
CV1
CL1
EV2
EL2
ED2
DU2
DK2
DC2
CT2
CJ2
CD1
BU1
BK1
BC1
AT1
AJ1
AB1
R1
CB2
BR2
BH2
BA2
AP2
AG2
Y2
N2 7
6
5
4
3
2
1
0
6
5
4
3
2
1
0
7
15
14
13
12
11
10
9
8
14
13
12
11
10
9
8
15
U6014U6014
2/11
A_PERN15
A_PERP15
A_PERN14
A_PERP14
A_PERN13
A_PERP13
A_PERN12
A_PERP12
A_PERN11
A_PERP11
A_PERN10
A_PERP10
A_PERN9
A_PERP9
A_PERN8
A_PERP8
1/11
A_PERN7
A_PERP7
A_PERN6
A_PERP6
A_PERN5
A_PERP5
A_PERN4
A_PERP4
A_PERN3
A_PERP3
A_PERN2
A_PERP2
A_PERN1
A_PERP1
A_PERN0
A_PERP0
RX : A_PER[15:8]
RX : A_PER[7:0]
1
SHEETDATE
23
7 3 2 16 5 4
E
A
B
C
E
D
C
B
A
7 6 5 4
D
DEPARTMENT
SIZE
PROJECT DOCUMENT NUMBER REV
REVIEWER
DESIGNER
IN
IN
IN
IN
C



RETIMER TO EXAMAX
P5E_CPU1_P0_TX_BUF_DP/DN<0-15> LANE REVERSAL
RETIMER TO EXAMAX
Thu Aug 24 14:09:40 2023<NAME_2>
<NAME_1>
MB FABCGTI V02
319 OF 365
320
320
122
122320
320
121
121
320
320
320
320
D IFF BU S_0.22U F
P5E_CPU1_P0_TX_BUF_DP<7:0>
P5E_CPU1_P0_TX_BUF_DN<7:0>
P5E_CPU1_P0_TX_BUF_C_DP<7:0>
P5E_CPU1_P0_TX_BUF_C_DN<7:0>
D IFF BU S_0.22U F
D IFF BU S_0.22U F
D IFF BU S_0.22U F
D IFF BU S_0.22U F
D IFF BU S_0.22U F
D IFF BU S_0.22U F
D IFF BU S_0.22U F
D IFF BU S_0.22U F
D IFF BU S_0.22U F
D IFF BU S_0.22U F
D IFF BU S_0.22U F
D IFF BU S_0.22U F
C0201
D IFF BU S_0.22U F
6.3V20%
X 6S
D IFF BU S_0.22U F
D IFF BU S_0.22U F
P5E_CPU1_P0_TX_BUF_DN<15:8>
P5E_CPU1_P0_TX_BUF_DP<15:8>
P5E_CPU1_P0_TX_BUF_C_DN<15:8>
P5E_CPU1_P0_TX_BUF_C_DP<15:8>
D IFF BU S_0.22U F
D IFF BU S_0.22U F
D IFF BU S_0.22U F
D IFF BU S_0.22U F
D IFF BU S_0.22U F
D IFF BU S_0.22U F
D IFF BU S_0.22U F
D IFF BU S_0.22U F
D IFF BU S_0.22U F
D IFF BU S_0.22U F
D IFF BU S_0.22U F
D IFF BU S_0.22U F
D IFF BU S_0.22U F
D IFF BU S_0.22U F
D IFF BU S_0.22U F
C0201 20%
X 6S
6.3V
D IFF BU S_0.22U F
IC IC
PT5161LRS
SMLFPT5161LRS
SMLF
RETIMER_CPU1_P0(4)
P5E_CPU1_P0_TX_BUF_DP<15:8>
P5E_CPU1_P0_TX_BUF_DN<15:8>
P5E_CPU1_P0_TX_BUF_DP<7:0>
P5E_CPU1_P0_TX_BUF_DN<7:0>
2 1
2 1
2 1
2 1
2 1
2 1
2 1
2 1
2 1
2 1
2 1
2 1
2 1
2 1
2 1
2 1
2 1
2 1
2 1
2 1
2 1
2 1
2 1
2 1
2 1
2 1
2 1
2 1
2 1
2 1
2 1
2 1
EU7
EK7
EC7
DT7
DJ7
DB7
CR7
CH7
EW10
EM10
EE10
DV10
DL10
DD10
CU10
CK10
CA7
BP7
BG7
AY7
AN7
AF7
W7
M7
CC10
BT10
BJ10
BB10
AR10
AH10
AA10
P10
7
6
5
4
7
6
5
7
5
7
4
5
3
2
1
0
4
3
2
1
0
4
3
2
1
0
3
2
1
0
6
6
13
15
14
12
11
10
9
8
15
14
13
12
11
10
9
8
15
15
14
14
13
13
12
11
11
10
10
9
8
9
8
12
14
8
9
10
11
12
13
8
9
10
11
12
13
14
15
7
0
1
2
3
4
5
6
0
1
2
3
4
5
6
7
15
U6014
C6645
C6646
C6648
C6647
C6650
C6649
C6651
C6652
C6653
C6654
C6655
C6656
C6657
C6658
C6659
C6660
C6630
C6629
C6631
C6632
U6014
C6633
C6634
C6635
C6636
C6638
C6637
C6640
C6639
C6642
C6641
C6643
C6644
10/11
B_PETN7
B_PETP7
B_PETN6
B_PETP6
B_PETN5
B_PETP5
B_PETN4
B_PETP4
B_PETN3
B_PETP3
B_PETN2
B_PETP2
B_PETN1
B_PETP1
B_PETN0
B_PETP0
11/11
B_PETN15
B_PETP15
B_PETN14
B_PETP14
B_PETN13
B_PETP13
B_PETN12
B_PETP12
B_PETN11
B_PETP11
B_PETN10
B_PETP10
B_PETN9
B_PETP9
B_PETN8
B_PETP8
TX : B_PET[7:0]
TX : B_PET[15:8]
2 1
2 1
2 1
2 1
2 1
2 1
2 1
2 1
2 1
2 1
2 1
2 1
2 1
2 1
2 1
2 1
2 1
2 1
2 1
2 1
2 1
2 1
2 1
2 1
2 1
2 1
2 1
2 1
2 1
2 1
2 1
2 1
1
SHEETDATE
23
7 3 2 16 5 4
E
A
B
C
E
D
C
B
A
7 6 5 4
D
DEPARTMENT
SIZE
PROJECT DOCUMENT NUMBER REV
REVIEWER
DESIGNER
OUT
OUT
IN
IN OUT
OUT
IN
OUT
OUT
OUT
OUT IN
C



CPU1 P0 RT ADDR: 0X48 (8-BIT) / 0X24 (7-BIT)
Thu Aug 24 14:09:36 2023<NAME_2>
<NAME_1>
MB FABCGTI V02
320 OF 365
P 1V 8_CP U1_RT_1D
P 1V 8_CP U1_RT_1D
P 1V 8_CP U1_RT_1DP 1V 8_CP U1_RT_1D
P 1V 8_CP U1_RT_1D
P 1V 8_CP U1_RT_1D
P 1V 8_CP U1_RT_1D
22 1%
1/20W
GPIO2_RT_CPU1_P0
RST_RT_CPU1_P0_RESET_R_N
0201LF
EMPTY
1/20W
5%
4.7K
10K
1/20W
0201LF
RT_CPU1_P0_ADDR3
RETIMER_CPU1_P0(5)
CLK_100M_RETIMER_CPU1_P0_R_DN
SMB_RT_CPU1_P0_R_SCL
TEST1_RT_CPU1_P0
GPIO3_RT_CPU1_P0
GPIO2_RT_CPU1_P0
SMB_RT_CPU1_P0_R_SDA
JTAG_TEST_MODE_RT_CPU1_P0
TEST0_RT_CPU1_P0
TEST2_RT_CPU1_P0 RST_RT_CPU1_P0_PERST_R_N
TEST2_RT_CPU1_P0
TEST0_RT_CPU1_P0
SMB_RT_CPU1_P0_R2_SCL
SMB_RT_CPU1_P0_R2_SDA
RT_CPU1_P0_ADDR1
RT_CPU1_P0_ADDR2
TEST1_RT_CPU1_P0
CLK_100M_RETIMER_CPU1_P0_DN
MODE_RT_CPU1_P0
RT_CPU1_P0_ADDR3
RT_CPU1_P0_ADDR2
RT_CPU1_P0_ADDR1
1K
1/20W
1%
0201LF
EMPTY
0201LF
1/20W
CHIP
1%
1K
0201LF
1/20W
1%
20K
CHIP
1%
EMPTY
1/20W
1K
0201LF
1/20W
EMPTY
1%
1K
0201LF
1K
1/20W
1%
CHIP
0201LF
1%
0201LF
CHIP
1/20W
10K
CHIP
1%
0201LF
1/20W
EMPTY
4.7K
5%
CHIP
4.7K
1/20W
0201LF
5%
5%
4.7K
EMPTY
1/20W
0201LF
0
0
0201LF
EMPTY
4.7K
5%
1/20W
0201LF
1/20W
CHIP
5%
4.7K
0201LF
CHIP
1/20W
1%
10K
0201LF
CHIP
1/20W
1%
10K
CHIP
0201LF
1/20W
5%
4.7K 4.7K
1/20W
CHIP
0201LF
5%
CHIP
1/20W
4.7K
0201LF
5%
0201LF
EMPTY
1/20W
4.7K
5%
4.7K
1/20W
EMPTY
0201LF
5%
EMPTY
0201LF
4.7K
5%
1/20W 1/20W
0201LF
EMPTY
4.7K
5%
51.1
1/20W
EMPTY
1%
0201LF
51.1
1/20W
0201LF
EMPTY
1%
1/20W 0201LF
5%0
CHIP
CHIP 0201LF
0201LF
IC
PT5161LRS
SMLF
CHIP
1/20W
5%0
CLK_100M_RETIMER_CPU1_P0_R_DP CLK_100M_RETIMER_CPU1_P0_DP
RXDET_BYP_RT_CPU1_P0
GPIO3_RT_CPU1_P0
RT_CPU1_P0_SCAN_MODE
1K
EMPTY
1/20W
1%
0201LF
CHIP
0201LF
1/20W
10K
1%
CHIP
0201LF
4.7K
5%
1/20W
CHIP
0201LF
MODE_RT_CPU1_P0
RST_RT_CPU1_P0_PERST_R_N
JTAG_TRST_RT_CPU1_P0_N 1K
0201LF
0201LF
0201LF
RST_RT_CPU1_P0_RESET_R_N
4.7K
JTAG_TEST_MODE_RT_CPU1_P0
CHIP
JTAG_TCK_RT_CPU1_P0
JTAG_TDO_RT_CPU1_P0
JTAG_TMS_RT_CPU1_P0
JTAG_TDI_RT_CPU1_P0
0201LF
EMPTY
1/20W
4.7K
5%
0201LF
EMPTY
1/20W
4.7K
5%
0201LF
EMPTY
1/20W
1%
1K
0201LF
EMPTY
1/20W
4.7K
5%
RXDET_BYP_RT_CPU1_P0
RT_CPU1_P0_SCAN_MODE
CLKREQ_RT_CPU1_P0_N
RST_RT_CPU1_P0_PERST_N
JTAG_TCK_RT_CPU1_P0
JTAG_TDO_RT_CPU1_P0
JTAG_TMS_RT_CPU1_P0
JTAG_TDI_RT_CPU1_P0
RST_RT_CPU1_P0_RESET_N
CHIP
1%
1/20W
0201LF
200
321
32181
321
183
184
321
321
321
184
321
321
321 32181
321
321
321
321
321
321
321
183
321
321
321
321
32181
32181
321
321
321
321
321
321
321
321
321
321
321
186 185
186 185 SMB_RT_CPU1_P0_ROM_MUX_1D_R_SDASMB_RT_CPU1_P0_ROM_MUX_1D_SDA
0201LF
49.9 1/20W1%
CHIP
321
SMB_RT_CPU1_P0_ROM_MUX_1D_R_SCLSMB_RT_CPU1_P0_ROM_MUX_1D_SCL
0201LFCHIP
321
R6720R6721
FF30
FF27
FF24
E30
B28
B31
B25
B23
F34
FF33
E11
FF11
FJ16
FF18
B16
E18
F2
FJ9
E8
B12
FF8
B9
B6
B3
FJ31
FJ28
FJ25
FJ23
FJ6
FJ3
FF5
G35
U6014
CLOCK
3/11
EE_DAT
EE_CLK
CLKREQ_N
TEST2
TEST1
TEST0
T_SENSE
SMBDAT
SMBCLK
SMB_ADDR3
SMB_ADDR2
SMB_ADDR1
SCAN_MODE
RXDET_BYP
RESET_N
REFCLKP
REFCLKN
REFCLK_OUTP
REFCLK_OUTN
PERST_N
MODE
JTAG_TRST_N
JTAG_TMS
JTAG_TEST_MODE
JTAG_TDO
JTAG_TDI
JTAG_TCK
INT_N
GPIO3
GPIO2
GPIO1
GPIO0
MISC JTAG
TESTEEPROM
SMBUS
GPIO
21
2
1
2
1
R1467
2
1
2
1
2
1
R1381
2
1
2
1
R1388
2
1
R1389
21R1380
21
2
1
2
1
2
1
R6715
2
1
2
1
R6713
2
1
R6712
2
1
R6724
2
1
2
1
2
1
R6725
2
1
R726
2
1
R6722
21
21
2
1
R728
2
1
R727
2
1
R707
2
1
R715
2
1
R719
2
1
R723
2
1
R725
2
1
R706
2
1
R716
2
1
R720
2
1
R724
2
1
2
1
21
21
21
21
21
1
SHEETDATE
23
7 3 2 16 5 4
E
A
B
C
E
D
C
B
A
7 6 5 4
D
DEPARTMENT
SIZE
PROJECT DOCUMENT NUMBER REV
REVIEWER
DESIGNER
IN
IN
IN
OUT
OUT
IN
OUT
OUT
OUT
IN
IN
IN
IN
IN
OUT
IN
OUT
OUT
OUT
IN
IN
IN
OUT
OUT
IN
BI
IN
IN
IN
IN IN
IN
IN
IN
OUT
OUT
OUT
OUT
OUT
IN
BI
IN
R674
R1464 R1466R1465
R6723
R1387
R6716
R6717
R6714
R6709
R6708
R628R627
R6813
R6812
R675
R599
R609
C



Thu Aug 24 14:09:36 2023<NAME_2>
<NAME_1>
MB FABCGTI V02
321 OF 365
P 0V 9_CP U1_RT_2D
P0V9_CPU1_RT0_2A
P0V9_CPU1_RT0_2A_2D
P 1V 8_CP U1_RT0_1A
P 1V 8_CP U1_RT0_1A _1D
P 1V 8_CP U1_RT_1D
200
1%
CHIP
0201LF
1/20W
RT_CPU1_P0_VQPS
RETIMER_CPU1_P0 POWER(6)
IC
PT5161LRS
SMLF
1/20W
CHIP
5%
0
0201LF
1/20W
CHIP
5%
0
0201LF
IC
PT5161LRS
SMLF
N C F_C PU 1_P0_GN D
N C F_A1_C PU 1_P0_GN D
1K
1/20W
EMPTY
1%
0201LF
FH34
FH2
FG35
FG1
FE34
FE2
D35
D1
C34
C2
A35
A1
V35
V1
U34
U2
T4
T32
T22
T13
L35
L1
K34
K2
J4
J22
H31
H19
H16
H12
FJ19
FJ12
FF21
FF14
FD35
FD1
FC9
FC6
FC3
FC28
FC25
FC23
FC19
FB34
FB2
FA32
FA15
ET35
ET1
ER34
ER2
EP4
EP32
EP22
EP13
EJ35
EJ1
EH34
EH2
EG4
EG32
EG22
EG13
EB35
EB1
EA34
EA2
E33
E27
E14
DY4
DY32
DY22
DY13
DR35
DR1
DP34
DP2
DN4
DN32
DN22
DN13
DH35
DH1
DG34
DG2
DF4
DF32
DF22
DF13
DA35
DA1
CY34
CY2
CW4
CW32
CW22
CW13
CP35
CP1
CN34
CN2
CM4
CM32
CM22
CM13
CG35
CG1
CF34
CF2
CE4
CE32
CE22
CE13
BY35
BY1
BW34
BW2
BV4
BV32
BV22
BV13
BN35
BN1
BM34
BM2
BL4
BL32
BL22
BL13
BF35
BF1
BE34
BE2
BD4
BD32
BD22
BD13
B19
AW35
AW1
AV34
AV2
AU4
AU32
AU22
AU13
AM35
AM1
AL34
AL2
AK4
AK32
AK22
AK13
AE35
AE1
AD34
AD2
AC4
AC32
AC22
AC13
G1
CW20
CW17
BL20
BL17
T20
T17
EP20
EP17
EG20
EG17
DY20
DY17
DN20
DN17
DF20
DF17
BD20
BD17
AU20
AU17
AK20
AK17
AC20
AC17
BV17
CM20
CM17
CE20
CE17
BV20
U6014
U6014
5/11
GND151
GND150
GND149
GND148
GND147
GND146
GND145
GND144
GND143
GND142
GND141
GND140
GND139
GND138
GND137
GND136
GND135
GND134
GND133
GND132
GND131
GND130
GND129
GND128
GND127
GND126
GND125
GND124
GND123
GND122
GND121
GND120
GND119
GND118
GND117
GND116
GND115
GND114
GND113
GND112
GND111
GND110
GND109
GND108
GND107
GND106
GND105
GND104
GND103
GND102
GND101
GND100
GND99
GND98
GND97
GND96
GND95
GND94
GND93
GND92
GND91
GND90
GND89
GND88
GND87
GND86
GND85
GND84
GND83
NCF_GND12
NCF_GND11
NCF_GND10
NCF_GND9
NCF_GND8
NCF_GND7
NCF_GND6
NCF_GND5
NCF_GND4
NCF_GND3
NCF_GND2
NCF_GND1
GND82
GND81
GND80
GND79
GND78
GND77
GND76
GND75
GND74
GND73
GND72
GND71
GND70
GND69
GND68
GND67
GND66
GND65
GND64
GND63
GND62
GND61
GND60
GND59
GND58
GND57
GND56
GND55
GND54
GND53
GND52
GND51
GND50
GND49
GND48
GND47
GND46
GND45
GND44
GND43
GND42
GND41
GND40
GND39
GND38
GND37
GND36
GND35
GND34
GND33
GND32
GND31
GND30
GND29
GND28
GND27
GND26
GND25
GND24
GND23
GND22
GND21
GND20
GND19
GND18
GND17
GND16
GND15
GND14
GND13
GND12
GND11
GND10
GND9
GND8
GND7
GND6
GND5
GND4
GND3
GND2
GND1
4/11
PWR_2A_20
PWR_2A_19
PWR_2A_18
PWR_2A_17
PWR_2A_16
PWR_2A_15
PWR_2A_14
PWR_2A_13
PWR_2A_12
PWR_2A_11
PWR_2A_10
PWR_2A_9
PWR_2A_8
PWR_2A_7
PWR_2A_6
PWR_2A_5
PWR_2A_4
PWR_2A_3
PWR_2A_2
PWR_2A_1
PWR_1D
PWR_2D_4
PWR_2D_3
PWR_2D_2
PWR_2D_1
PWR_1A_5
PWR_1A_4
PWR_1A_3
PWR_1A_2
PWR_1A_1
VQPS
0.9V 0.9V
1.8V
/1.8V
1.2V / 1.5V
2
1
R699
2
1
2
1
2
1
1
SHEETDATE
23
7 3 2 16 5 4
E
A
B
C
E
D
C
B
A
7 6 5 4
D
DEPARTMENT
SIZE
PROJECT DOCUMENT NUMBER REV
REVIEWER
DESIGNER
R701
R709
R711
C



RETIMER EEPRO ADDRESS: 0XA0 (8 BIT) / 0X50 (7 BIT)
Thu Aug 24 14:09:46 2023<NAME_2>
<NAME_1>
MB FABCGTI V02
322 OF 365
P 1V 8_CP U1_RT_1D
185186
185186
SMB_RT_CPU1_P0_ROM_SDASMB_RT_CPU1_P0_ROM_R_SDA
1%33.2
SMB_RT_CPU1_P0_ROM_SCLSMB_RT_CPU1_P0_ROM_R_SCL
0201LF1/20W CHIP
M24M02-DRMN6TP
U12_E2
0.1UF
IC
10V
SMLF
CHIP
0201LF
C0201
10%
RETIMER_CPU1_P0(7)
1K
1%
X 7S
1/20W
7
4
8
5
6 3
2
1
U12
DU1
DU2
E2
VSSSDA
SCL
WC_N
VCC
2
1
2
1 C7501
21
21
1
SHEETDATE
23
7 3 2 16 5 4
E
A
B
C
E
D
C
B
A
7 6 5 4
D
DEPARTMENT
SIZE
PROJECT DOCUMENT NUMBER REV
REVIEWER
DESIGNER
BI
IN R6788R673
R672
C



Thu Aug 24 14:09:47 2023<NAME_2>
<NAME_1>
MB FABCGTI V02
323 OF 365
P0V9_CPU1_RT0_2A_2D
P0V9_CPU1_RT_2D
P 1V 8_CP U1_RT0_1A _1D
P 1V 8_CP U1_RT_1D
P 1V 8_CP U1_RT0_1A
P0V9_CPU1_RT0_2A
20%
100UF
X 6S
4V
C0805
X 6S
20%
100UF
4V
C0805 C0805
X 6S
20%
4V
100UF
C0805
X 6S
20%
4V
100UF100UF
4V
20%
C0805
X 6S
20%
100UF
4V
C0805
X 6S
4V
X 6S
C0805
100UF
20%
470UF
20%
S MLF
2.5V
S P CA P
2.5V
S MLF
S P CA P
20%
470UF
4V
100UF
C0805
X6S
20%
10%
10V
4.7UF
20%
0.1UF
X 6S
4.7UF4.7UF10UF
6.3V
C0402
1UF
X 6S
0201
0.1UF
10%
10V
0.1UF
10V
0.1UF
10%10%
10V
4V
20%
X 6S
0201
20%
X 6S
0201
10%
X7S
C0201
10V10V
10%
0201
0201
0.1UF
X7S
C0201
X7SX7S
C0201C0201
X7S
0.1UF
10%
4V
1UF
X 6S
20%
0201
20%
X 6S
0201
X 6S
10V 10V 10V 10V
0.1UF
X 6S
20% 20%
4V
20%
4.7UF
1UF
C0201
0201
X 6SX 6S
0201
X 6S
20%
6.3V
20%20%
6.3V
X 6S
20%
C0402
6.3V
C0402C0402
X 6S
20%
C0402
4V
10UF
22UF22UF
4V
X7S
C0201
1UF
X7S
C0201
0201
10%
0402
X 6S
20%
6.3V
4.7UF
20%
4V
1UF10UF
0.1UF
10%
X7S
10V20%
4V
C0402 C02010402
X 6S
20%
6.3V
10UF
0.1UF
0201
10V
0.1UF
10% 10%
X7S
4V
4.7UF
RETIMER_CPU1_P0 DECAPS (8)
X 6S
22UF
C0402
1UF1UF
X 6S
4V
SMLF
100NH/16A
IND
20%
X 6S
6.3V
C0402
4V
X 6S
CHIP
0 5%
1/4W
5%
1/4W
0
R6704 AND R6705 COLAY
X 6S
1UF
20%
4V
EMPTY
0
5%0402LF
0
5%
EMPTY
0.1UF
10V
C0201
10V
X7S
C0201
10%
C0201
10%
X7SX7S
C0201
X7S
10%
10V
X7S
C0201
10%
C0201
0603LF
C0402
4V
IND
1/16W
1/16W
SMLF
1/16W
BLM21SN300SN1D/5A
5%
EMPTY
0402LF
L27/R6701 COLAY WITH R6702/R6703
20%
X 6SX 6S
20%
SMLF
BLM15PD121SN1D/1300MA
0
IND
X 6S
0402
C0402
X 6S
22UF
6.3V
X 6SX 6S
20%
10UF
20%
4.7UF
6.3V
22UF 1UF
20%
0201
10%
10V
0.1UF0.1UF
10V4V
20% 10%
X7S
C0201
X7S
X 6S
20%
0201
X 6S
0.1UF
X7SC0402
X 6S
6.3V
C0201
10V
0.1UF
X 6S
1UF
0402
10%
4V
20%
22UF
20%
6.3V6.3V
X 6S
10UF
20%
X 6S
C0402
20%
10UF
X 6S
4V
X 6S
20%20%
04020402
4V
1UF
0201
20%
4V4V
1UF
20%
6.3V
X 6S
0402
20%
10V
0.1UF
X 6S
6.3V
C0402
02010201
0.1UF
10%
C0201
0.1UF
X 6S
C0201
10V
1UF
4V
1UF
1UF 0.1UF 0.1UF
X7S
10%
4V
1UF
0402LF
EMPTY
0603LF
C0201
20%
C0201
X7S
10%20%
4V
4V
1UF
0.1UF
10V
X7S
22UF
4V
20%
X 6S
C0402
4V
0201
C0201
X7S
C115
C7022
C125
C122C118C113
C121C117C114
2121
2 1
L4L3
CAD NOTE:
CAD NOTE:
1 21 2
L27
12
2
1
2
1 C7021
2
1 C7020
2
1
2
1
2
1
2
1
2
1
R6701
2
1
21
2
1
2
1
2
1
2
1
2
1
2
1
2
1
2
1
2
1
2
1
2
1
2
1
2
1
2
1
2
1
2
1
2
1
2
1
2
1
2
1
2
1
2
1
2
1
2
1
2
1
2
1
2
1
2
1
2
1
2
1
2
1
2
1
2
1
2
1
2
1
2
1
2
1
2
1
2
1
2
1
2
1
2
1
2
1
2
1
2
1
2
1
21R6703
21R6702
2
1
2
1
2
1
2
1
2
1
2
1
2
1 C119
2
1
2
1 C123
2
1
2
1
2
1
2
1 C126
2
1
2
1
2
1
1
SHEETDATE
23
7 3 2 16 5 4
E
A
B
C
E
D
C
B
A
7 6 5 4
D
DEPARTMENT
SIZE
PROJECT DOCUMENT NUMBER REV
REVIEWER
DESIGNER
C283C281
C201C187
R6704
R6705
C191 C198
C228 C253 C184 C260 C192C141 C264 C282
C137 C139 C266 C189
C247
C241C269C250
C286C254C259C262C255
C285C190C280C186C227
C265C188
C284C240C225
C258C221
C257C138C243C135
C220
C222
C185C256C261C244C229
C130
C134C133C131C129
C



Thu Aug 24 10:16:45 2023<NAME_2>
<NAME_1>
MB FABCGTI V02
324 OF 365RETIMER_CPU1_P0 (9)
1
SHEETDATE
23
7 3 2 16 5 4
E
A
B
C
E
D
C
B
A
7 6 5 4
D
DEPARTMENT
SIZE
PROJECT DOCUMENT NUMBER REV
REVIEWER
DESIGNER
C



Thu Aug 24 10:16:45 2023<NAME_2>
<NAME_1>
MB FABCGTI V02
325 OF 365RETIMER_CPU1_P0(10)
1
SHEETDATE
23
7 3 2 16 5 4
E
A
B
C
E
D
C
B
A
7 6 5 4
D
DEPARTMENT
SIZE
PROJECT DOCUMENT NUMBER REV
REVIEWER
DESIGNER
C



Thu Aug 24 10:16:46 2023<NAME_2>
<NAME_1>
MB FABCGTI V02
326 OF 365BLANK
1
SHEETDATE
23
7 3 2 16 5 4
E
A
B
C
E
D
C
B
A
7 6 5 4
D
DEPARTMENT
SIZE
PROJECT DOCUMENT NUMBER REV
REVIEWER
DESIGNER
C



P/N SWAP
P/N SWAP
P/N SWAP
P/N SWAP
P/N SWAP
P/N SWAP
P/N SWAP
P/N SWAP
P/N SWAP
P/N SWAP
P/N SWAP
P/N SWAP
P/N SWAP
P/N SWAP
P5E_CPU1_P1_TX_C_DP/DN<0-15> LANE REVERSAL
CPU TO RETIMERCPU TO RETIMER
Thu Aug 24 14:09:36 2023<NAME_2>
<NAME_1>
MB FABCGTI V02
327 OF 365
66
66
66
66
P5E_CPU1_P1_TX_C_DP<15:8>
P5E_CPU1_P1_TX_C_DN<15:8>
P5E_CPU1_P1_TX_C_DP<7:0>
P5E_CPU1_P1_TX_C_DN<7:0>
RETIMER_CPU1_P1(1)
IC
PT5161LRS
SMLFPT5161LRS
SMLF
IC
EV34
EL34
ED34
DU34
DK34
DC34
CT34
CJ34
EY35
EN35
EF35
DW35
DM35
DE35
CV35
CL35
CB34
BR34
BH34
BA34
AP34
AG34
Y34
N34
CD35
BU35
BK35
BC35
AT35
AJ35
AB35
R35
14
14
13
13
12
12
2
3
3
4
5
6
7
11
10
9
2
0
6
5
4
0
7
11
8
9
8
10
15
15
1
1
U6015
U6015
9/11
B_PERN15
B_PERP15
B_PERN14
B_PERP14
B_PERN13
B_PERP13
B_PERN12
B_PERP12
B_PERN11
B_PERP11
B_PERN10
B_PERP10
B_PERN9
B_PERP9
B_PERN8
B_PERP8
8/11
B_PERN7
B_PERP7
B_PERN6
B_PERP6
B_PERN5
B_PERP5
B_PERN4
B_PERP4
B_PERN3
B_PERP3
B_PERN2
B_PERP2
B_PERN1
B_PERP1
B_PERN0
B_PERP0
RX : B_PER[15:8]
RX : B_PER[7:0]
1
SHEETDATE
23
7 3 2 16 5 4
E
A
B
C
E
D
C
B
A
7 6 5 4
D
DEPARTMENT
SIZE
PROJECT DOCUMENT NUMBER REV
REVIEWER
DESIGNER
IN
IN
IN
IN
C



P5E_CPU1_P1_RX_DP/DN<0-15> LANE REVERSAL
RETIMER TO CPU RETIMER TO CPU
Thu Aug 24 14:09:36 2023<NAME_2>
<NAME_1>
MB FABCGTI V02
328 OF 365
51
51
51
51
SMLF
IC
PT5161LRS
SMLF
IC
PT5161LRS
RETIMER_CPU1_P1(2)
P5E_CPU1_P1_RX_DP<15:8>
P5E_CPU1_P1_RX_DN<15:8>
P5E_CPU1_P1_RX_DP<7:0>
P5E_CPU1_P1_RX_DN<7:0>
EU26
EK26
EC26
DT26
DJ26
DB26
CR26
CH26
EW29
EM29
EE29
DV29
DL29
DD29
CU29
CK29
CA26
BP26
BG26
AY26
AN26
AF26
W26
M26
CC29
BT29
BJ29
BB29
AR29
AH29
AA29
P29
12
12
13
13
15
5
11
9
8
8
9
11
15
0
3
2
1
0
1
2
3
4
6
7
5
6
7
10
4
10
14
14
U6015
U6015
7/11
A_PETN15
A_PETP15
A_PETN14
A_PETP14
A_PETN13
A_PETP13
A_PETN12
A_PETP12
A_PETN11
A_PETP11
A_PETN10
A_PETP10
A_PETN9
A_PETP9
A_PETN8
A_PETP8
6/11
A_PETN7
A_PETP7
A_PETN6
A_PETP6
A_PETN5
A_PETP5
A_PETN4
A_PETP4
A_PETN3
A_PETP3
A_PETN2
A_PETP2
A_PETN1
A_PETP1
A_PETN0
A_PETP0
TX : A_PET[15:8]
TX : A_PET[7:0]
1
SHEETDATE
23
7 3 2 16 5 4
E
A
B
C
E
D
C
B
A
7 6 5 4
D
DEPARTMENT
SIZE
PROJECT DOCUMENT NUMBER REV
REVIEWER
DESIGNER
OUT
OUT
OUT
OUT
C



P5E_CPU1_P1_RX_BUF_DP/DN<0-15> LANE REVERSAL
EXAMAX TO RETIMER EXAMAX TO RETIMER
Thu Aug 24 14:09:35 2023<NAME_2>
<NAME_1>
MB FABCGTI V02
329 OF 365
122
122
121
121
P5E_CPU1_P1_RX_BUF_DN<7:0>
P5E_CPU1_P1_RX_BUF_DP<7:0>
P5E_CPU1_P1_RX_BUF_DN<15:8>
P5E_CPU1_P1_RX_BUF_DP<15:8>
PT5161LRS
IC
SMLF SMLF
IC
PT5161LRS
RETIMER_CPU1_P1(3)
EY1
EN1
EF1
DW1
DM1
DE1
CV1
CL1
EV2
EL2
ED2
DU2
DK2
DC2
CT2
CJ2
CD1
BU1
BK1
BC1
AT1
AJ1
AB1
R1
CB2
BR2
BH2
BA2
AP2
AG2
Y2
N2 7
6
5
2
1
0
0
1
2
3
4
6
15
15
14
8
14
13
12
11
10
9
8
13
12
11
10
9
7
5
4
3
U6015U6015
2/11
A_PERN15
A_PERP15
A_PERN14
A_PERP14
A_PERN13
A_PERP13
A_PERN12
A_PERP12
A_PERN11
A_PERP11
A_PERN10
A_PERP10
A_PERN9
A_PERP9
A_PERN8
A_PERP8
1/11
A_PERN7
A_PERP7
A_PERN6
A_PERP6
A_PERN5
A_PERP5
A_PERN4
A_PERP4
A_PERN3
A_PERP3
A_PERN2
A_PERP2
A_PERN1
A_PERP1
A_PERN0
A_PERP0
RX : A_PER[15:8]
RX : A_PER[7:0]
1
SHEETDATE
23
7 3 2 16 5 4
E
A
B
C
E
D
C
B
A
7 6 5 4
D
DEPARTMENT
SIZE
PROJECT DOCUMENT NUMBER REV
REVIEWER
DESIGNER
IN
IN
IN
IN
C



RETIMER TO EXAMAX
P5E_CPU1_P1_TX_BUF_DP/DN<0-15> LANE REVERSAL
RETIMER TO EXAMAX
Thu Aug 24 14:09:35 2023<NAME_2>
<NAME_1>
MB FABCGTI V02
330 OF 365
331
331
331
331
121
121
331
331
122
122331
331
SMLF
P5E_CPU1_P1_TX_BUF_DP<15:8>
PT5161LRS
IC IC
RETIMER_CPU1_P1(4)
P5E_CPU1_P1_TX_BUF_DN<15:8>
P5E_CPU1_P1_TX_BUF_DP<7:0>
PT5161LRS
SMLF
P5E_CPU1_P1_TX_BUF_DN<7:0>
D IFF BU S_0.22U F
6.3V
X 6S
20%C0201
D IFF BU S_0.22U F
D IFF BU S_0.22U F
D IFF BU S_0.22U F
D IFF BU S_0.22U F
D IFF BU S_0.22U F
D IFF BU S_0.22U F
D IFF BU S_0.22U F
D IFF BU S_0.22U F
D IFF BU S_0.22U F
D IFF BU S_0.22U F
D IFF BU S_0.22U F
D IFF BU S_0.22U F
D IFF BU S_0.22U F
D IFF BU S_0.22U F
D IFF BU S_0.22U F
P5E_CPU1_P1_TX_BUF_C_DN<15:8>
P5E_CPU1_P1_TX_BUF_C_DP<15:8>
P5E_CPU1_P1_TX_BUF_DN<15:8>
P5E_CPU1_P1_TX_BUF_DP<15:8>
D IFF BU S_0.22U F
6.3V
X 6S
20%C0201
D IFF BU S_0.22U F
D IFF BU S_0.22U F
D IFF BU S_0.22U F
D IFF BU S_0.22U F
D IFF BU S_0.22U F
D IFF BU S_0.22U F
D IFF BU S_0.22U F
D IFF BU S_0.22U F
D IFF BU S_0.22U F
D IFF BU S_0.22U F
D IFF BU S_0.22U F
D IFF BU S_0.22U F
D IFF BU S_0.22U F
D IFF BU S_0.22U F
P5E_CPU1_P1_TX_BUF_C_DN<7:0>
P5E_CPU1_P1_TX_BUF_C_DP<7:0>P5E_CPU1_P1_TX_BUF_DP<7:0>
P5E_CPU1_P1_TX_BUF_DN<7:0>
D IFF BU S_0.22U F
2 1
2 1
2 1
2 1
2 1
2 1
2 1
2 1
2 1
2 1
2 1
2 1
2 1
2 1
2 1
2 1
2 1
2 1
2 1
2 1
2 1
2 1
2 1
2 1
2 1
2 1
2 1
2 1
2 1
2 1
2 1
2 1
EU7
EK7
EC7
DT7
DJ7
DB7
CR7
CH7
EW10
EM10
EE10
DV10
DL10
DD10
CU10
CK10
CA7
BP7
BG7
AY7
AN7
AF7
W7
M7
CC10
BT10
BJ10
BB10
AR10
AH10
AA10
P10
15
14
13
12
11
10
9
8
8
9
10
11
12
14
15
7
6
5
4
3
2
1
0
0
1
2
3
4
5
6
7
13
8
8
9
10
11
12
13
9
10
11
12
13
14
15
14
15
8
8
9
10
11
12
13
14
15
9
10
12
11
13
14
15
0
1
0
1
2
3
4
5
6
7
3
2
6
5
4
7
0
1
0
2
1
3
5
4
6
2
3
4
5
6
7
7
U6015
C6677
C6678
C6680
C6679
C6682
C6681
C6683
C6684
C6685
C6686
C6687
C6688
C6689
C6690
C6691
C6692
C6661
U6015
C6662
C6664
C6663
C6665
C6666
C6668
C6667
C6669
C6670
C6671
C6672
C6673
C6674
C6675
C6676
10/11
B_PETN7
B_PETP7
B_PETN6
B_PETP6
B_PETN5
B_PETP5
B_PETN4
B_PETP4
B_PETN3
B_PETP3
B_PETN2
B_PETP2
B_PETN1
B_PETP1
B_PETN0
B_PETP0
11/11
B_PETN15
B_PETP15
B_PETN14
B_PETP14
B_PETN13
B_PETP13
B_PETN12
B_PETP12
B_PETN11
B_PETP11
B_PETN10
B_PETP10
B_PETN9
B_PETP9
B_PETN8
B_PETP8
TX : B_PET[7:0]
TX : B_PET[15:8]
2 1
2 1
2 1
2 1
2 1
2 1
2 1
2 1
2 1
2 1
2 1
2 1
2 1
2 1
2 1
2 1
2 1
2 1
2 1
2 1
2 1
2 1
2 1
2 1
2 1
2 1
2 1
2 1
2 1
2 1
2 1
2 1
1
SHEETDATE
23
7 3 2 16 5 4
E
A
B
C
E
D
C
B
A
7 6 5 4
D
DEPARTMENT
SIZE
PROJECT DOCUMENT NUMBER REV
REVIEWER
DESIGNER
OUT
OUT
OUTIN
IN OUT
IN
OUT
OUT
OUT
OUT IN
C



CPU1 P1 RT ADDR: 0X48 (8-BIT) / 0X24 (7-BIT)
Thu Aug 24 14:09:51 2023<NAME_2>
<NAME_1>
MB FABCGTI V02
331 OF 365
P 1V 8_CP U1_RT_1D
P 1V 8_CP U1_RT_1D
P 1V 8_CP U1_RT_1D
P 1V 8_CP U1_RT_1D
P 1V 8_CP U1_RT_1DP 1V 8_CP U1_RT_1D
P 1V 8_CP U1_RT_1D
SMB_RT_CPU1_P1_ROM_MUX_1D_R_SCLSMB_RT_CPU1_P1_ROM_MUX_1D_SCL
1%49.9
CHIP 0201LF1/20W
SMB_RT_CPU1_P1_ROM_MUX_1D_R_SDASMB_RT_CPU1_P1_ROM_MUX_1D_SDA
185186
185186
332
332
332
332
332
184
332
332
332
81 332
332
332
332
332
332
332
332
332
332
332
332
332332
332
332
332
332
332
184
332
81
332
81 332
332
332
332
332
332
183
183
81 332
1/20W
CHIP
200
1%
0201LF
JTAG_TDI_RT_CPU1_P1
JTAG_TMS_RT_CPU1_P1
JTAG_TDO_RT_CPU1_P1
JTAG_TCK_RT_CPU1_P1
0201LF
1/20W 1/20W
1%
4.7K
TEST0_RT_CPU1_P1
SMB_RT_CPU1_P1_R_SDA
5%
4.7K
EMPTY
5%
4.7K
EMPTY
0201LF
5%
1/20W
EMPTY
0201LF
1K
1/20W
EMPTY
0201LF
0
JTAG_TEST_MODE_RT_CPU1_P1
JTAG_TRST_RT_CPU1_P1_N
JTAG_TDI_RT_CPU1_P1
1/20W
5%
4.7K
0201LF
CHIP
RST_RT_CPU1_P1_RESET_N 0201LF
0201LF
CHIP
JTAG_TMS_RT_CPU1_P1
CHIP
RST_RT_CPU1_P1_PERST_R_N
0201LF
JTAG_TDO_RT_CPU1_P1
MODE_RT_CPU1_P1
RXDET_BYP_RT_CPU1_P1
1K
JTAG_TCK_RT_CPU1_P1
1KRT_CPU1_P1_SCAN_MODE
5%
EMPTY
1/20W
1%
0201LF
CHIP
1%
10K
1/20W
0201LF
RXDET_BYP_RT_CPU1_P1
RT_CPU1_P1_SCAN_MODE
GPIO3_RT_CPU1_P1
RT_CPU1_P1_ADDR2
1/20W
EMPTY
0201LF
RT_CPU1_P1_ADDR1
RT_CPU1_P1_ADDR2
RT_CPU1_P1_ADDR3
0201LF
EMPTY
1/20W
1K
1%
1%
1K
CHIP
0201LF
1/20W
CHIP
0201LF
20K
1% 1%
1K
0201LF
1/20W
1K
1%
1/20W
1K
1%
0201LF
1/20W
4.7K
5%
EMPTY
1%
10K
1/20W
CHIP
0201LF
10K
0201LF
1/20W
CHIP
1%
4.7K
5%
1/20W
CHIP
0201LF
EMPTY
5%
4.7K
0201LF
EMPTY
0201LF
5%
4.7K
1/20W
4.7K
5%
EMPTY
0201LF
1/20W1/20W
5%
4.7K
0201LF
EMPTY
1/20W
CHIP
0201LF
4.7K
5%
0201LF
5%
4.7K
1/20W
CHIP
5%
1/20W
4.7K
0201LF
CHIP
1/20W
5%
CHIP
0
5%
0201LF
EMPTY
1/20W
4.7K
5%
4.7K
1/20W
0201LF
EMPTY
4.7K
5%
1/20W
0201LF
CHIP
10K
1%
1/20W
CHIP
0201LF
10K
1%
1/20W
CHIP
0201LF
0201LF
EMPTY
1/20W
4.7K
MODE_RT_CPU1_P1
JTAG_TEST_MODE_RT_CPU1_P1
GPIO3_RT_CPU1_P1
TEST0_RT_CPU1_P1
TEST1_RT_CPU1_P1
TEST2_RT_CPU1_P1
SMB_RT_CPU1_P1_R_SCL
GPIO2_RT_CPU1_P1
51.1
1% 1%
51.1
1/20W
0201LF
IC
RETIMER_CPU1_P1(5)
1/20W
EMPTY EMPTY
0201LF
PT5161LRS
CHIP
5%0
1/20W
SMLF
RST_RT_CPU1_P1_RESET_R_N
RST_RT_CPU1_P1_PERST_R_N
1/20W
EMPTY
SMB_RT_CPU1_P1_R2_SDA
SMB_RT_CPU1_P1_R2_SCL
CHIP
0201LF
GPIO2_RT_CPU1_P1
1/20W
0201LF
TEST1_RT_CPU1_P1
TEST2_RT_CPU1_P1
RT_CPU1_P1_ADDR1
RT_CPU1_P1_ADDR3
CLK_100M_RETIMER_CPU1_P1_R_DP
CLK_100M_RETIMER_CPU1_P1_R_DN
CHIP 0201LF
0201LF
CLK_100M_RETIMER_CPU1_P1_DN
CLK_100M_RETIMER_CPU1_P1_DP
RST_RT_CPU1_P1_PERST_N
CLKREQ_RT_CPU1_P1_N
RST_RT_CPU1_P1_RESET_R_N
4.7K
0
0201LF
R749R752
FF30
FF27
FF24
E30
B28
B31
B25
B23
F34
FF33
E11
FF11
FJ16
FF18
B16
E18
F2
FJ9
E8
B12
FF8
B9
B6
B3
FJ31
FJ28
FJ25
FJ23
FJ6
FJ3
FF5
G35
U6015
CLOCK
3/11
EE_DAT
EE_CLK
CLKREQ_N
TEST2
TEST1
TEST0
T_SENSE
SMBDAT
SMBCLK
SMB_ADDR3
SMB_ADDR2
SMB_ADDR1
SCAN_MODE
RXDET_BYP
RESET_N
REFCLKP
REFCLKN
REFCLK_OUTP
REFCLK_OUTN
PERST_N
MODE
JTAG_TRST_N
JTAG_TMS
JTAG_TEST_MODE
JTAG_TDO
JTAG_TDI
JTAG_TCK
INT_N
GPIO3
GPIO2
GPIO1
GPIO0
MISC JTAG
TESTEEPROM
SMBUS
GPIO
2
1
2
1
R1461
2
1
R1373
2
1
2
1
2
1
2
1
R1378
2
1
R1377
21R1372
21
2
1
2
1
2
1
2
1
R735
2
1
R746
2
1
R741
2
1
R758
2
1
2
1
21
21
2
1
R793
2
1
R794
2
1
R759
2
1
R788
2
1
R786
2
1
R792
2
1
R791
2
1
R787
21
21
21
21
21
21
2
1
2
1
2
1
R784
2
1
R781
2
1
R785
2
1
R783
2
1
R782
2
1
R755
1
SHEETDATE
23
7 3 2 16 5 4
E
A
B
C
E
D
C
B
A
7 6 5 4
D
DEPARTMENT
SIZE
PROJECT DOCUMENT NUMBER REV
REVIEWER
DESIGNER
IN
IN
IN
IN
IN
IN
IN
OUT
OUT
OUT
OUT
OUT
OUT
OUT
IN
IN
IN
IN
IN
IN
IN
OUT
IN
BI
IN
OUT
BI
IN
IN
IN
IN
IN
IN
OUT
OUT
OUT
OUT
IN
IN
OUT
OUT
OUT
R1456R1455R1454
R756
R1376
R795
R796
R745
R732
R731
R779
R780
R670
R671
R598
R597
R626R625
C



Thu Aug 24 14:09:50 2023<NAME_2>
<NAME_1>
MB FABCGTI V02
332 OF 365
P0V9_CPU1_RT1_2A_2D
P 1V 8_CP U1_RT_1D
P 1V 8_CP U1_RT1_1A
P 1V 8_CP U1_RT1_1A _1D
P0V9_CPU1_RT1_2A
P 0V 9_CP U1_RT_2D
0201LF
CHIP
1%
1/20W
200
1/20W
EMPTY
0201LF
1%
1K
RT_CPU1_P1_VQPS
RETIMER_CPU1_P1 POWER(6)
N C F_C PU 1_P1_GN D
N C F_A1_C PU 1_P1_GN D
IC
PT5161LRS
SMLF
1/20W
CHIP
5%
0
0201LF
1/20W
CHIP
5%
0
0201LF
IC
PT5161LRS
SMLF
FH34
FH2
FG35
FG1
FE34
FE2
D35
D1
C34
C2
A35
A1
V35
V1
U34
U2
T4
T32
T22
T13
L35
L1
K34
K2
J4
J22
H31
H19
H16
H12
FJ19
FJ12
FF21
FF14
FD35
FD1
FC9
FC6
FC3
FC28
FC25
FC23
FC19
FB34
FB2
FA32
FA15
ET35
ET1
ER34
ER2
EP4
EP32
EP22
EP13
EJ35
EJ1
EH34
EH2
EG4
EG32
EG22
EG13
EB35
EB1
EA34
EA2
E33
E27
E14
DY4
DY32
DY22
DY13
DR35
DR1
DP34
DP2
DN4
DN32
DN22
DN13
DH35
DH1
DG34
DG2
DF4
DF32
DF22
DF13
DA35
DA1
CY34
CY2
CW4
CW32
CW22
CW13
CP35
CP1
CN34
CN2
CM4
CM32
CM22
CM13
CG35
CG1
CF34
CF2
CE4
CE32
CE22
CE13
BY35
BY1
BW34
BW2
BV4
BV32
BV22
BV13
BN35
BN1
BM34
BM2
BL4
BL32
BL22
BL13
BF35
BF1
BE34
BE2
BD4
BD32
BD22
BD13
B19
AW35
AW1
AV34
AV2
AU4
AU32
AU22
AU13
AM35
AM1
AL34
AL2
AK4
AK32
AK22
AK13
AE35
AE1
AD34
AD2
AC4
AC32
AC22
AC13
G1
CW20
CW17
BL20
BL17
T20
T17
EP20
EP17
EG20
EG17
DY20
DY17
DN20
DN17
DF20
DF17
BD20
BD17
AU20
AU17
AK20
AK17
AC20
AC17
BV17
CM20
CM17
CE20
CE17
BV20
U6015
U6015
4/11
PWR_2A_20
PWR_2A_19
PWR_2A_18
PWR_2A_17
PWR_2A_16
PWR_2A_15
PWR_2A_14
PWR_2A_13
PWR_2A_12
PWR_2A_11
PWR_2A_10
PWR_2A_9
PWR_2A_8
PWR_2A_7
PWR_2A_6
PWR_2A_5
PWR_2A_4
PWR_2A_3
PWR_2A_2
PWR_2A_1
PWR_1D
PWR_2D_4
PWR_2D_3
PWR_2D_2
PWR_2D_1
PWR_1A_5
PWR_1A_4
PWR_1A_3
PWR_1A_2
PWR_1A_1
VQPS
5/11
GND151
GND150
GND149
GND148
GND147
GND146
GND145
GND144
GND143
GND142
GND141
GND140
GND139
GND138
GND137
GND136
GND135
GND134
GND133
GND132
GND131
GND130
GND129
GND128
GND127
GND126
GND125
GND124
GND123
GND122
GND121
GND120
GND119
GND118
GND117
GND116
GND115
GND114
GND113
GND112
GND111
GND110
GND109
GND108
GND107
GND106
GND105
GND104
GND103
GND102
GND101
GND100
GND99
GND98
GND97
GND96
GND95
GND94
GND93
GND92
GND91
GND90
GND89
GND88
GND87
GND86
GND85
GND84
GND83
NCF_GND12
NCF_GND11
NCF_GND10
NCF_GND9
NCF_GND8
NCF_GND7
NCF_GND6
NCF_GND5
NCF_GND4
NCF_GND3
NCF_GND2
NCF_GND1
GND82
GND81
GND80
GND79
GND78
GND77
GND76
GND75
GND74
GND73
GND72
GND71
GND70
GND69
GND68
GND67
GND66
GND65
GND64
GND63
GND62
GND61
GND60
GND59
GND58
GND57
GND56
GND55
GND54
GND53
GND52
GND51
GND50
GND49
GND48
GND47
GND46
GND45
GND44
GND43
GND42
GND41
GND40
GND39
GND38
GND37
GND36
GND35
GND34
GND33
GND32
GND31
GND30
GND29
GND28
GND27
GND26
GND25
GND24
GND23
GND22
GND21
GND20
GND19
GND18
GND17
GND16
GND15
GND14
GND13
GND12
GND11
GND10
GND9
GND8
GND7
GND6
GND5
GND4
GND3
GND2
GND1
0.9V 0.9V
1.8V
/1.8V
1.2V / 1.5V
2
1
R6730
2
1
2
1
2
1
1
SHEETDATE
23
7 3 2 16 5 4
E
A
B
C
E
D
C
B
A
7 6 5 4
D
DEPARTMENT
SIZE
PROJECT DOCUMENT NUMBER REV
REVIEWER
DESIGNER
R6731
R6732
R6733
C



RETIMER EEPRO ADDRESS: 0XA0 (8 BIT) / 0X50 (7 BIT)
Thu Aug 24 14:09:46 2023<NAME_2>
<NAME_1>
MB FABCGTI V02
333 OF 365
P 1V 8_CP U1_RT_1D
185186
185186
SMB_RT_CPU1_P1_ROM_SDASMB_RT_CPU1_P1_ROM_R_SDA
1%33.2
SMB_RT_CPU1_P1_ROM_SCLSMB_RT_CPU1_P1_ROM_R_SCL
0201LFCHIP1/20W
M24M02-DRMN6TP
U19_E2
0.1UF
IC
X 7S
10%
C0201
10V
CHIP
0201LF
1K
1%
1/20W
SMLF
RETIMER_CPU1_P1(7)
7
4
8
5
6 3
2
1
U19
DU1
DU2
E2
VSSSDA
SCL
WC_N
VCC
2
1 C7502
2
1
21
21
1
SHEETDATE
23
7 3 2 16 5 4
E
A
B
C
E
D
C
B
A
7 6 5 4
D
DEPARTMENT
SIZE
PROJECT DOCUMENT NUMBER REV
REVIEWER
DESIGNER
IN
BI R6789
R689
R690
C



Thu Aug 24 14:09:51 2023<NAME_2>
<NAME_1>
MB FABCGTI V02
334 OF 365
EMPTY
P 1V 8_CP U1_RT_1D
P 1V 8_CP U1_RT1_1A _1D
P 1V 8_CP U1_RT1_1A
P0V9_CPU1_RT_2D
P0V9_CPU1_RT1_2A_2D
P0V9_CPU1_RT1_2A
C0805
4V
X 6S
100UF
20%
100UF
X 6S
4V
20%
C0805
100UF
C0805
4V
X 6S
20%20%
4V
100UF
C0805
X 6S
100UF
X 6S
C0805
20%
4V
100UF
X 6S
20%
4V
C0805
100UF
C0805
20%
X 6S
4V
X7S X7S X7S
2.5V 2.5V
4V
100UF
10% 10%
10V 10V 20%
470UF470UF0.1UF0.1UF0.1UF0.1UF
10V
S MLF
0.1UF
20%
4V
C0201
10%
10V
0201
6.3V
C0201
6.3V
20%
C0402
1/16W
BLM15PD121SN1D/1300MA
0.1UF
10V
C0201C0201
10%20%
6.3V
BLM21SN300SN1D/5A
10V
10%
X7S
C0402
20%
0402
20%
4V
4.7UF
X 6S
0201
1UF 1UF
10%10%
10V
4V
1UF
X 6S X 6SX 6S
4V
4.7UF
20%
1UF
10UF
20%
C0402C0402
X 6S
20%
6.3V
10UF
6.3V
20%
X 6SX 6S
20%
4V4V
C0402
20%
22UF
4V4V
C0402
X 6SX 6S
10%
X 6S
100NH/16A
0.1UF0.1UF
10%
X7S
X 6S
20%
10UF
4V
20%
6.3V
22UF
10UF
C0402 0201
X 6S
1UF
20%
X 6SX 6S
10%20%
C0402
X 6S
20%
4V
4V
C0402
0.1UF
10V
X 6SX 6S
10V
0402
6.3V
0.1UF
0201
X 6S
20%
4.7UF10UF
20%
20%
0402
IND
SMLF
L31/R704 COLAY WITH R653/R664
0402LF
5%
EMPTY
0
IND
SMLF
C0402
20%
6.3V
X 6S
22UF
0201
X 6S
RETIMER_CPU1_P1 DECAPS(8)
0
5%
0
0402LF 5%
1/16W
1UF
20%
4V
5%
0
1/4W CHIP
0 5%
22UF
X 6S
20%
SMLF
IND
10UF
6.3V
X 6S
10UF
X 6S X 6S
X 6S
4.7UF
4V
6.3V
4.7UF
X 6S
4V
1UF
C0402
0402LF
1/16W EMPTY
R705 AND R712 COLAY
0603LF
EMPTY
1/4W
10%
0.1UF
10V
X7S
C0201
X7S
C0201
10V
10%
X7S
10%
10V
0.1UF
10V
X7S
0.1UF
10%
10V
X7S
C0201
X7S X7S
C0201
10%
0.1UF
10V
X7S
10%
10V
X7S
C0201
10%
10V
X7S
C0201
10%
X7S
C0201
6.3V
X 6S
0402
1UF
20%
4.7UF
4V
C0201
X7S
4V
0402
C0402
4V
20%
C0201C0201 C0201 C0201
0.1UF
10V20%
0201
0.1UF
X 6S
6.3V
C0402 C0402
22UF
X 6S
6.3V
20%
22UF22UF
20% 20%
X 6SX 6S
6.3V
0402
X7S X7S
0.1UF
20%
02010201
X 6S
4.7UF
0201
4V
0201 0201
10V10V
0.1UF
0603LF
20% 20% 20%
4V4V4V
1UF 1UF 1UF 1UF
0.1UF0.1UF
1UF
20%
X 6S
10V
10%
X7S
4V
20%
X 6S
0201
02010201
1UF
C0201
1UF
0201
20%
X 6S
0402
20%
X7S
C0201
10%
C0201
4V
1UF
20%
X 6S
0201 0201
X 6S
20%
4V
1UF
X 6S
C0201
20%
X6S
C0805
S P CA PS P CA P
S MLF
20%
C0201
10%
0.1UF
C110
C7025
C200C127
C195
C102
C111C103
C203
2121
2 1
L6L5
CAD NOTE:
CAD NOTE:
1 21 2
L31
12
2
1
2
1 C7024
2
1 C7023
2
1
2
1
2
1
2
1
2
1
R704
2
1
2
1
2
1
2
1
2
1
2
1
2
1
2
1
2
1
2
1
2
1
2
1
2
1
2
1
2
1
2
1
2
1
2
1
2
1
2
1
2
1
2
1
2
1
2
1
2
1
2
1
2
1
2
1
2
1
2
1
2
1
2
1
2
1
2
1
2
1
2
1
2
1
2
1
2
1
2
1
2
1
2
1
2
1
2
1
2
1
2
1
2
1
2
1
2
1
2
1
2
1
2
1
2
1
2
1 C204
2
1 C202
2
1
2
1 C199
2
1
2
1
2
1
21
2
1
2
1
2
1
21R653
21R664
1
SHEETDATE
23
7 3 2 16 5 4
E
A
B
C
E
D
C
B
A
7 6 5 4
D
DEPARTMENT
SIZE
PROJECT DOCUMENT NUMBER REV
REVIEWER
DESIGNER
C350C341
C315C306
C333 C290 C292 C311C300
C354C339
C342C338
C318C351C335C329
C327C323
C328C324C320C317
C353C289
C334C322
C301C293
C346
C336C343
C337C314
C319C291C349C312
C330
C331C325C321
C326C307
C332
C294
C344C340
C316C313
C288C287C217C205
R712
R705
C206
C



Thu Aug 24 10:16:54 2023<NAME_2>
<NAME_1>
MB FABCGTI V02
335 OF 365RETIMER_CPU1_P1(9)
1
SHEETDATE
23
7 3 2 16 5 4
E
A
B
C
E
D
C
B
A
7 6 5 4
D
DEPARTMENT
SIZE
PROJECT DOCUMENT NUMBER REV
REVIEWER
DESIGNER
C



Thu Aug 24 10:16:55 2023<NAME_2>
<NAME_1>
MB FABCGTI V02
336 OF 365RETIMER_CPU1_P1(10)
1
SHEETDATE
23
7 3 2 16 5 4
E
A
B
C
E
D
C
B
A
7 6 5 4
D
DEPARTMENT
SIZE
PROJECT DOCUMENT NUMBER REV
REVIEWER
DESIGNER
C



Thu Aug 24 10:16:56 2023<NAME_2>
<NAME_1>
MB FABCGTI V02
337 OF 365BLANK
1
SHEETDATE
23
7 3 2 16 5 4
E
A
B
C
E
D
C
B
A
7 6 5 4
D
DEPARTMENT
SIZE
PROJECT DOCUMENT NUMBER REV
REVIEWER
DESIGNER
C



CPU TO RETIMER CPU TO RETIMER
P5E_CPU1_P2_TX_C_DP/DN<0-15> LANE REVERSAL
P/N SWAP
P/N SWAP
P/N SWAP
P/N SWAP
P/N SWAP
P/N SWAP
P/N SWAP
P/N SWAP
P/N SWAP
P/N SWAP
P/N SWAP
P/N SWAP
P/N SWAP
P/N SWAP
P/N SWAP
Thu Aug 24 14:09:40 2023<NAME_2>
<NAME_1>
MB FABCGTI V02
338 OF 365
66
66
66
66
P5E_CPU1_P2_TX_C_DP<15:8>
P5E_CPU1_P2_TX_C_DN<15:8>
RETIMER_CPU1_P2(1)
SMLF
PT5161LRS
IC
IC
SMLF
PT5161LRS
P5E_CPU1_P2_TX_C_DP<7:0>
P5E_CPU1_P2_TX_C_DN<7:0>
EV34
EL34
ED34
DU34
DK34
DC34
CT34
CJ34
EY35
EN35
EF35
DW35
DM35
DE35
CV35
CL35
CB34
BR34
BH34
BA34
AP34
AG34
Y34
N34
CD35
BU35
BK35
BC35
AT35
AJ35
AB35
R35
1
15
9
10
12
13
14
11
8
9
10
11
12
13
14
15
8
7
0
2
3
4
5
6
0
2
3
4
6
7
5
1
U6016
U6016
9/11
B_PERN15
B_PERP15
B_PERN14
B_PERP14
B_PERN13
B_PERP13
B_PERN12
B_PERP12
B_PERN11
B_PERP11
B_PERN10
B_PERP10
B_PERN9
B_PERP9
B_PERN8
B_PERP8
8/11
B_PERN7
B_PERP7
B_PERN6
B_PERP6
B_PERN5
B_PERP5
B_PERN4
B_PERP4
B_PERN3
B_PERP3
B_PERN2
B_PERP2
B_PERN1
B_PERP1
B_PERN0
B_PERP0
RX : B_PER[15:8]
RX : B_PER[7:0]
1
SHEETDATE
23
7 3 2 16 5 4
E
A
B
C
E
D
C
B
A
7 6 5 4
D
DEPARTMENT
SIZE
PROJECT DOCUMENT NUMBER REV
REVIEWER
DESIGNER
IN
IN
IN
IN
C



RETIMER TO CPU RETIMER TO CPU
P5E_CPU1_P2_RX_DP/DN<0-15> LANE REVERSAL
Thu Aug 24 14:09:40 2023<NAME_2>
<NAME_1>
MB FABCGTI V02
339 OF 365
52
52
52
52
P5E_CPU1_P2_RX_DN<7:0>
P5E_CPU1_P2_RX_DP<7:0>
PT5161LRS
SMLF
RETIMER_CPU1_P2(2)
IC
PT5161LRS
SMLF
IC
P5E_CPU1_P2_RX_DN<15:8>
P5E_CPU1_P2_RX_DP<15:8>
EU26
EK26
EC26
DT26
DJ26
DB26
CR26
CH26
EW29
EM29
EE29
DV29
DL29
DD29
CU29
CK29
CA26
BP26
BG26
AY26
AN26
AF26
W26
M26
CC29
BT29
BJ29
BB29
AR29
AH29
AA29
P29
14 6
7
7
6
2
13
11
12
1
5
5
4
4
3
3
2
1
0
0
13
11
10
12
10
9
8
9
8
14
15
15
U6016
U6016
7/11
A_PETN15
A_PETP15
A_PETN14
A_PETP14
A_PETN13
A_PETP13
A_PETN12
A_PETP12
A_PETN11
A_PETP11
A_PETN10
A_PETP10
A_PETN9
A_PETP9
A_PETN8
A_PETP8
6/11
A_PETN7
A_PETP7
A_PETN6
A_PETP6
A_PETN5
A_PETP5
A_PETN4
A_PETP4
A_PETN3
A_PETP3
A_PETN2
A_PETP2
A_PETN1
A_PETP1
A_PETN0
A_PETP0
TX : A_PET[15:8]
TX : A_PET[7:0]
1
SHEETDATE
23
7 3 2 16 5 4
E
A
B
C
E
D
C
B
A
7 6 5 4
D
DEPARTMENT
SIZE
PROJECT DOCUMENT NUMBER REV
REVIEWER
DESIGNER
OUT
OUT
OUT
OUT
C



EXAMAX TO RETIMEREXAMAX TO RETIMER
P5E_CPU1_P2_RX_BUF_DP/DN<0-15> LANE REVERSAL
Thu Aug 24 14:09:40 2023<NAME_2>
<NAME_1>
MB FABCGTI V02
340 OF 365
119
120
120
119
P5E_CPU1_P2_RX_BUF_DP<15:8>
P5E_CPU1_P2_RX_BUF_DN<7:0>
P5E_CPU1_P2_RX_BUF_DP<7:0>
P5E_CPU1_P2_RX_BUF_DN<15:8>
SMLF
IC
PT5161LRS PT5161LRS
IC
SMLF
RETIMER_CPU1_P2(3)
EY1
EN1
EF1
DW1
DM1
DE1
CV1
CL1
EV2
EL2
ED2
DU2
DK2
DC2
CT2
CJ2
CD1
BU1
BK1
BC1
AT1
AJ1
AB1
R1
CB2
BR2
BH2
BA2
AP2
AG2
Y2
N2 7
6
5
4
3
2
1
0
0
1
2
3
4
5
6
7
15
14
13
12
11
10
9
8
8
9
10
11
12
13
14
15
U6016U6016
2/11
A_PERN15
A_PERP15
A_PERN14
A_PERP14
A_PERN13
A_PERP13
A_PERN12
A_PERP12
A_PERN11
A_PERP11
A_PERN10
A_PERP10
A_PERN9
A_PERP9
A_PERN8
A_PERP8
1/11
A_PERN7
A_PERP7
A_PERN6
A_PERP6
A_PERN5
A_PERP5
A_PERN4
A_PERP4
A_PERN3
A_PERP3
A_PERN2
A_PERP2
A_PERN1
A_PERP1
A_PERN0
A_PERP0
RX : A_PER[15:8]
RX : A_PER[7:0]
1
SHEETDATE
23
7 3 2 16 5 4
E
A
B
C
E
D
C
B
A
7 6 5 4
D
DEPARTMENT
SIZE
PROJECT DOCUMENT NUMBER REV
REVIEWER
DESIGNER
IN
IN
IN
IN
C



P5E_CPU1_P2_TX_BUF_DP/DN<0-15> LANE REVERSAL
RETIMER TO EXAMAX RETIMER TO EXAMAX
Thu Aug 24 14:09:41 2023<NAME_2>
<NAME_1>
MB FABCGTI V02
341 OF 365
342
342
120
120
342
342 119
119
342
342 342
342
D IFF BU S_0.22U F
D IFF BU S_0.22U F
P5E_CPU1_P2_TX_BUF_DP<7:0>
P5E_CPU1_P2_TX_BUF_DN<7:0>
P5E_CPU1_P2_TX_BUF_C_DP<7:0>
P5E_CPU1_P2_TX_BUF_C_DN<7:0>
D IFF BU S_0.22U F
D IFF BU S_0.22U F
D IFF BU S_0.22U F
D IFF BU S_0.22U F
D IFF BU S_0.22U F
D IFF BU S_0.22U F
D IFF BU S_0.22U F
D IFF BU S_0.22U F
D IFF BU S_0.22U F
D IFF BU S_0.22U F
D IFF BU S_0.22U F
D IFF BU S_0.22U F
D IFF BU S_0.22U F
C0201
X 6S
D IFF BU S_0.22U F
20% 6.3V
P5E_CPU1_P2_TX_BUF_DN<15:8>
P5E_CPU1_P2_TX_BUF_DP<15:8> P5E_CPU1_P2_TX_BUF_C_DP<15:8>
P5E_CPU1_P2_TX_BUF_C_DN<15:8>
D IFF BU S_0.22U F
D IFF BU S_0.22U F
D IFF BU S_0.22U F
D IFF BU S_0.22U F
D IFF BU S_0.22U F
D IFF BU S_0.22U F
D IFF BU S_0.22U F
D IFF BU S_0.22U F
D IFF BU S_0.22U F
D IFF BU S_0.22U F
D IFF BU S_0.22U F
D IFF BU S_0.22U F
D IFF BU S_0.22U F
D IFF BU S_0.22U F
D IFF BU S_0.22U F
20%C0201
X 6S
6.3V
D IFF BU S_0.22U F
P5E_CPU1_P2_TX_BUF_DN<15:8>
RETIMER_CPU1_P2(4)
SMLF
PT5161LRS
IC
SMLF
IC
PT5161LRS
P5E_CPU1_P2_TX_BUF_DP<15:8> P5E_CPU1_P2_TX_BUF_DP<7:0>
P5E_CPU1_P2_TX_BUF_DN<7:0>
2 1
2 1
2 1
2 1
2 1
2 1
2 1
2 1
2 1
2 1
2 1
2 1
2 1
2 1
2 1
2 1
2 1
2 1
2 1
2 1
2 1
2 1
2 1
2 1
2 1
2 1
2 1
2 1
2 1
2 1
2 1
2 1
EU7
EK7
EC7
DT7
DJ7
DB7
CR7
CH7
EW10
EM10
EE10
DV10
DL10
DD10
CU10
CK10
CA7
BP7
BG7
AY7
AN7
AF7
W7
M7
CC10
BT10
BJ10
BB10
AR10
AH10
AA10
P10
7
6
5
4
3
2
1
0
7
6
5
4
3
2
1
0
7
5
6
7
6
5
3
2
4
4
3
2
0
1
1
0
15
14
15
14
12
13
13
12
10
11
9
11
10
9
8
8
15
14
15
14
13
12
12
11
10
9
11
10
9
8
8
13
8 0
2
15
14
13
12
11
10
9
8
9
10
11
12
13
14
15
7
6
5
4
3
2
1
0
1
3
4
5
6
7
U6016
C6710
C6709
C6711
C6712
C6713
C6714
C6715
C6716
C6717
C6718
C6719
C6720
C6721
C6722
C6723
C6724
C6694
C6693
U6016
C6697
C6695
C6696
C6698
C6700
C6699
C6701
C6702
C6703
C6704
C6705
C6706
C6707
C6708
10/11
B_PETN7
B_PETP7
B_PETN6
B_PETP6
B_PETN5
B_PETP5
B_PETN4
B_PETP4
B_PETN3
B_PETP3
B_PETN2
B_PETP2
B_PETN1
B_PETP1
B_PETN0
B_PETP0
11/11
B_PETN15
B_PETP15
B_PETN14
B_PETP14
B_PETN13
B_PETP13
B_PETN12
B_PETP12
B_PETN11
B_PETP11
B_PETN10
B_PETP10
B_PETN9
B_PETP9
B_PETN8
B_PETP8
TX : B_PET[7:0]
TX : B_PET[15:8]
2 1
2 1
2 1
2 1
2 1
2 1
2 1
2 1
2 1
2 1
2 1
2 1
2 1
2 1
2 1
2 1
2 1
2 1
2 1
2 1
2 1
2 1
2 1
2 1
2 1
2 1
2 1
2 1
2 1
2 1
2 1
2 1
1
SHEETDATE
23
7 3 2 16 5 4
E
A
B
C
E
D
C
B
A
7 6 5 4
D
DEPARTMENT
SIZE
PROJECT DOCUMENT NUMBER REV
REVIEWER
DESIGNER
OUT
OUT
IN
IN
OUT
OUTIN
OUT
OUT
OUT
OUT
IN
C



CPU1 P1 RT ADDR: 0X48 (8-BIT) / 0X24 (7-BIT)
Thu Aug 24 14:09:52 2023<NAME_2>
<NAME_1>
MB FABCGTI V02
342 OF 365
P 1V 8_CP U1_RT_1D
P 1V 8_CP U1_RT_1D P 1V 8_CP U1_RT_1D
P 1V 8_CP U1_RT_1D
P 1V 8_CP U1_RT_1D
P 1V 8_CP U1_RT_1D
P 1V 8_CP U1_RT_1D
SMB_RT_CPU1_P2_ROM_MUX_1D_R_SCLSMB_RT_CPU1_P2_ROM_MUX_1D_SCL
1%49.9
0201LF1/20W CHIP
SMB_RT_CPU1_P2_ROM_MUX_1D_R_SDASMB_RT_CPU1_P2_ROM_MUX_1D_SDA
185186
185186
343
343
343
343
343
343
343
343
81 343
81 343
343
183
343
343
183
343
343
343
343
81 343
81 343
343 343
343
343
343
343 343
343
343
184
343
343
343
343
343
184
343
343
343
0201LF
1%
200
1/20W
CHIP
JTAG_TCK_RT_CPU1_P2
JTAG_TMS_RT_CPU1_P2
JTAG_TDI_RT_CPU1_P2
JTAG_TDO_RT_CPU1_P2
EMPTY
5%
0201LF
4.7K
1/20W
4.7K
5%
1/20W
0201LF
EMPTY1/20W
1%
1K
0201LF
EMPTY
4.7K
1/20W
5%
0201LF
EMPTY
JTAG_TDI_RT_CPU1_P2
JTAG_TMS_RT_CPU1_P2
JTAG_TDO_RT_CPU1_P2
JTAG_TCK_RT_CPU1_P2
0201LF
RST_RT_CPU1_P2_RESET_R_N
CHIP
0 RST_RT_CPU1_P2_PERST_R_N
CHIP
0201LF
1K
RXDET_BYP_RT_CPU1_P2
CLK_100M_RETIMER_CPU1_P2_R_DP
CHIP 0201LF
0201LF1/20W
5%0
CHIP
51.1
1/20W
EMPTY
1%
0201LF
EMPTY
1%
0201LF
51.1
1/20W
IC
PT5161LRS
SMLFEMPTY
1/20W
4.7K
5%
0201LF
10K
1%
1/20W
CHIP
0201LF
10K
1%
1/20W
CHIP
0201LF
5%
0201LF
EMPTY
4.7K
1/20W
0201LF
0
CHIP1/20W
5%
4.7K
5%
1/20W
0201LF
CHIP
4.7K
5%
0201LF
CHIP
1/20W
CHIP
0201LF
4.7K
5%
1/20W 1/20W
CHIP
4.7K
5%
0201LF
5%
0201LF
EMPTY
1/20W
4.7K
1/20W
5%
4.7K
0201LF
EMPTY
4.7K
1/20W
EMPTY
0201LF
5% 1/20W
EMPTY
5%
4.7K
0201LF
EMPTY
5%
0201LF
1/20W
4.7K
4.7K
5%
1/20W
CHIP
0201LF
0201LF0
0201LF
0201LF
1/20W
1%
1K
EMPTY
20K
1%
1/20W
CHIP
0201LF
CHIP
0201LF
1/20W
1%
1K
EMPTY
1/20W
1K
1%
0201LF
1K
0201LF
1/20W
1%
CHIP
0201LF
1/20W
1K
1%
EMPTY
CHIP
0201LF
10K
1/20W
1%
10K
1/20W
1%
CHIP
0201LF
0201LF
EMPTY
4.7K
1/20W
5%
TEST1_RT_CPU1_P2
TEST2_RT_CPU1_P2
CLK_100M_RETIMER_CPU1_P2_R_DN
RT_CPU1_P2_ADDR2
GPIO2_RT_CPU1_P2
RT_CPU1_P2_ADDR1
SMB_RT_CPU1_P2_R2_SDA
RT_CPU1_P2_ADDR3
RST_RT_CPU1_P2_RESET_R_N
RST_RT_CPU1_P2_PERST_R_N
MODE_RT_CPU1_P2 RT_CPU1_P2_ADDR3
JTAG_TEST_MODE_RT_CPU1_P2
TEST2_RT_CPU1_P2
TEST1_RT_CPU1_P2
TEST0_RT_CPU1_P2 RT_CPU1_P2_ADDR1
TEST0_RT_CPU1_P2
RT_CPU1_P2_ADDR2
CLK_100M_RETIMER_CPU1_P2_DN
RETIMER_CPU1_P2(5)
SMB_RT_CPU1_P2_R_SDA
GPIO2_RT_CPU1_P2
GPIO3_RT_CPU1_P2
GPIO3_RT_CPU1_P2
CLK_100M_RETIMER_CPU1_P2_DP
MODE_RT_CPU1_P2
RT_CPU1_P2_SCAN_MODE
SMB_RT_CPU1_P2_R2_SCLSMB_RT_CPU1_P2_R_SCL
RT_CPU1_P2_SCAN_MODE
JTAG_TEST_MODE_RT_CPU1_P2
JTAG_TRST_RT_CPU1_P2_N
CLKREQ_RT_CPU1_P2_N
RXDET_BYP_RT_CPU1_P2
1%
1/20W
0201LF
EMPTY
1K
0201LF
1/20W
10K
1%
CHIP
4.7K
RST_RT_CPU1_P2_PERST_N
4.7K
5%
1/20W
0201LF
CHIP
RST_RT_CPU1_P2_RESET_N
R866R867
FF30
FF27
FF24
E30
B28
B31
B25
B23
F34
FF33
E11
FF11
FJ16
FF18
B16
E18
F2
FJ9
E8
B12
FF8
B9
B6
B3
FJ31
FJ28
FJ25
FJ23
FJ6
FJ3
FF5
G35
U6016
CLOCK
3/11
EE_DAT
EE_CLK
CLKREQ_N
TEST2
TEST1
TEST0
T_SENSE
SMBDAT
SMBCLK
SMB_ADDR3
SMB_ADDR2
SMB_ADDR1
SCAN_MODE
RXDET_BYP
RESET_N
REFCLKP
REFCLKN
REFCLK_OUTP
REFCLK_OUTN
PERST_N
MODE
JTAG_TRST_N
JTAG_TMS
JTAG_TEST_MODE
JTAG_TDO
JTAG_TDI
JTAG_TCK
INT_N
GPIO3
GPIO2
GPIO1
GPIO0
MISC JTAG
TESTEEPROM
SMBUS
GPIO
2
1
2
1
2
1
R1499
2
1
R1417
2
1
2
1
2
1
R1426
2
1
R1427
21R1416
21
2
1
2
1
R870
2
1
2
1
2
1
2
1
2
1
2
1
R861
2
1
R865
2
1
R863
21
21
2
1
R885
2
1
R886
2
1
R871
2
1
R882
2
1
R880
2
1
R878
2
1
R884
2
1
R883
2
1
R881
2
1
R879
2
1
21
21
21
21
21
21
2
1
R874
2
1
R876
2
1
R875
2
1
R868
1
SHEETDATE
23
7 3 2 16 5 4
E
A
B
C
E
D
C
B
A
7 6 5 4
D
DEPARTMENT
SIZE
PROJECT DOCUMENT NUMBER REV
REVIEWER
DESIGNER
IN
IN
IN
IN
IN
OUT
OUT
OUT
OUT
IN
IN
IN
IN
IN
OUT
OUT
OUT
OUT
OUT
OUT
IN
IN
IN
IN
IN
OUT
IN
BI
BI
OUT
IN
IN
IN
IN
IN
IN
OUT
OUT
OUT
OUT
IN
IN
R1489 R1490R1488
R869
R1421
R637
R887
R892
R864
R854
R860
R640
R873
R872
R691
R692
R619
R620
C



Thu Aug 24 14:09:52 2023<NAME_2>
<NAME_1>
MB FABCGTI V02
343 OF 365
P 0V 9_CP U1_RT_2D
P0V9_CPU1_RT2_2A_2D
P0V9_CPU1_RT2_2A
P 1V 8_CP U1_RT_1D
P 1V 8_CP U1_RT2_1A
P 1V 8_CP U1_RT2_1A _1D
CHIP
1/20W
200
1%
0201LF
0201LF
1/20W
1%
1K
EMPTY
RT_CPU1_P2_VQPS
RETIMER_CPU1_P2 POWER(6)
N C F_C PU 1_P2_GN D
N C F_A1_C PU 1_P2_GN D
0
0
5%
1/20W
CHIP
0201LF
IC
PT5161LRS
SMLF
1/20W
5%
0201LF
IC
PT5161LRS
SMLF
CHIP
FH34
FH2
FG35
FG1
FE34
FE2
D35
D1
C34
C2
A35
A1
V35
V1
U34
U2
T4
T32
T22
T13
L35
L1
K34
K2
J4
J22
H31
H19
H16
H12
FJ19
FJ12
FF21
FF14
FD35
FD1
FC9
FC6
FC3
FC28
FC25
FC23
FC19
FB34
FB2
FA32
FA15
ET35
ET1
ER34
ER2
EP4
EP32
EP22
EP13
EJ35
EJ1
EH34
EH2
EG4
EG32
EG22
EG13
EB35
EB1
EA34
EA2
E33
E27
E14
DY4
DY32
DY22
DY13
DR35
DR1
DP34
DP2
DN4
DN32
DN22
DN13
DH35
DH1
DG34
DG2
DF4
DF32
DF22
DF13
DA35
DA1
CY34
CY2
CW4
CW32
CW22
CW13
CP35
CP1
CN34
CN2
CM4
CM32
CM22
CM13
CG35
CG1
CF34
CF2
CE4
CE32
CE22
CE13
BY35
BY1
BW34
BW2
BV4
BV32
BV22
BV13
BN35
BN1
BM34
BM2
BL4
BL32
BL22
BL13
BF35
BF1
BE34
BE2
BD4
BD32
BD22
BD13
B19
AW35
AW1
AV34
AV2
AU4
AU32
AU22
AU13
AM35
AM1
AL34
AL2
AK4
AK32
AK22
AK13
AE35
AE1
AD34
AD2
AC4
AC32
AC22
AC13
G1
CW20
CW17
BL20
BL17
T20
T17
EP20
EP17
EG20
EG17
DY20
DY17
DN20
DN17
DF20
DF17
BD20
BD17
AU20
AU17
AK20
AK17
AC20
AC17
BV17
CM20
CM17
CE20
CE17
BV20
U6016
U6016
4/11
PWR_2A_20
PWR_2A_19
PWR_2A_18
PWR_2A_17
PWR_2A_16
PWR_2A_15
PWR_2A_14
PWR_2A_13
PWR_2A_12
PWR_2A_11
PWR_2A_10
PWR_2A_9
PWR_2A_8
PWR_2A_7
PWR_2A_6
PWR_2A_5
PWR_2A_4
PWR_2A_3
PWR_2A_2
PWR_2A_1
PWR_1D
PWR_2D_4
PWR_2D_3
PWR_2D_2
PWR_2D_1
PWR_1A_5
PWR_1A_4
PWR_1A_3
PWR_1A_2
PWR_1A_1
VQPS
5/11
GND151
GND150
GND149
GND148
GND147
GND146
GND145
GND144
GND143
GND142
GND141
GND140
GND139
GND138
GND137
GND136
GND135
GND134
GND133
GND132
GND131
GND130
GND129
GND128
GND127
GND126
GND125
GND124
GND123
GND122
GND121
GND120
GND119
GND118
GND117
GND116
GND115
GND114
GND113
GND112
GND111
GND110
GND109
GND108
GND107
GND106
GND105
GND104
GND103
GND102
GND101
GND100
GND99
GND98
GND97
GND96
GND95
GND94
GND93
GND92
GND91
GND90
GND89
GND88
GND87
GND86
GND85
GND84
GND83
NCF_GND12
NCF_GND11
NCF_GND10
NCF_GND9
NCF_GND8
NCF_GND7
NCF_GND6
NCF_GND5
NCF_GND4
NCF_GND3
NCF_GND2
NCF_GND1
GND82
GND81
GND80
GND79
GND78
GND77
GND76
GND75
GND74
GND73
GND72
GND71
GND70
GND69
GND68
GND67
GND66
GND65
GND64
GND63
GND62
GND61
GND60
GND59
GND58
GND57
GND56
GND55
GND54
GND53
GND52
GND51
GND50
GND49
GND48
GND47
GND46
GND45
GND44
GND43
GND42
GND41
GND40
GND39
GND38
GND37
GND36
GND35
GND34
GND33
GND32
GND31
GND30
GND29
GND28
GND27
GND26
GND25
GND24
GND23
GND22
GND21
GND20
GND19
GND18
GND17
GND16
GND15
GND14
GND13
GND12
GND11
GND10
GND9
GND8
GND7
GND6
GND5
GND4
GND3
GND2
GND1
0.9V 0.9V
1.8V
/1.8V
1.2V / 1.5V
2
1
R6794
2
1
2
1
2
1
1
SHEETDATE
23
7 3 2 16 5 4
E
A
B
C
E
D
C
B
A
7 6 5 4
D
DEPARTMENT
SIZE
PROJECT DOCUMENT NUMBER REV
REVIEWER
DESIGNER
R6795
R6796
R6797
C



RETIMER EEPRO ADDRESS: 0XA0 (8 BIT) / 0X50 (7 BIT)
Thu Aug 24 14:09:46 2023<NAME_2>
<NAME_1>
MB FABCGTI V02
344 OF 365
P 1V 8_CP U1_RT_1D
185186
185186
1%33.2
SMB_RT_CPU1_P2_ROM_SCLSMB_RT_CPU1_P2_ROM_R_SCL
0201LF1/20W CHIP
SMB_RT_CPU1_P2_ROM_SDASMB_RT_CPU1_P2_ROM_R_SDA
M24M02-DRMN6TP
U20_E2
10V
10%
0.1UF
C0201
X 7S
0201LF
CHIP
1K
1%
1/20W
SMLF
RETIMER_CPU1_P2(7)
IC
7
4
8
5
6 3
2
1
U20
DU1
DU2
E2
VSSSDA
SCL
WC_N
VCC
2
1 C7503
2
1
21
21
1
SHEETDATE
23
7 3 2 16 5 4
E
A
B
C
E
D
C
B
A
7 6 5 4
D
DEPARTMENT
SIZE
PROJECT DOCUMENT NUMBER REV
REVIEWER
DESIGNER
BI
IN R6790R693
R694
C



Thu Aug 24 14:09:52 2023<NAME_2>
<NAME_1>
MB FABCGTI V02
345 OF 365
P0V9_CPU1_RT2_2A
P 1V 8_CP U1_RT2_1A
P 1V 8_CP U1_RT_1D
P0V9_CPU1_RT2_2A_2D
P 1V 8_CP U1_RT2_1A _1D
P0V9_CPU1_RT_2D
X 6S
4V
100UF
C0805
20%
4V
20%
X 6S
C0805
100UF
X 6S
20%
100UF
4V
C0805
20%
100UF
4V
C0805
X 6S
4V
X 6S
20%
100UF
C0805
100UF
X 6S
20%
4V
C0805
20%
100UF
4V
C0805
X 6S
X 6S
2.5V 20% 20%
4V 4V
47UF47UF
4V4V20%
47UF
20% 20%
470UF
S P CA P
C0805
X6S
47UF
C0805
X6S
C0805
X6SX6S
C0805
S MLF
20%
0402
C0402
X 6S
20%
6.3V
10UF
C0402
0201
X 6SX 6S
C0402
X 6S
22UF
20%
4V
10UF
6.3V
20%
6.3V
4.7UF
10%
X7S
10%
10V
0.1UF
C0201
X7S
10%
10V
0.1UF
C0201
10V
10%
X7S
0.1UF
1UF
0201
0.1UF
C0201
X 6S
10V
C0201
C0201
4V
20%
0201
4V
X 6S
0.1UF
10%
C0201
0.1UF
1UF 1UF
X 6S
20%
X 6S
6.3V
1UF
X 6S
0201
1UF
6.3V
20%
X 6S
4V
C0402
20%
X 6S
C0402
6.3V
20%
4V
22UF
0.1UF0.1UF
0201 C0201C0201
X7S
10%
4V
1UF
1UF
10V
X7SX 6S
0.1UF
10V
4.7UF
22UF
BLM21SN300SN1D/5A
0
BLM15PD121SN1D/1300MA
SMLF
IND
EMPTY
0402LF
1/16W
L32/R857 COLAY WITH R852/R853
1/16W
5%
0
20%
4V
IND
SMLF
R858 AND R859 COLAY
0603LF
EMPTY
C0201
EMPTY
100NH/16A
SMLF
X7S
10%
X7S
10%
X 6S
20%
X 6S
20%
X 6S
20%
X 6S
0201
20%
1UF
0
1/4W
X7S
10%
X7S
C0201
X7S
10V
10%
C0201
X7S
10V
10%
20%
0402
6.3V
20%
20%
1/4W
0
5%
C0201
X7S
10%
10V10V
10%
22UF
X7S
10V
0.1UF
10%X 6S
0201
EMPTY1/16W
5%0402LF
0
0402LF 5%
X7S
RETIMER_CPU1_P2 DECAPS(8)
X 6S
0.1UF
C0402
4V
C0402
X 6SX 6S
C0402
1UF
X 6S
C0402
20%
10UF
6.3V4V
10UF
6.3V
4V
20% 20%
X 6S
C0201
X7S
10%
0.1UF
X 6S
5%
C0201
X7S
X 6S
20%
X 6S
0201
0.1UF
0402
X 6S
20%
6.3V
4.7UF
IND
6.3V
4V
22UF
4V
X 6S
20%
22UF 10UF
6.3V
20%20%20%
4.7UF10UF
X 6S
C0402
1UF
4V
1UF
X 6S
C0402
4V
4.7UF
6.3V
10%
10V
X 6S
4V
1UF
4V
10V
10%
X7S
C0201
X7S
10%
X 6S
10V
0.1UF
020104020402
10UF
6.3V
1UF
4V
1UF
10%
X 6S
C0402C0402
4V
10V
0.1UF
20% 20% 20%
20%
4V4V
20%20%
0201
X 6S
4V
20%
0201
10V
0.1UF
0603LFCHIP
0402 0402 0201 0201 0201
X 6S
20%
4.7UF
4V
1UF
20%
X 6S
02010201
X 6S
20%
1UF
4V
4V
C0805
4V
X6S
47UF
C0805
20%2.5V
S P CA P
470UF
S MLF
20%
S MLF
2.5V
20%
X7S
S P CA P
470UF
47UF
X6S
20%
0.1UF
10V
C0201
0201
C0402
X 6S
20%
22UF
4.7UF
10%
X7S
0.1UF0.1UF0.1UF
10V10V10V
C0201
10V
X7S
C0201
20%
X6S
C0805
100UF
4V
470UF
20%
S P CA P
S MLF
2.5V
S P CA P
2.5V
S MLF
470UF
20%
C0201
10%
0.1UF
C0201C0201
20%
4V
1UF
C368
C7041C7040C7039C7038C7037
C7028
C7006C7004
C373C370C366
C371C369
C375
C367
2121
2 1
L8L7
CAD NOTE:
CAD NOTE:
1 21 2
L32
12
2
1
2
1
2
1
2
1
2
1
2
1
2
1 C7027
2
1 C7026
2
1
2
1
2
1 C7005
2
1
2
1
2
1
2
1
2
1
2
1
R857
2
1
2
1
2
1
2
1
2
1
2
1
2
1
2
1
2
1
2
1
2
1
2
1
2
1
2
1
2
1
2
1
2
1
2
1
2
1
2
1
2
1
2
1
2
1
2
1
2
1
2
1
2
1
2
1
2
1
2
1
2
1
2
1
2
1
2
1
2
1
2
1
2
1
2
1
2
1
21
2
1
2
1
2
1
2
1
2
1
2
1
2
1
2
1
2
1
2
1
2
1
2
1
2
1
2
1
2
1
2
1
2
1 C376
2
1 C374
2
1
2
1 C372
2
1
2
1
2
1
2
1
21R853
21R852
1
SHEETDATE
23
7 3 2 16 5 4
E
A
B
C
E
D
C
B
A
7 6 5 4
D
DEPARTMENT
SIZE
PROJECT DOCUMENT NUMBER REV
REVIEWER
DESIGNER
C7007
C428C426
C394C390
C409C405
C392C388C385C383C423C419C414C408C404
C431
C382
C429C424
C389C425
C395C411C403
C402C399
C386C412
C417
C413C416
C422C418C415C391C407
C406
C401C398
C420C410
C387C384
R859
C400C430C393C427
C397C396
C421
R858
C381C380C379C377
C378
C



Thu Aug 24 10:17:04 2023<NAME_2>
<NAME_1>
MB FABCGTI V02
346 OF 365RETIMER_CPU1_P2(9)
1
SHEETDATE
23
7 3 2 16 5 4
E
A
B
C
E
D
C
B
A
7 6 5 4
D
DEPARTMENT
SIZE
PROJECT DOCUMENT NUMBER REV
REVIEWER
DESIGNER
C



Thu Aug 24 10:17:04 2023<NAME_2>
<NAME_1>
MB FABCGTI V02
347 OF 365RETIMER_CPU1_P2(10)
1
SHEETDATE
23
7 3 2 16 5 4
E
A
B
C
E
D
C
B
A
7 6 5 4
D
DEPARTMENT
SIZE
PROJECT DOCUMENT NUMBER REV
REVIEWER
DESIGNER
C



Thu Aug 24 10:17:05 2023<NAME_2>
<NAME_1>
MB FABCGTI V02
348 OF 365BLANK
1
SHEETDATE
23
7 3 2 16 5 4
E
A
B
C
E
D
C
B
A
7 6 5 4
D
DEPARTMENT
SIZE
PROJECT DOCUMENT NUMBER REV
REVIEWER
DESIGNER
C



P5E_CPU1_P3_TX_C_DP/DN<0-15> LANE REVERSAL
CPU TO RETIMERCPU TO RETIMER
P/N SWAP
P/N SWAP
P/N SWAP
P/N SWAP
P/N SWAP
P/N SWAP
P/N SWAP
P/N SWAP
P/N SWAP
P/N SWAP
P/N SWAP
P/N SWAP
P/N SWAP
P/N SWAP
Thu Aug 24 14:09:41 2023<NAME_2>
<NAME_1>
MB FABCGTI V02
349 OF 365
67
67
67
67
P5E_CPU1_P3_TX_C_DP<15:8>
IC
SMLF
PT5161LRS
IC
SMLF
PT5161LRS
RETIMER_CPU1_P3(1)
P5E_CPU1_P3_TX_C_DP<7:0>
P5E_CPU1_P3_TX_C_DN<7:0>
P5E_CPU1_P3_TX_C_DN<15:8>
EV34
EL34
ED34
DU34
DK34
DC34
CT34
CJ34
EY35
EN35
EF35
DW35
DM35
DE35
CV35
CL35
CB34
BR34
BH34
BA34
AP34
AG34
Y34
N34
CD35
BU35
BK35
BC35
AT35
AJ35
AB35
R35
1
7
6
7
5
4
3
2
0
0
2
3
4
5
6
13
12
11
10
9
8
13
12
11
10
9
8
15
15
1
14
14
U6017
U6017
9/11
B_PERN15
B_PERP15
B_PERN14
B_PERP14
B_PERN13
B_PERP13
B_PERN12
B_PERP12
B_PERN11
B_PERP11
B_PERN10
B_PERP10
B_PERN9
B_PERP9
B_PERN8
B_PERP8
8/11
B_PERN7
B_PERP7
B_PERN6
B_PERP6
B_PERN5
B_PERP5
B_PERN4
B_PERP4
B_PERN3
B_PERP3
B_PERN2
B_PERP2
B_PERN1
B_PERP1
B_PERN0
B_PERP0
RX : B_PER[15:8]
RX : B_PER[7:0]
1
SHEETDATE
23
7 3 2 16 5 4
E
A
B
C
E
D
C
B
A
7 6 5 4
D
DEPARTMENT
SIZE
PROJECT DOCUMENT NUMBER REV
REVIEWER
DESIGNER
IN
IN
IN
IN
C



P5E_CPU1_P3_RX_DP/DN<0-15> LANE REVERSAL
RETIMER TO CPU RETIMER TO CPU
Thu Aug 24 14:09:41 2023<NAME_2>
<NAME_1>
MB FABCGTI V02
350 OF 365
52
52
52
52
SMLF
IC
PT5161LRS
IC
SMLF
PT5161LRS
RETIMER_CPU1_P3(2)
P5E_CPU1_P3_RX_DP<15:8>
P5E_CPU1_P3_RX_DN<15:8>
P5E_CPU1_P3_RX_DP<7:0>
P5E_CPU1_P3_RX_DN<7:0>
EU26
EK26
EC26
DT26
DJ26
DB26
CR26
CH26
EW29
EM29
EE29
DV29
DL29
DD29
CU29
CK29
CA26
BP26
BG26
AY26
AN26
AF26
W26
M26
CC29
BT29
BJ29
BB29
AR29
AH29
AA29
P29
9
10
11
12
12
8
9
8
10
11
13
15
13
15
0
1
2
3
4
1
2
3
4
6
7
5
6
5
0
7
14
14
U6017
U6017
7/11
A_PETN15
A_PETP15
A_PETN14
A_PETP14
A_PETN13
A_PETP13
A_PETN12
A_PETP12
A_PETN11
A_PETP11
A_PETN10
A_PETP10
A_PETN9
A_PETP9
A_PETN8
A_PETP8
6/11
A_PETN7
A_PETP7
A_PETN6
A_PETP6
A_PETN5
A_PETP5
A_PETN4
A_PETP4
A_PETN3
A_PETP3
A_PETN2
A_PETP2
A_PETN1
A_PETP1
A_PETN0
A_PETP0
TX : A_PET[15:8]
TX : A_PET[7:0]
1
SHEETDATE
23
7 3 2 16 5 4
E
A
B
C
E
D
C
B
A
7 6 5 4
D
DEPARTMENT
SIZE
PROJECT DOCUMENT NUMBER REV
REVIEWER
DESIGNER
OUT
OUT
OUT
OUT
C



EXAMAX TO RETIMEREXAMAX TO RETIMER
P5E_CPU1_P3_RX_BUF_DP/DN<0-15> LANE REVERSAL
Thu Aug 24 14:09:41 2023<NAME_2>
<NAME_1>
MB FABCGTI V02
351 OF 365
119
119
120
120
IC IC
RETIMER_CPU1_P3(3)
PT5161LRS
SMLFSMLF
PT5161LRS
P5E_CPU1_P3_RX_BUF_DP<15:8>
P5E_CPU1_P3_RX_BUF_DN<15:8>
P5E_CPU1_P3_RX_BUF_DP<7:0>
P5E_CPU1_P3_RX_BUF_DN<7:0>
EY1
EN1
EF1
DW1
DM1
DE1
CV1
CL1
EV2
EL2
ED2
DU2
DK2
DC2
CT2
CJ2
CD1
BU1
BK1
BC1
AT1
AJ1
AB1
R1
CB2
BR2
BH2
BA2
AP2
AG2
Y2
N2
15
13
14
12
11
10
8
9
8
9
10
11
12
13
14
15
7
0
1
2
3
4
5
6
1
2
3
5
6
7
0
4
U6017U6017
2/11
A_PERN15
A_PERP15
A_PERN14
A_PERP14
A_PERN13
A_PERP13
A_PERN12
A_PERP12
A_PERN11
A_PERP11
A_PERN10
A_PERP10
A_PERN9
A_PERP9
A_PERN8
A_PERP8
1/11
A_PERN7
A_PERP7
A_PERN6
A_PERP6
A_PERN5
A_PERP5
A_PERN4
A_PERP4
A_PERN3
A_PERP3
A_PERN2
A_PERP2
A_PERN1
A_PERP1
A_PERN0
A_PERP0
RX : A_PER[15:8]
RX : A_PER[7:0]
1
SHEETDATE
23
7 3 2 16 5 4
E
A
B
C
E
D
C
B
A
7 6 5 4
D
DEPARTMENT
SIZE
PROJECT DOCUMENT NUMBER REV
REVIEWER
DESIGNER
IN
IN
IN
IN
C



RETIMER TO EXAMAXRETIMER TO EXAMAX
Thu Aug 24 14:09:42 2023<NAME_2>
<NAME_1>
MB FABCGTI V02
352 OF 365
353
353 120
120
353
353 119
119
353
353 353
353
P5E_CPU1_P3_TX_BUF_DN<7:0>
P5E_CPU1_P3_TX_BUF_DP<7:0> P5E_CPU1_P3_TX_BUF_C_DP<7:0>
P5E_CPU1_P3_TX_BUF_C_DN<7:0>
D IFF BU S_0.22U F
D IFF BU S_0.22U F
D IFF BU S_0.22U F
D IFF BU S_0.22U F
D IFF BU S_0.22U F
D IFF BU S_0.22U F
D IFF BU S_0.22U F
D IFF BU S_0.22U F
D IFF BU S_0.22U F
D IFF BU S_0.22U F
D IFF BU S_0.22U F
D IFF BU S_0.22U F
D IFF BU S_0.22U F
D IFF BU S_0.22U F
D IFF BU S_0.22U F
6.3V
X 6S
20%C0201
D IFF BU S_0.22U F
P5E_CPU1_P3_TX_BUF_DN<15:8>
P5E_CPU1_P3_TX_BUF_DP<15:8> P5E_CPU1_P3_TX_BUF_C_DP<15:8>
P5E_CPU1_P3_TX_BUF_C_DN<15:8>
D IFF BU S_0.22U F
D IFF BU S_0.22U F
D IFF BU S_0.22U F
D IFF BU S_0.22U F
D IFF BU S_0.22U F
D IFF BU S_0.22U F
D IFF BU S_0.22U F
D IFF BU S_0.22U F
D IFF BU S_0.22U F
D IFF BU S_0.22U F
D IFF BU S_0.22U F
D IFF BU S_0.22U F
D IFF BU S_0.22U F
D IFF BU S_0.22U F
D IFF BU S_0.22U F
6.3V
X 6S
C0201 20%
D IFF BU S_0.22U F
SMLF
PT5161LRS
IC
SMLF
PT5161LRS
IC
RETIMER_CPU1_P3(4)
P5E_CPU1_P3_TX_BUF_DN<15:8>
P5E_CPU1_P3_TX_BUF_DP<15:8> P5E_CPU1_P3_TX_BUF_DP<7:0>
P5E_CPU1_P3_TX_BUF_DN<7:0>
2 1
2 1
2 1
2 1
2 1
2 1
2 1
2 1
2 1
2 1
2 1
2 1
2 1
2 1
2 1
2 1
2 1
2 1
2 1
2 1
2 1
2 1
2 1
2 1
2 1
2 1
2 1
2 1
2 1
2 1
2 1
2 1
EU7
EK7
EC7
DT7
DJ7
DB7
CR7
CH7
EW10
EM10
EE10
DV10
DL10
DD10
CU10
CK10
CA7
BP7
BG7
AY7
AN7
AF7
W7
M7
CC10
BT10
BJ10
BB10
AR10
AH10
AA10
P10
7
6
7
5
4
3
1
2
6
5
4
3
2
7
6
5
4
3
2
0
0
1
0
1
7
6
5
4
3
2
1
0
15
14
15
14
11
13
12
13
12
11
10
9
10
9
8
8
15
14
15
14
13
12
11
13
12
11
10
9
10
9
8
8
15
8
9
10
11
12
13
14
8
9
10
11
12
13
14
15
7
6
5
4
3
2
1
0
0
1
2
3
4
6
7
5
U6017
C6741
C6742
C6743
C6744
C6745
C6746
C6747
C6748
C6749
C6750
C6751
C6752
C6753
C6754
C6755
C6756
C6725
C6726
U6017
C6727
C6729
C6728
C6730
C6732
C6731
C6733
C6734
C6735
C6736
C6737
C6740
C6739
C6738
10/11
B_PETN7
B_PETP7
B_PETN6
B_PETP6
B_PETN5
B_PETP5
B_PETN4
B_PETP4
B_PETN3
B_PETP3
B_PETN2
B_PETP2
B_PETN1
B_PETP1
B_PETN0
B_PETP0
11/11
B_PETN15
B_PETP15
B_PETN14
B_PETP14
B_PETN13
B_PETP13
B_PETN12
B_PETP12
B_PETN11
B_PETP11
B_PETN10
B_PETP10
B_PETN9
B_PETP9
B_PETN8
B_PETP8
TX : B_PET[7:0]
TX : B_PET[15:8]
2 1
2 1
2 1
2 1
2 1
2 1
2 1
2 1
2 1
2 1
2 1
2 1
2 1
2 1
2 1
2 1
2 1
2 1
2 1
2 1
2 1
2 1
2 1
2 1
2 1
2 1
2 1
2 1
2 1
2 1
2 1
2 1
1
SHEETDATE
23
7 3 2 16 5 4
E
A
B
C
E
D
C
B
A
7 6 5 4
D
DEPARTMENT
SIZE
PROJECT DOCUMENT NUMBER REV
REVIEWER
DESIGNER
OUT
OUT
IN
IN
OUT
OUT
IN
OUT
OUT
OUT
OUT
IN
C



CPU1 P1 RT ADDR: 0X48 (8-BIT) / 0X24 (7-BIT)
Thu Aug 24 14:09:53 2023<NAME_2>
<NAME_1>
MB FABCGTI V02
353 OF 365
P 1V 8_CP U1_RT_1D
P 1V 8_CP U1_RT_1D
P 1V 8_CP U1_RT_1D
P 1V 8_CP U1_RT_1DP 1V 8_CP U1_RT_1D
P 1V 8_CP U1_RT_1D
P 1V 8_CP U1_RT_1D0201LFCHIP1/20W
22 1%
SMB_RT_CPU1_P3_ROM_MUX_1D_SCL SMB_RT_CPU1_P3_ROM_MUX_1D_R_SCL
354
TEST0_RT_CPU1_P3354
SMB_RT_CPU1_P3_ROM_MUX_1D_SDA
CHIP
354
SMB_RT_CPU1_P3_ROM_MUX_1D_R_SDA
0201LF
1%1/20W49.9
185186
185186
354
354
184
354
354
354
354
354
354
354
354
354
354
354
354
354
354
354
354
354
183
81 354
81 354
184
183
354
354
354
81 354
81 354
354
354
354
354
354
354
354
CHIP
1/20W
200
1%
0201LF
CLKREQ_RT_CPU1_P3_N
JTAG_TCK_RT_CPU1_P3
RT_CPU1_P3_SCAN_MODE
CHIP
0201LF
5%
TEST2_RT_CPU1_P3
TEST1_RT_CPU1_P3
SMB_RT_CPU1_P3_R_SCL
RT_CPU1_P3_SCAN_MODE
0201LF
EMPTY
1/20W
GPIO3_RT_CPU1_P3
CHIP
1%
10K
1/20W
0201LF
1K
EMPTY
0201LF
1/20W
1%
RXDET_BYP_RT_CPU1_P3
GPIO2_RT_CPU1_P3
5%
SMLF
MODE_RT_CPU1_P3
JTAG_TEST_MODE_RT_CPU1_P3
TEST2_RT_CPU1_P3
TEST0_RT_CPU1_P3
GPIO3_RT_CPU1_P3
GPIO2_RT_CPU1_P3
TEST1_RT_CPU1_P3
PT5161LRS
RT_CPU1_P3_ADDR1
RT_CPU1_P3_ADDR2
RT_CPU1_P3_ADDR1
RT_CPU1_P3_ADDR2
RT_CPU1_P3_ADDR3
RT_CPU1_P3_ADDR3
CHIP 0201LF
CLK_100M_RETIMER_CPU1_P3_R_DN
5%0
0201LF
1%
1/20W
EMPTY
0201LF
IC
RETIMER_CPU1_P3(5)
51.151.1
1%
0201LF
EMPTY
1/20W
CLK_100M_RETIMER_CPU1_P3_DN
1/20W CHIP
CLK_100M_RETIMER_CPU1_P3_DP
RST_RT_CPU1_P3_PERST_R_N
RST_RT_CPU1_P3_RESET_R_N
SMB_RT_CPU1_P3_R2_SCL
SMB_RT_CPU1_P3_R_SDA SMB_RT_CPU1_P3_R2_SDA
5%
1/20W
4.7K
EMPTY
0201LF
CHIP
1/20W
0201LF
1%
10K
CHIP
1%
1/20W
10K
0201LF
EMPTY
1%
1K
0201LF
1/20W
1%
0201LF
1K
1/20W
CHIP
1%
1K
1/20W
EMPTY
0201LF
1%
CHIP
1/20W
0201LF
20K
1K
1%
1/20W
0201LF
CHIP
1K
1%
1/20W
0201LF
EMPTY
0
0
0201LF
CHIP
1/20W
5%
4.7K
4.7K
1/20W
0201LF
5%
EMPTY
4.7K
5%
EMPTY
1/20W
0201LF
5%
0201LF
EMPTY
1/20W
4.7K4.7K
5%
1/20W
0201LF
EMPTY
5%
CHIP
0201LF
4.7K
1/20W
5%
4.7K
0201LF
CHIP
1/20W
CHIP
1/20W
5%
0201LF
4.7K
1/20W CHIP 0201LF
0
4.7K
1/20W
EMPTY
0201LF
5%
4.7K
1/20W
EMPTY
0201LF
5%
4.7K
1/20W
CHIP
0201LF
5%
0201LF
1%
10K
CHIP
1/20W
0201LF
CHIP
1/20W
1%
10K
5%
4.7K
CLK_100M_RETIMER_CPU1_P3_R_DP
4.7K
1/20W
RXDET_BYP_RT_CPU1_P3
MODE_RT_CPU1_P3
JTAG_TCK_RT_CPU1_P3
RST_RT_CPU1_P3_RESET_R_N
RST_RT_CPU1_P3_PERST_R_N
0201LF
0201LF
4.7K
EMPTY
0201LF
1K
1/20W
1%
1/20W
5%
EMPTY
0201LF
EMPTY
0201LF
4.7K
1/20W
5%4.7K
5%
1/20W
0201LF
EMPTY
RST_RT_CPU1_P3_PERST_N
JTAG_TMS_RT_CPU1_P3
RST_RT_CPU1_P3_RESET_N
JTAG_TDI_RT_CPU1_P3
0201LF
0201LF
CHIP
JTAG_TEST_MODE_RT_CPU1_P3
JTAG_TRST_RT_CPU1_P3_N
JTAG_TDO_RT_CPU1_P3
JTAG_TMS_RT_CPU1_P3
JTAG_TDI_RT_CPU1_P3
1K CHIP
4.7K
JTAG_TDO_RT_CPU1_P3
R907R908
FF30
FF27
FF24
E30
B28
B31
B25
B23
F34
FF33
E11
FF11
FJ16
FF18
B16
E18
F2
FJ9
E8
B12
FF8
B9
B6
B3
FJ31
FJ28
FJ25
FJ23
FJ6
FJ3
FF5
G35
U6017
CLOCK
3/11
EE_DAT
EE_CLK
CLKREQ_N
TEST2
TEST1
TEST0
T_SENSE
SMBDAT
SMBCLK
SMB_ADDR3
SMB_ADDR2
SMB_ADDR1
SCAN_MODE
RXDET_BYP
RESET_N
REFCLKP
REFCLKN
REFCLK_OUTP
REFCLK_OUTN
PERST_N
MODE
JTAG_TRST_N
JTAG_TMS
JTAG_TEST_MODE
JTAG_TDO
JTAG_TDI
JTAG_TCK
INT_N
GPIO3
GPIO2
GPIO1
GPIO0
MISC JTAG
TESTEEPROM
SMBUS
GPIO
21R695
2
1
2
1
2
1
R1513
2
1
R1430
2
1
2
1
2
1
R1434
2
1
R1435
21R1429
21
2
1
R911
2
1
2
1
2
1
2
1
2
1
2
1
R906
2
1
R902
2
1
R903
21
21
2
1
R925
2
1
R926
2
1
R912
2
1
R922
2
1
R920
2
1
R924
2
1
R923
2
1
R921
2
1
21
21
21
21
21
2
1
2
1
R918
2
1
R915
2
1
R919
2
1
R917
2
1
R916
2
1
R909
1
SHEETDATE
23
7 3 2 16 5 4
E
A
B
C
E
D
C
B
A
7 6 5 4
D
DEPARTMENT
SIZE
PROJECT DOCUMENT NUMBER REV
REVIEWER
DESIGNER
IN
IN
OUT
OUT
OUT
IN
IN
IN
IN
IN
OUT
OUT
OUT
OUT
OUT
OUT
OUT
IN
IN
IN
IN
IN
IN
OUT
BI
IN
IN
IN
OUT
BI
IN
IN
IN
IN
IN
IN
OUT
OUT
OUT
OUT
IN
IN
R1512R1510 R1511
R910
R1433
R927
R949
R904
R901
R895
R642
R913
R914
R696
R621
R622
R641
C



Thu Aug 24 14:09:53 2023<NAME_2>
<NAME_1>
MB FABCGTI V02
354 OF 365
0201LF
P 1V 8_CP U1_RT3_1A _1D
P0V9_CPU1_RT3_2A_2D
P0V9_CPU1_RT3_2A
P 1V 8_CP U1_RT3_1A
P 1V 8_CP U1_RT_1D
P 0V 9_CP U1_RT_2D
CHIP
1/20W
200
1%
1/20W
0201LF
1%
1K
EMPTY
RT_CPU1_P3_VQPS
1/20W
0201LF
CHIP
5%
0
N C F_C PU 1_P3_GN D
N C F_A1_C PU 1_P3_GN D
RETIMER_CPU1_P3 POWER(6)
IC
PT5161LRS
SMLF
0
1/20W
5%
0201LF
CHIP
IC
PT5161LRS
SMLF
FH34
FH2
FG35
FG1
FE34
FE2
D35
D1
C34
C2
A35
A1
V35
V1
U34
U2
T4
T32
T22
T13
L35
L1
K34
K2
J4
J22
H31
H19
H16
H12
FJ19
FJ12
FF21
FF14
FD35
FD1
FC9
FC6
FC3
FC28
FC25
FC23
FC19
FB34
FB2
FA32
FA15
ET35
ET1
ER34
ER2
EP4
EP32
EP22
EP13
EJ35
EJ1
EH34
EH2
EG4
EG32
EG22
EG13
EB35
EB1
EA34
EA2
E33
E27
E14
DY4
DY32
DY22
DY13
DR35
DR1
DP34
DP2
DN4
DN32
DN22
DN13
DH35
DH1
DG34
DG2
DF4
DF32
DF22
DF13
DA35
DA1
CY34
CY2
CW4
CW32
CW22
CW13
CP35
CP1
CN34
CN2
CM4
CM32
CM22
CM13
CG35
CG1
CF34
CF2
CE4
CE32
CE22
CE13
BY35
BY1
BW34
BW2
BV4
BV32
BV22
BV13
BN35
BN1
BM34
BM2
BL4
BL32
BL22
BL13
BF35
BF1
BE34
BE2
BD4
BD32
BD22
BD13
B19
AW35
AW1
AV34
AV2
AU4
AU32
AU22
AU13
AM35
AM1
AL34
AL2
AK4
AK32
AK22
AK13
AE35
AE1
AD34
AD2
AC4
AC32
AC22
AC13
G1
CW20
CW17
BL20
BL17
T20
T17
EP20
EP17
EG20
EG17
DY20
DY17
DN20
DN17
DF20
DF17
BD20
BD17
AU20
AU17
AK20
AK17
AC20
AC17
BV17
CM20
CM17
CE20
CE17
BV20
U6017
U6017
4/11
PWR_2A_20
PWR_2A_19
PWR_2A_18
PWR_2A_17
PWR_2A_16
PWR_2A_15
PWR_2A_14
PWR_2A_13
PWR_2A_12
PWR_2A_11
PWR_2A_10
PWR_2A_9
PWR_2A_8
PWR_2A_7
PWR_2A_6
PWR_2A_5
PWR_2A_4
PWR_2A_3
PWR_2A_2
PWR_2A_1
PWR_1D
PWR_2D_4
PWR_2D_3
PWR_2D_2
PWR_2D_1
PWR_1A_5
PWR_1A_4
PWR_1A_3
PWR_1A_2
PWR_1A_1
VQPS
5/11
GND151
GND150
GND149
GND148
GND147
GND146
GND145
GND144
GND143
GND142
GND141
GND140
GND139
GND138
GND137
GND136
GND135
GND134
GND133
GND132
GND131
GND130
GND129
GND128
GND127
GND126
GND125
GND124
GND123
GND122
GND121
GND120
GND119
GND118
GND117
GND116
GND115
GND114
GND113
GND112
GND111
GND110
GND109
GND108
GND107
GND106
GND105
GND104
GND103
GND102
GND101
GND100
GND99
GND98
GND97
GND96
GND95
GND94
GND93
GND92
GND91
GND90
GND89
GND88
GND87
GND86
GND85
GND84
GND83
NCF_GND12
NCF_GND11
NCF_GND10
NCF_GND9
NCF_GND8
NCF_GND7
NCF_GND6
NCF_GND5
NCF_GND4
NCF_GND3
NCF_GND2
NCF_GND1
GND82
GND81
GND80
GND79
GND78
GND77
GND76
GND75
GND74
GND73
GND72
GND71
GND70
GND69
GND68
GND67
GND66
GND65
GND64
GND63
GND62
GND61
GND60
GND59
GND58
GND57
GND56
GND55
GND54
GND53
GND52
GND51
GND50
GND49
GND48
GND47
GND46
GND45
GND44
GND43
GND42
GND41
GND40
GND39
GND38
GND37
GND36
GND35
GND34
GND33
GND32
GND31
GND30
GND29
GND28
GND27
GND26
GND25
GND24
GND23
GND22
GND21
GND20
GND19
GND18
GND17
GND16
GND15
GND14
GND13
GND12
GND11
GND10
GND9
GND8
GND7
GND6
GND5
GND4
GND3
GND2
GND1
0.9V 0.9V
1.8V
/1.8V
1.2V / 1.5V
2
1
R6900
2
1
2
1
2
1
1
SHEETDATE
23
7 3 2 16 5 4
E
A
B
C
E
D
C
B
A
7 6 5 4
D
DEPARTMENT
SIZE
PROJECT DOCUMENT NUMBER REV
REVIEWER
DESIGNER
R6901
R6902
R6903
C



RETIMER EEPRO ADDRESS: 0XA0 (8 BIT) / 0X50 (7 BIT)
Thu Aug 24 14:09:46 2023<NAME_2>
<NAME_1>
MB FABCGTI V02
355 OF 365
P 1V 8_CP U1_RT_1D
1/20W
0 5%
0201LFCHIP
SMB_RT_CPU1_P3_ROM_R_SCL SMB_RT_CPU1_P3_ROM_SCL
1/20W
CHIP
10V
X 7S M24M02-DRMN6TP
U21_E2
SMLF10%
1/20W
1%
1K
CHIP
RETIMER_CPU1_P3(7)
IC
0.1UF
0201LF
186 185
186 185
0201LF
1%
SMB_RT_CPU1_P3_ROM_SDA
C0201
33.2
SMB_RT_CPU1_P3_ROM_R_SDA
7
4
8
5
6 3
2
1
U21
DU1
DU2
E2
VSSSDA
SCL
WC_N
VCC
21R697
2
1
2
1 C7504
21
1
SHEETDATE
23
7 3 2 16 5 4
E
A
B
C
E
D
C
B
A
7 6 5 4
D
DEPARTMENT
SIZE
PROJECT DOCUMENT NUMBER REV
REVIEWER
DESIGNER
BI
IN R6791R698
C



Thu Aug 24 14:09:53 2023<NAME_2>
<NAME_1>
MB FABCGTI V02
356 OF 365
P0V9_CPU1_RT3_2A_2D
P 1V 8_CP U1_RT3_1A _1D
P 1V 8_CP U1_RT_1D
P 1V 8_CP U1_RT3_1A
P0V9_CPU1_RT_2D
P0V9_CPU1_RT3_2A
100UF
4V
20%
C0805
X 6S
X 6S
100UF
C0805
4V
20%
X 6S
20%
C0805
4V
100UF
X 6S
4V
100UF
20%
C0805
100UF
4V
X 6S
20%
C0805
X 6S
20%
4V
C0805
100UF
4V
100UF
C0805
X 6S
20%
C0402
22UF
4.7UF
4V
0201
10%
X7S
10V 10V
20% 20%
2.5V
S P CA P
X7SX7S
10%
10V 10V
470UF
2.5V
S P CA P
S MLFX7S
10% 10%
0.1UF
4V
0201
X 6S
20%
4V
1UF
20%
X 6S
0201
X7S
C0201C0201
X7S
10%
10V
X7S
0.1UF
20%
0201
20% 20%
X 6S
4V 4V 4V 4V
10%
1UF
20%
0201
20%
20%
X 6S
6.3V
10UF
4V
C0402 C0402
20%
X 6S
20%
22UF
20%
6.3V
X 6S
C0402
22UF22UF
20%
C0201
0.1UF0.1UF0.1UF
10V 10V 10V
10%
X7S
10%
X7S
C0201
X7S
4.7UF
20%
X 6S
0402
22UF
4V
X 6S
C02010402
20%
4V
10%
IND
4V
10%
X7S
C0201
4V
IND
SMLF
C0201
0402
1UF
20%
4V
X 6S
X7S
X 6S
0201
1UF
20%
X 6S
X7S
C0201
X7S
C0201
C0402C0402
20%
X 6S
4V
X 6S
0201
10%
10V
X7S
C0201
0 5%
CHIP1/4W
0.1UF
10%
10V
0.1UF
10V
X7S
10%
0.1UF
10V
X7S
10%
10V
X7S
10%
X7S
0201
X 6S
4.7UF
0402
X 6S
20%
X 6S
0201
6.3V
20%
X 6S
4.7UF
X 6S
C0402
20%
6.3V
10UF
4V
20%
X 6S
22UF
5%
0
0603LF
EMPTY
1/4W
0201
X 6S
20%
4V
5%
0
EMPTY
0
EMPTY
5%
0.1UF
10V
X7S
C0201
RETIMER_CPU1_P3 DECAPS(8)
R705 AND R712 COLAY
X 6S
EMPTY
0402LF
5%
1/16W
0
SMLF
BLM15PD121SN1D/1300MA 0402LF
1/16W
0402LF
1/16W
L33/R897 COLAY WITH R893/R894
IND
SMLF
BLM21SN300SN1D/5A
X 6S
6.3V
4V
10UF
6.3V
20%
C0402
22UF
0.1UF
10V
0.1UF
C0402
20%
10%
1UF
C0201C0201C0201
4V
1UF1UF
20%
C0402
X 6S
10UF
6.3V
20%
C0402
20%
6.3V
C0201
10%
0201
C0201
1UF
4V
X 6S
20%
0201
X 6S
20%
4V
1UF
0.1UF
10V
100NH/16A
4V
X 6S
20%
X 6S
10UF
C0402
X 6S X 6S
10UF
C0402
X 6S
20%
X 6S
C0402
20%
1UF
0603LF
0402
20%
0201
0.1UF
X 6S
1UF
10V
4.7UF 1UF 1UF 1UF
0201
4.7UF 4.7UF
6.3V
20%
X 6S X 6S
0201
20%
X 6S
0201
1UF
4V4V
0.1UF
10V
10% 10%
10V
0.1UF 0.1UF 0.1UF0.1UF
C0201
X7S
C0201
0201
1UF
C0201
10%
10V
0.1UF
10%
6.3V
0.1UF1UF
6.3V 6.3V 6.3V
20%
6.3V
20%
X 6S
04020402
X 6S
20%
10UF
10V4V
X 6S
C0201
C0201
470UF
S MLF
20%
X6S
C0805
4V
100UF
0.1UF
C434
C7031
C439C436
C438
C432
C435C433
C441
2121
2 1
L10L9
CAD NOTE:
CAD NOTE:
1 21 2
L33
12
2
1
2
1 C7030
2
1 C7029
2
1
2
1
2
1
2
1
2
1
R897
2
1
2
1
2
1
2
1
2
1
2
1
2
1
2
1
2
1
2
1
2
1
2
1
2
1
2
1
2
1
2
1
2
1
2
1
2
1
2
1
2
1
2
1
2
1
2
1
2
1
2
1
2
1
2
1
2
1
2
1
2
1
2
1
2
1
2
1
2
1
2
1
2
1
2
1
2
1
2
1
2
1
2
1
2
1
2
1
21
2
1
2
1
2
1
2
1
2
1
2
1
2
1 C442
2
1
2
1
2
1 C440
2
1
2
1
2
1
2
1 C437
2
1
2
1
2
1
2
1
2
1
21R893
21R894
1
SHEETDATE
23
7 3 2 16 5 4
E
A
B
C
E
D
C
B
A
7 6 5 4
D
DEPARTMENT
SIZE
PROJECT DOCUMENT NUMBER REV
REVIEWER
DESIGNER
C498C496
C460C456
C479
C483
C486
C452
C462
C458C493C451C449
C482C499C487
C454C484C489
C476C501C475
C478C474
C471C466
C455C497
C457C481
C492
C491C494C469C472
C488C485
C450C477
C453C448
C473C500
C490C480
C459C470
C495
R900
C464C463
C447C446C445C443
R898
C444
C



0X46 (7-BIT)
ADDRESS : 0X8E (8-BIT)
0X48 (7-BIT)
ADDRESS : 0X90 (8-BIT)
0X47 (7-BIT)
ADDRESS : 0X8C (8-BIT)
Thu Aug 24 14:09:58 2023<NAME_2>
<NAME_1>
MB FABCGTI V02
357 OF 365
P12V_OCP_V3_2_R
P12V_OCP_SFF_R P12V_OCP_SFF
P3V3_AUX
P3V3_AUX
P3V3_AUX
P3V3_AUX
P3V3_AUX
P3V3_AUX
P3V3_AUX
P12V_E1S_0_R P12V_E1S_0
P12V_OCP_V3_2
P12V_OCP_SFF
P3V3_AUX
P3V3_AUX
P12V_E1S_0
P12V_OCP_V3_2
237 82
252
252
252
238
82
252
252
252
237 82
POWER MONITOR WILL CHANGE TO AL000230001
25V
10%
0402LF
1/16W
5%
0
CHIP
0
5%
CHIP
1/16W
0402LF
0
5%
CHIP
0402LF
1/16W
NC_INA230_6_NC2
P12V_OCP_V3_2_ADC_ALERT_R
NC_INA230_7_NC1
NC_INA230_7_NC3
E1S_0_P3V3_P12V_ADC_R_ALERTCHIP4.7K
4.7K
0402LF
1/16W
0402LF
SMB_IN A230_8_3V3AU X_SC L_R 1
SMB_IN A230_8_3V3AU X_SD A_R 1
4.7K
1/16W
0402LF
1/16W
5%0
SMB_INA230_7_3V3AUX_SDA_R
1/16W
4.7K
1/16W
SMB_INA230_6_3V3AUX_SDA_R
SMB_INA230_6_3V3AUX_SCL_R
2512LF
CHIP
0402LF
0402LF
CHIP
CHIP
0402LF
X7R
25V
0.1UF
X7R
1%
1%4.7K E MP TY
1%
CHIP
4.7K
0402LF
1% E MP TY0402LF4.7K 1/16W
4.7K E MP TY1/16W 1%
1%
IC
10%
CHIP
1%
CHIP
0402
0.1UF
P12V_E1S_0_ADC_ALERT_R
0402LF
EMPTY
1/16W
1%
1K
1K
1%
1/16W
OCP_V3_2_P3V3_P12V_ADC_R_ALERT
0402LF
EMPTY
0402LF
1%
1K
P12V_OCP_SFF_ADC_ALERT_R 0402LFCHIP0
0402LFCHIP
NC_INA230_8_NC1
NC_INA230_8_NC2
NC_INA230_8_NC3
NC_INA230_8_NC4
NC_INA230_8_NC0
NC_INA230_6_NC3
NC_INA230_6_NC5
NC_INA230_6_NC4
10
0.1UF
0.002 2512LF
10 1%
0.1UF
X7R
0402
CHIP
CHIP
CHIP
2512LF
2W
0.002 1%
0402
10%
25V
X7R
1%
CHIP1/16W
10 0402LF
1% 0402LF10
1/16W CHIP
1/16W
0 CHIP5%
CHIP0 5%
0402
25V
0.1UF
10%
X 7R
0
IC
10
0.1UF
10%
X 7R
0402
1%0.002
2W
0.1UF
25V
10%
10
1/16W
1%
5%0
10%
25V
CHIP0
IC
0402LF
5% CHIP
25V
0402
X 7R
10%
25V
5%
0402LF
1/16W
0402
X7R
0.1UF
2W
1%
POWER MONITOR (4/4)
NC_INA230_8_NC5
SMB_INA230_8_3V3AUX_SDA_R
SMB_INA230_8_3V3AUX_SCL_R
V S E NS E _P 12V _INA 230_7_INN
V S E NS E _P 12V _INA 230_7_INP
NC_INA230_6_NC0
V S E NS E _P 12V _INA 230_8_INP
V S E NS E _P 12V _INA 230_8_INN
0402LF
EMPTY
1/16W
1/16W
CHIP
0
4.7K
1/16W
0402LF
0
0402LF
1/16W
1/16W E MP TY
1%
0402LF
CHIP
1/16W
0402LF
E MP TY1%
E MP TY
1%
SMB_INA230_7_3V3AUX_SCL_R
0402LF
0402
INA230_6_A1
INA230_6_A0
SMB_IN A230_6_3V3AU X_SC L_R 1
SMB_IN A230_6_3V3AU X_SD A_R 1
V S E NS E _P 12V _INA 230_6_INP
V S E NS E _P 12V _INA 230_6_INN
CHIP
ISL28022FRZ-T
SMLF0.1UF
INA230_7_A1
INA230_7_A0
SMB_IN A230_7_3V3AU X_SC L_R 1
SMB_IN A230_7_3V3AU X_SD A_R 1
25V
10%
SMLF
ISL28022FRZ-T
INA230_8_A1
0402
INA230_8_A00402LF
X7R
ISL28022FRZ-T
SMLF
OCP_SFF_P3V3_P12V_ADC_R_ALERT
NC_INA230_6_NC1
NC_INA230_7_NC5
NC_INA230_7_NC4
NC_INA230_7_NC2
NC_INA230_7_NC0
R1308
R1350
R1360
R1269
R1271
R1270
R1317
R1355
R1292
R1283
R1305
R1302
R1310
R1307
R1291
R1309
R1306
R1301
R1284
13
12
9
11
TH
4
5
16
15
14
8
7
6
10
3
1
2
13
12
9
11
TH
4
5
16
15
14
8
7
6
10
3
1
2
13
12
9
11
TH
4
5
16
15
14
8
7
6
10
3
1
2
U52
U56
U55
BOM NOTE:
TH_GND
GND
NC5
NC4
NC3
NC2
NC1
NC0
EXT_CLK||INT
VINM
VINP
VBUS
SDA||SMBDAT
SCL|||SMBCLK
A0
A1
VCC
TH_GND
GND
NC5
NC4
NC3
NC2
NC1
NC0
EXT_CLK||INT
VINM
VINP
VBUS
SDA||SMBDAT
SCL|||SMBCLK
A0
A1
VCC
TH_GND
GND
NC5
NC4
NC3
NC2
NC1
NC0
EXT_CLK||INT
VINM
VINP
VBUS
SDA||SMBDAT
SCL|||SMBCLK
A0
A1
VCC
21
2
1
2
1
2
1
2
1
2
1
2
1
2
1
21
2
1
21
21
21
21R1272
21R1275
2
1
2
1
21
21 2
1
21
2
1 21
21
21
21R1274 21R1277
2
1
2
1
21
21R1273
21
2
1
2
1
2
1
21R1276
21
21
21
21
2
1
21
1
SHEETDATE
23
7 3 2 16 5 4
E
A
B
C
E
D
C
B
A
7 6 5 4
D
DEPARTMENT
SIZE
PROJECT DOCUMENT NUMBER REV
REVIEWER
DESIGNER
BI
IN
BI
OUT
IN
BI
IN
OUT
OUT
R1326
R1328
R1327
R1323
C1107
C1110
C1096
C1112
R1325
C1109
R1322 C1106
C1097R1320
C1111
C1108
R1324
C



0 0
1
ID0ID1
1
ASTERA_LABS
BOARD ID(RT)
PARADE
RENESAS
0 1
RSVD 1
0
Thu Aug 24 14:09:51 2023<NAME_2>
<NAME_1>
MB FABCGTI V02
358 OF 365
P 1V 8_A UX
82
82
1/16W
CHIP
0402LF
EMPTY
0402LF 0402LF
RT_BOARD_ID_ID1
RT_BOARD_ID_ID0
1K
1%
1%
1/16W
EMPTY
1/16W
1%
1/16W
CHIP
1K
BOARD ID (RETIMER)
1%
1K
1K
0402LF
2
1
2
1
2
1
2
1
1
SHEETDATE
23
7 3 2 16 5 4
E
A
B
C
E
D
C
B
A
7 6 5 4
D
DEPARTMENT
SIZE
PROJECT DOCUMENT NUMBER REV
REVIEWER
DESIGNER
OUT
OUT
R6743R6742
R6745R6744
C



Thu Aug 24 10:17:15 2023<NAME_2>
<NAME_1>
MB FABCGTI V02
359 OF 365Blank
1
SHEETDATE
23
7 3 2 16 5 4
E
A
B
C
E
D
C
B
A
7 6 5 4
D
DEPARTMENT
SIZE
PROJECT DOCUMENT NUMBER REV
REVIEWER
DESIGNER
C



2ND AL053319002 / RS53319LR / REEDSEMI
BOM NOTE
1ST AL008633005 / MPQ8633BGLE-C838-Z/ MPS
BOM CHANGE R&C TABLE
WORK FREQUENCY=600KHZ
SLEW RATE=1A/US
LOAD STEP=7.2A
OCP=17.52A (IOUT MAX*1.2)
IOUT MAX=15.72A
AC + DC =1.710-1.890
OUTPUT VOLTAGE=1.8V +/- 5%
IOUT TDC=14.6A
EFFICIENCY > 90% @TDC
3RD=CV+10G0MZ08
PG2289.101HLT
ISAT:13A@100C
2ND=CC7390JMZ11
E S R=10M O HM
5.0*5.8
RB
PCMC135T-1R0MF
13*13*5.0
SPECFICATION
FSW=600KHZ
DCR:0.105M OHM
2ND=CV+10G0MZ12
4.5*4.7*4.5
FCCM
VOUT=0.6(1+RA/RB)=1.8V
RA
DCR=2.5M OHM
P1V8_CPU0_RT_1D
2ND=CV-10^0MZ03
ISAT:47A@100C
Thu Aug 24 14:09:47 2023<NAME_2>
<NAME_1>
MB FABCGTI V02
360 OF 365
P 3V 3_A UX
P 12V _A UX
P 1V 8_CP U0_RT_1D
P 3V 3_A UX
C0402
X 6S
P 1V 8_RE TIME R_CP U0_CS
0.22UF
33
22UF
16V
22UF
X 6S
20%
SMLF
P 1V 8_RE TIME R_CP U0_MO DE
0402LF
5%
X 6S
20%
16V
P 1V 8_RE TIME R_CP U0_E N
MP Q 8633B G LE -C838-Z
X 6S
22UF
C0805 C0805 C0805
20% 20% 20%
1/16W
C0805 C0805
22UF 22UF
16V
X 6S
16V16V
16V
O S CO N X 6S
S MLF
270UF
20%
0402LF
P W RG D_P 1V 8_RE TIME R_CP U0
S MLF
1UH
20%
X 6S
C0805
1/16W
P 1V 8_RE TIME R_CP U0_FB
0.1UF
X 7R
5%
X7R
0402
C0805
X 6S
C0805
X 6S
20% 20% 20%
X 6S
C0805
22UF
P1V8_CPU0_RT_1D
CHIP
0402
20K
NP O
C0402
CHIP
4V
22UF22UF
CHIP
22UF
X 6S
20%
P 1V 8_RE TIME R_CP U0_V CC
25V
IND
FM_P W RG D_P 1V 8_RE TIME R_CP U0
P 1V 8_RE TIME R_CP U0_RE F
4V
S MLF
100NH/16A
0
5%
7.15K
0402LF
1/16W
1%
0402
0.1UF
10K
5%
0402LF2.2
0402LF
CHIP
1%
10K
50V
0402
IND
4V
1000PF
50V
2.5V
0.1UF
10%
IC
0
10%
1/16W
1/16W
CHIP
0402LF
CHIP
X 7R
10%
25V
C0805
X 6S
150P F
SW_P1V8_RETIMER_CPU0_BST_R
0402LF
S W _P 1V 8_RE TIME R_CP U0_S W
S W _P 1V 8_RE TIME R_CP U0_B S T
4V 20%
A LUM
390UF
2.5V
25V
A LUM
20%
390UF
S MLF
5%
4V
S MLF
22UF
CHIP
22UF
16V
X 6S
C0805
20%
22UF22UF
16V
20%
X 6S
C0805
16V
20%
X 6S
C0805
S W _P 12V _A UX _P 1V 8_RE TIME R_CP U0_FLT
25V
1UF
10%
0402
10%
25V
E MP TY
0.1UF
0402
16V
10%
X 7R
X 6S
10%
C0402
1UF
25V
80
81
PC6900 PC6901 PC6902
PC6512
21
10
19
5
20
6
9
11_18
4
7
8
3
1
2
PU6500
2
1 PC6514PC6805
2
1 PC6513
2
1 PC6511
2
1 PC6510
2
1 PC6509
2
1 PC6508
21 R6506
21
PL6501
21
PR6505
21
PC6515
2
1
PR6507
2
1
PC6507
PR6800
2
1
R6505
2
1 PC6518
2
1 PC6505
2
1 PC6504
21
PR6500
2
1
PR6502
2
1 PC6503
2
1 PC6502
2
1 PC6501
2
1
PR6501
2
1
PC6506
PL6500
PC6802
2
1C6757
PC6500
C6758
21 1 2
VIN2
CS
MODE
TRK_REF
SW
RGND
VCC
AGND
FB
BST
EN
PGND
PGOODVIN1
1 2
2
1
2
1
2
1
2
1
2
1
2
1
21
2
1
2
1PC6800
2
1
1
SHEETDATE
23
7 3 2 16 5 4
E
A
B
C
E
D
C
B
A
7 6 5 4
D
DEPARTMENT
SIZE
PROJECT DOCUMENT NUMBER REV
REVIEWER
DESIGNER
OUT
IN
C



BOM NOTE
1ST AL008633005 / MPQ8633BGLE-C838-Z/ MPS
2ND AL053319002 / RS53319LR / REEDSEMI
SPECFICATION
IOUT MAX=15.72A
LOAD STEP=7.2A
EFFICIENCY > 90% @TDC
SLEW RATE=1A/US
WORK FREQUENCY=600KHZ
OCP=17.52A (IOUT MAX*1.2)
IOUT TDC=14.6A
AC + DC =1.710-1.890
OUTPUT VOLTAGE=1.8V +/- 5%
3RD=CV+10G0MZ08
2ND=CV+10G0MZ12
DCR:0.105M OHM
4.5*4.7*4.5
ISAT:13A@100C
E S R=10M O HM
2ND=CC7390JMZ11
5.0*5.8
PCMC135T-1R0MF
RA
13*13*5.0
DCR=2.5M OHM
VOUT=0.6(1+RA/RB)=1.8V
FSW=600KHZ
BOM CHANGE R&C TABLE
PG2289.101HLT
FCCM
ISAT:47A@100C
RB
2ND=CV-10^0MZ03
P1V8_CPU1_RT_1D
Thu Aug 24 14:09:47 2023<NAME_2>
<NAME_1>
MB FABCGTI V02
361 OF 365
P 3V 3_A UX
P 3V 3_A UX
P 12V _A UX
P 1V 8_CP U1_RT_1D
1/16W
S W _P 1V 8_RE TIME R_CP U1_S W
S W _P 1V 8_RE TIME R_CP U1_B S T
P 1V 8_RE TIME R_CP U1_E N
C0805
X 6S
C0805
X 6S
20%
270UF
20%
X 6S
IND
16V
C0805
X 6S
16V
22UF 22UF
16V
X 6S
C0805
O S CO N
20%
16V
2.5V
20%
390UF22UF
4V
22UF
C0805
20%
4V
20%
C0805
X 6S X 6S
20% 25V
0.1UF
A LUM
22UF
A LUM
390UF
2.5V
0402
S MLF
22UF
4V
C0805
0402LF
SW _P1V8_RETIMER_CPU1_BST_R
P 1V 8_RE TIME R_CP U1_CS
10K
50V
C0805
20%
22UF
0402LF
P 1V 8_RE TIME R_CP U1_V CC
P 1V 8_RE TIME R_CP U1_MO DE
P 1V 8_RE TIME R_CP U1_RE F
P 1V 8_RE TIME R_CP U1_FB
P W RG D_P 1V 8_RE TIME R_CP U1 FM_P W RG D_P 1V 8_RE TIME R_CP U110%
25V
C0402
S MLF
100NH/16A
0402LF
1/16W
5%
0
CHIP
0402LF
CHIP
1%
7.15K
1/16W
0402LF
5%
10%
X 7R
25V
0402
0.1UF
2.2
10K
5%
1/16W
CHIP
1%
1/16W
CHIP
0402LF
0402
150P F
5%
NP O
0402LF
20K CHIP
S MLF
IND
1UH
X 6S
20%
4V
0402
5%
1000PF
X7R
50V
C0805
X 6S X 6S
4V
20%
S MLF
10%
X 7R
IC
0.1UF
CHIP
P1V8_CPU1_RT_1D
CHIP
22UF
X 6S
20%20%
S MLF
C0805
22UF
16V
22UF
16V
0
SMLF
MP Q 8633B G LE -C838-Z
C0805
X 6S
16V
22UF
20%
C0805
X 6S
20%
22UF
16V
22UF
16V
20%
X 6S
C0805
20%
S W _P 12V _A UX _P 1V 8_RE TIME R_CP U1_FLT
25V
10%
X 6S
C0402
1UF
0.1UF
25V
10%
E MP TY
0402
10%
25V
X 6S
1UF
C0402
0.22UF
0402
16V
X 7R
10%
33
80
81
PC6903 PC6904 PC6905
21
10
19
5
20
6
9
11_18
4
7
8
3
1
2
PU6501
2
1 PC6533PC6804
2
1 PC6532
2
1 PC6531
2
1 PC6530
2
1 PC6529
2
1 PC6528
2
1 PC6527
21
PL6502
21 R645
2
1
PC6526
21
PR6524
21
PC6534
2
1
PR6526
2
1
R644
PR6801
2
1 PC6537
2
1 PC6524
2
1 PC6523
21
PR6520
2
1
PR6522
2
1 PC6522
2
1 PC6521
2
1 PC6520
2
1
PR6521
2
1
PC6525
PL6503
PC6803
2
1C105
PC6519
C109
21 1 2
VIN2
CS
MODE
TRK_REF
SW
RGND
VCC
AGND
FB
BST
EN
PGND
PGOODVIN1
1 2
2
1
2
1
2
1
2
1
2
1
21
2
1
2
1PC6801
2
1
1
SHEETDATE
23
7 3 2 16 5 4
E
A
B
C
E
D
C
B
A
7 6 5 4
D
DEPARTMENT
SIZE
PROJECT DOCUMENT NUMBER REV
REVIEWER
DESIGNER
OUT
IN
C



PC6606 = CH4106K1B01
PC6607 = CH11006JB00
PC6601 = CH3104J1B00
PC6540 = CH12206KB14
PR6604 = CS25362FB02
PMBUS ADDRESS AND CONFIG
SVID:UNUSED
DESIGN SPECIFICATION
VR ADDRESS(7-BIT)
LOCAL SENSE
TRACE WIDTH = 10MIL
DIFFERENTIAL PAIR
REMOTE SENSE
TRACE SPACING = 5MIL
OUTPUT VOLTAGE = 0.86V - 0.945V
TRANSIENT TOLERANCE = 90MV
OUTPUT RIPPLE & NOISE < 46MV
TDC = 54.8A
MAX CURRENT = 57.6A
OVER-CURRENT PROTECTION= 92A
EFFICIENCY > 85% @TDC
WORK FREQUENCY = 600KHZ
SLEW RATE = 2.5A/US
CURRENT STEP = 22A
UNUSED
RENESAS
INFENEON
0/00X60
0X60 /17.4K
CONFIG/R
2023/3/28 MODIFY
BOM NOTE
MAIN SOURCE: RENESAS BOM
PU6502 = TBD / ISL69260IRAZ-T
PR6603 = CS31742FB04
PR6531 = CS01002FB07
PR6609,PR6610,PR6611,PR6612,PR6613,PR6614 = EMPTY
PR6810,PR6819,R6801,PR6618 = EMPTY
PR6803,PR6805,PR6817,PR6605 = CS21002FB06
PU6502 = TBD / XDPE15284D-0000
2ND SOURCE: INFENEON BOM
Thu Aug 24 14:09:48 2023<NAME_2>
<NAME_1>
MB FABCGTI V02
362 OF 365
P0V9_CPU0_RT_2D P0V9_CPU0_RT_2D
P1V8_AUX P3V3_AUX
P5V_AUX
P3V3_AUX
P3V3_AUX
P12V_AUX
P3V3_AUX
P3V3_AUX
10%
X 7R
PV09_RETIMER_CPU0_VCCS
1UF
16V
ISL69260IRAZ-T
040250V
1/16W
NC_P0V9_RETIMER_CPU0_PWM8
P0V9_CPU0_RT_2D_VR_CONTROLLER
NC_P0V9_RETIMER_CPU0_PG1
NC_P0V9_RETIMER_CPU0_IMON5
NC_P0V9_RETIMER_CPU0_PWM5
NC_P0V9_RETIMER_CPU0_PWM4
1/16W
NC_P0V9_RETIMER_CPU0_IMON3
P0V9_RETIMER_CPU0_IMON2
P0V9_RETIMER_CPU0_PWM2
P0V9_RETIMER_CPU0_EN0_R
P0V9_RETIMER_CPU0_SVID_SDA
P0V9_RETIMER_CPU0_SENSE_R_P
SMLF
IC
P0V9_RETIMER_CPU0_IMON1
P0V9_RETIMER_CPU0_VCC
P0V9_RETIMER_CPU0_EN1_R
P0V9_RETIMER_CPU0_PMSCL_R
TP_P0V9_RETIMER_CPU0_SVID_ALERT_N
P0V9_RETIMER_CPU0_VRHOT
NC_P0V9_RETIMER_CPU0_IMON4
P0V9_RETIMER_CPU0_SVID_CLK
TP_P0V9_RETIMER_CPU0_PMALERT
P0V9_RETIMER_CPU0_PMSDA_R
NC_P0V9_RETIMER_CPU0_PWM3
NC_P0V9_RETIMER_CPU0_PWM7
PWRGD_P0V9_RETIMER_CPU0_R
P0V9_RETIMER_CPU0_VMON
P0V9_RETIMER_CPU0_TEMP1_R
P0V9_RETIMER_CPU0_INALERT
NC_P0V9_RETIMER_CPU0_IMON7
P0V9_RETIMER_CPU0_PWM1
NC_P0V9_RETIMER_CPU0_PWM6
NC_P0V9_RETIMER_CPU0_IMON6
P0V9_RETIMER_CPU0_CFP
P0V9_RETIMER_CPU0_ADDR
P0V9_RETIMER_CPU0_TEMP0
NC_P0V9_RETIMER_CPU0_IMON8
CHIP
20%
CHIP
6.3V
364
1/16W
81
364
364
364
151
151
81
SM
0402LF
SM
EMPTY
P0V9_RETIMER_CPU0_SENSE_SH_N
EMPTY
P0V9_RETIMER_CPU0_SENSE_SH_P
1/16W
1/16W
1/16W
PWRGD_P0V9_RETIMER_CPU0
CHIP 0402LF
5%0
1%1K
CHIP 0402LF
1K
0402LF1/16WE MP TY
1%
0
0402LF1/16W
E MP TY
5%
0402LF
5%
1/16W
0
1K
1000P F
1/16W
1/16W
1%
1/16W
CHIPCHIP
0402LF
CHIP
1/16W
1K
1%
CHIP
5%0
CHIP 1/16W
0
5%
0 5%
CHIP
0 5%
CHIP 1/16W
0 5%
1/16WCHIP
0 5%
1/16WCHIP
0 5%
1/16W
0
E MP TY
10%
50V
0402
X 7R
25V
0402
1K
1%
1/16W
0402LF
E MP TY
1K
1%
0402LF
CHIP
1
1/16W
X 6S
10%
16V
1UF
1/16W
CHIP
1%
0402LF
1K
CHIP
5%
1%
10K
0402LF
50V
100NF
C0402
X 6S
10UF
C0402
10%
X 6S
C0402
50V
10%
CHIP
1/16W
5%
0
25V
0.1UF
10%
0402
0
CHIP
0402LFE MP TY
1%
0
1%
CHIP
0402LF49.9 1%
0
TP_P0V9_RETIMER_CPU0_VRHOT
5%
5%
3300P F
5%
0 5%
0402LF
1/16W
0
0
E MP TY
1/16W
470P F
0402
X 7R
1/16WCHIP
5%
1K
CHIP
1%49.9
4.7K
0 5%
5%
5.36K
5%
EMPTY
0 P0V9_RETIMER_CPU0_VINSEN
1%
0402LF
1/16W
1/16W
0
1%
5%
0402LF
5%
0402LF
0.1UF
10%
X 7RE MP TY
0402LF
C0402
E MP TY
CHIP
1/16W
1%
1K
P0V9_RETIMER_CPU0_PMSDA
0402LF
E MP TY
1%1K
E MP TY
E MP TY
P0V9_RETIMER_CPU0_PMSCL
P0V9_RETIMER_CPU0_EN
0402LF
364
364
R6860 R643
PR883
R649
PR6817
PR6819
PR6803
PR6805
PR6810
R651
R650
C101
R647
R646
PU6502
21
21
21
21
37
38
14
19
11
15
32
21
40
39
TH
36
35
18
17
31
22
8
7
6
5
4
3
2
1
9
10
16
12
20
13
23
24
25
26
27
28
29
30
33
34
PJ09_P0_N
PJ09_P0_P
PR6530
PR6532
CS0
PWM0
TEMP0
ADDR_CFG
TH_GND
CFP
CS2
PWM2
CS3
PWM3
PWM7
CS1
RGND1
VSEN1
nPINALERT#||nPSYSCRIT#
TEMP1||ISYS
VINSEN||VSYS
VMON||IINSEN||VSYS||ISYS
VCCS
PWM6
PG0
PWM1
VSEN0
PWM5
PWM4
PMSDA
RGND0
EN0
nPMALERT#
SVCLK
PG1
CS4
CS5
nVRHOT#
nSVALERT#
CS6
SVDATA
PMSCL
EN1
VCC
CS7
SHORT
1 2
SHORT
1 2
21 21
2
1
2
1
R6786
21
21 PR6618
21
PR6614
21
21
21
21
21
21PR6603
21PR6604
21
2
1
21
21
2
1
21R6801
21PR6606
21PR6807
2
1 PC6601
2
1PR6605
2
1 PC6607
2
1 PC6605
2
1 PC6606
2
1 PC6603
2
1
PR6814
21
PR6616
2
1
PR6615
2
1 PC6604
21
PR6608
2
1R652
2
1R655
2
1
PR6607
2
1
PC6602
2
1 PC6540
21
21
21
21PR6531
21
21
1
SHEETDATE
23
7 3 2 16 5 4
E
A
B
C
E
D
C
B
A
7 6 5 4
D
DEPARTMENT
SIZE
PROJECT DOCUMENT NUMBER REV
REVIEWER
DESIGNER
OUT
OUT
IN
IN
OUT
IN
IN
OUT
BI
IN
PR6613
PR6612
PR6611
PR6610
PR6609
C



P0V9_CPU0_RT_2D_PHASE1
ESR=27M OHM
RI=3A
5*5.8
4.5*4.5*4.5
HCBS4545-101
DCR = 0.105M OHM
DCR=0.17MOHM
ISAT=60 @100C
PGL6312.121AHLT
6.5*6.5*10
ISAT=60 @100C
PGL6312.121AHLT
DCR=0.17MOHM
ISAT = 13A @ 100C
P0V9_CPU0_RT_2D_PHASE2
6.5*6.5*10
ESR=27M OHM
5*5.8
RI=3A
BOM NOTE
2023/3/28 MODIFY
PC6563,PC6584 = CH4224K1B01
PC6553_1,PC6576 = EMPTY
PR6556,PR6564,PR6557 = EMPTY
PR6554,PR6562,PR6553,PR6561 = CS00002JB13
PU6503,PU6504 = AL021590000 / TDA21590
2ND SOURCE: INFENEON BOM
PU6503,PU6504 = AL099390004 / ISL99390FRZ-TR5935
MAIN SOURCE: RENESAS BOM
Thu Aug 24 14:09:48 2023<NAME_2>
<NAME_1>
MB FABCGTI V02
363 OF 365
SW_P12V_AUX_P0V9_RETIMER_CPU0_FLT
P0V9_CPU0_RT_2D
SW_P12V_AUX_P0V9_RETIMER_CPU0_FLT
P0V9_RETIMER_CPU0_PVCC
P0V9_CPU0_RT_2D
P5V_AUX P3V3_AUX
P0V9_RETIMER_CPU0_PVCC
P12V_AUX
22UF
363364
363
364
363
363
363
364
363
363364
363
390UF390UF
20%
S MLFS MLFS MLFC0805
X 6S
S MLF
C0805
O S CO N
20%
SW_P0V9_RETIMER_CPU0_SW1
0402
SW_P0V9_RETIMER_CPU0_BOOT1
ISL99390FRZ-TR5935
SMLF
E MP TY
IC
2.2UF
10%
C0402
P0V9_RETIMER_CPU0_VCC1
22UF
25V
10%
3300PF
50V
X7R
SW_P0V9_RETIMER_CPU0_BOOT1_RC
560P F
S W _P 0V 9_RE TIME R_CP U0_S W 1_RC
NC_PV09_RETIMER_CPU0_GL1_1
NC_PV09_RETIMER_CPU0_GL2_1
0402LF
SW_P0V9_RETIMER_CPU0_PH1
C0402
10%
1%
C0805
20%
5.6 SW_P0V9_RETIMER_CPU0_BOOT2_RCSW_P0V9_RETIMER_CPU0_BOOT2
1/16W
1%
0402LFCHIP
5.6
1/16WCHIP
S P CA P
2.5V
470UF
20%
2.5V
20%
S P CA P
2.5V
470UF
S MLF
20%
S P CA P
2.5V
S MLF
470UF
20%
S P CA P
2.5V
20%
470UF
S P CA P
2.5V
470UF
20%
0402
X7R
50V
3300PF
10%
100UF
20%
S MLF
16V
O S CO N
16V
100UF
P0V9_CPU0_RT_2D VR PHASE1 & 2
SMLF
1/10W
C0402
C0805
20%
2.5V
499
22UF
10%
20%
390UF
2.5V
CHIP
S MLF
X6S
16V
22UF
20%
SMLF
IND
100NH/16A
1/16W
0
0402LF
CHIP
5%
0402LF
1/16W
0
5%
0603LF
1%4V
20%
C0805
X 6S
22UF
22UF
16V
X6S
20%
C0805
22UF
C0805
20%
16V
C0805
X 6S
20%
16V
22UF
C0805
16V
X 6S
1/16W
0402LF
1%
8.87K
E MP TY
4V
22UF
20%
X 6S
S MLF
A LUM
20%
C0805
16V
X6S
20%
C0805
22UF
20%
X 6S
22UF
16V
20%
C0805
X6S
C0805
20%
16V
22UF
C0805
X6S
22UF
16V
20%
22UF
16V
X6S
20%
22UF
4V
C0805
50V
IND
C0402
25V
X6S
10%
1UF
5%0
0402LF1/16W
C0402
X6S
10%
10V
2.2UF2.2
5%
CHIP
1/16W
0402LF
X6S
16V
IC
ISL99390FRZ-TR5935
C0402
X6S
10V
2.2UF
E MP TY
1/16W
8.87K
100NF
C0402
10%
50V
X7R
1%
1.5
E MP TY
1/8W
10%
50V
C0402
E MP TY
1/8W
0402LF
E MP TY
560P F
C0402
E MP TY
10%
50V
X6S
1UF 0.1UF
25V
0402
X 7R
100NF
X7R10%
C0402
C0402
10%
100NF
50V
IND 120NH/69A
SMLF
0402LF
0 5%
1/16WCHIP
10V
X6S
2.2UF
X6S
10V
C0402
1/16W
CHIP
5%
2.2
0402LF
50V
100NF
10%
X7R
C0402
CCBU
PV09_RETIMER_CPU0_VCCS
P0V9_RETIMER_CPU0_IMON1
P0V9_RETIMER_CPU0_TEMP0
P0V9_RETIMER_CPU0_PWM1
P0V9_RETIMER_CPU0_VCC2
P0V9_RETIMER_CPU0_LSET2
P0V9_RETIMER_CPU0_PWM2
P0V9_RETIMER_CPU0_TEMP0
NC_PV09_RETIMER_CPU0_DNC2
PV09_RETIMER_CPU0_VCCS
P0V9_RETIMER_CPU0_IMON2 SW_P0V9_RETIMER_CPU0_SW2
P0V9_RETIMER_CPU0_VOS2
NC_PV09_RETIMER_CPU0_GL2_2
NC_PV09_RETIMER_CPU0_GL1_2
SW_P0V9_RETIMER_CPU0_PH2
390UF
A LUM
100NF
P0V9_RETIMER_CPU0_LSET1
NC_PV09_RETIMER_CPU0_DNC1
10% X7R
S W _P 0V 9_RE TIME R_CP U0_S W 2_RC
CHIP
1.5
0402LF
1%
100NF
120NH/69A
50V
SMLF
X 7R
16V
C0402
10%
X 6S X 6S
22UF
4V
20%
20%X6S
P0V9_RETIMER_CPU0_VOS1
50V
X 7R
C0805 S MLF
0402LF
1%
2.5V
20%
S MLFS MLF
S P CA P A LUMA LUM
2.5V
470UF
PC6562
PC6812
PC6567_1PC6566_1
PC6585
PR6563
PC6564
PR6555
PR6562
PC6586_2 PC6587_2 PC6811 PC534 PC6573 PC6574
PC6571PC6570PC6569PC6568 PC6572
PR6554
2
1
2
1
2
1
2
1
21
2
1
21
2
1
2
1
1
30
25_29
3
36
10_19
39
34
4
32
40
7_9-20_24
5
37
38
41
6
35
31
33
2
21
21
1
30
25_29
3
36
10_19
39
34
4
32
40
7_9-20_24
5
37
38
41
6
35
31
33
2
21
PU6504
PR6560
PL6506
PL6504
PC6553_1
PR6552
PU6503
PC6552
PC6550_09P0_1
PR6556
PL6505
PC6565
PC6563
PC6554_1PC6555_1
PGND2
GL2
GL1
DNC
EN
PGND3
VOS
VIN2
PGND1
SW
LSET
IOUT
TOUT_FLT
PVCC
PHASE
VIN1
BOOT
AGND
VCC
REFIN
PWM
1 2
PGND2
GL2
GL1
DNC
EN
PGND3
VOS
VIN2
PGND1
SW
LSET
IOUT
TOUT_FLT
PVCC
PHASE
VIN1
BOOT
AGND
VCC
REFIN
PWM
1 2
1 2
2
1
2
1
2
1
2
1
2
1
2
1
2
1
2
1
2
1
2
1
21
21
2
1
2
1
2
1
21
2
1
2
1
2
1
2
1
2
1
2
1
2
1
2
1
2
1
2
1
2
1
2
1
2
1
2
1 PC6810
2
1
2
1
2
1
2
1
2
1
2
1
21
2
1
2
1
2
1
2
1
2
1 PC6561
2
1
2
1
PR6557
2
1
PR6551
2
1
PR6550
2
1 PC6556_1
2
1 PC6557_1
2
1 PC6558_1
1
SHEETDATE
23
7 3 2 16 5 4
E
A
B
C
E
D
C
B
A
7 6 5 4
D
DEPARTMENT
SIZE
PROJECT DOCUMENT NUMBER REV
REVIEWER
DESIGNER
OUT
IN
OUT
IN
OUT
IN
OUT
IN
PC6576
PR6561
PC6575
PC6551_09P0_2
PR6564
PC6578_2 PC6577_2
PC6806
PC6584
PC6579_2 PC6580_2 PC6581_2 PC6582_2
PC6583 PC6817
PR6553
PC6560 PC6816
PC6559_1
C



/475
PMBUS ADDRESS AND CONFIG
CONFIG/R
0/22.1K0X76RENESAS
VR ADDRESS(7-BIT)
0X76INFENEON
PR6601 =CS01002FB07
PR885 = CS25362FB02
PR6533 = CS14752FB04
PR6541,PR6542,PR6543,PR6544,PR6548 = EMPTY
R6800,PR6811,PR6820,PR6539,PR6540 = EMPTY
2ND SOURCE: INFENEON BOM
PU6510 = TBD / XDPE15284D-0000
PR6804,PR6806,PR6818,PR6821 = CS21002FB06
PC6600 = CH12206KB14
PC514 = CH3104J1B00
PC6546 = CH4106K1B01
PC523 = CH11006JB00
PU6510 = TBD / ISL69260IRAZ-T
2023/3/28 MODIFY
BOM NOTE
MAIN SOURCE: RENESAS BOM
OVER-CURRENT PROTECTION= 92A
MAX CURRENT = 57.6A
TRANSIENT TOLERANCE = 90MV
OUTPUT RIPPLE & NOISE < 46MV
OUTPUT VOLTAGE = 0.86V - 0.945V
DESIGN SPECIFICATION
CURRENT STEP = 22A
SLEW RATE = 2.5A/US
EFFICIENCY > 85% @TDC
WORK FREQUENCY = 600KHZ
TDC = 54.7A
REMOTE SENSE
TRACE SPACING = 5MIL
LOCAL SENSE
TRACE WIDTH = 10MIL
DIFFERENTIAL PAIR
Thu Aug 24 14:09:48 2023<NAME_2>
<NAME_1>
MB FABCGTI V02
364 OF 365
P0V9_CPU1_RT_2D P0V9_CPU1_RT_2D
P3V3_AUX
P3V3_AUX
P3V3_AUX
P5V_AUX
P12V_AUX
P3V3_AUX
P3V3_AUXP1V8_AUX
P0V9_CPU1_RT_2D_VR_CONTROLLER
P0V9_RETIMER_CPU1_EN1_R
P0V9_RETIMER_CPU1_INALERT
NC_P0V9_RETIMER_CPU1_IMON5
NC_P0V9_RETIMER_CPU1_PWM5
CHIP
366
X 6S
P0V9_RETIMER_CPU1_PWM1
P0V9_RETIMER_CPU1_IMON1
P0V9_RETIMER_CPU1_EN0_R
P0V9_RETIMER_CPU1_SENSE_R_P
PV09_RETIMER_CPU1_VCCS
P0V9_RETIMER_CPU1_SVID_SDA
TP_P0V9_RETIMER_CPU1_SVID_ALERT_N
IC
ISL69260IRAZ-T
SMLF
P0V9_RETIMER_CPU1_VCC
P0V9_RETIMER_CPU1_PMSCL_R
P0V9_RETIMER_CPU1_IMON2
P0V9_RETIMER_CPU1_VRHOT
NC_P0V9_RETIMER_CPU1_IMON3
NC_P0V9_RETIMER_CPU1_IMON4
NC_P0V9_RETIMER_CPU1_PG1
P0V9_RETIMER_CPU1_SVID_CLK
TP_P0V9_RETIMER_CPU1_PMALERT
P0V9_RETIMER_CPU1_PMSDA_R
NC_P0V9_RETIMER_CPU1_PWM4
NC_P0V9_RETIMER_CPU1_PWM3
NC_P0V9_RETIMER_CPU1_PWM7
PWRGD_P0V9_RETIMER_CPU1_R
P0V9_RETIMER_CPU1_PWM2
P0V9_RETIMER_CPU1_VMON
P0V9_RETIMER_CPU1_TEMP1_R
NC_P0V9_RETIMER_CPU1_IMON7
NC_P0V9_RETIMER_CPU1_PWM6
NC_P0V9_RETIMER_CPU1_IMON6
P0V9_RETIMER_CPU1_CFP
P0V9_RETIMER_CPU1_TEMP0
NC_P0V9_RETIMER_CPU1_PWM8
NC_P0V9_RETIMER_CPU1_IMON8
151
151
366
366
366
366
366
81
81
P0V9_RETIMER_CPU1_SENSE_SH_P
SM
EMPTY
P0V9_RETIMER_CPU1_SENSE_SH_N
SM
EMPTY
49.9 1% 0402LF
0402LF
CHIP
CHIP 1/16W
0402LF
CHIP
1K
1%
1/16W
P0V9_RETIMER_CPU1_PMSDA
P0V9_RETIMER_CPU1_PMSCL
0402LF
1/16WCHIP
1/16W
CHIP
0402LF
5%0
E MP TY
4.7K
1/16W 0402LF
5%0
1%
5%
0 5%
1/16W
5%
0 5%
5%
TP_P0V9_RETIMER_CPU1_VRHOT
0
0 5%
0 5%
5%0
0 5%
1/16W
C0402
C0402
X 6S
10%
16V
1UF100NF
50V
1%
0402LFCHIP
1/16W
CHIP
P0V9_RETIMER_CPU1_ADDR
1%
0.1UF
25V
P0V9_RETIMER_CPU1_VINSEN
EMPTY
CHIP
1%
1K
1/16W
0402LF
49.9 1%
3300P F
50V
0402
X 7R
10%
5%
0
1%1K
E MP TY
1%1K
0 5%
0
0402LF
0
0402
5%
0402LF
E MP TY
1%
1K
10%
E MP TY
0402
25V
0.1UF
X 7R
50V
470P F
0402
CHIP 1/16W
1/16W
E MP TY
1%
0402LF
10K
0
0402LF
CHIP 1/16W
1/16WCHIP
1/16WCHIP
1/16W
CHIP
1%
C0402
X 6S
20%
6.3V
10UF
10%
16V
1UF
10%
X 7R
C0402
1
1/16W
1K
0402LF
1%
CHIP
1/16W
E MP TY
5%
1/16W
1/16W
5.36K
0402
X 7R
1/16W
10%
10%
CHIP
0402LF
5%
CHIP
0402LF
CHIP
1/16W
E MP TY
50V
1000P F
1K 1%
0
1/16W
CHIP
0402LF
5%0
0 5%
0402LF1/16WCHIP
22.1K
5%0
5%0
E MP TY
0402LF1/16WE MP TY
1/16W
1%
1K
E MP TY
P0V9_RETIMER_CPU1_EN
5%0PWRGD_P0V9_RETIMER_CPU1
CHIP
0402LF
1/16W 0402LF
1/16WCHIP
1%
E MP TY 1/16W 0402LF
1K1%1K
R6861 R656
R660
PU6510
C107
PR6802PR6820PR6811
R661
R662
PR6806
PR6804
R657
PR6818
R658
21
21
37
38
14
19
11
15
32
21
40
39
TH
36
35
18
17
31
22
8
7
6
5
4
3
2
1
9
10
16
12
20
13
23
24
25
26
27
28
29
30
33
34
PJ09_P1_N
PJ09_P1_P
PR6600
PR6602
SHORT
1 2
SHORT
1 2
CS0
PWM0
TEMP0
ADDR_CFG
TH_GND
CFP
CS2
PWM2
CS3
PWM3
PWM7
CS1
RGND1
VSEN1
nPINALERT#||nPSYSCRIT#
TEMP1||ISYS
VINSEN||VSYS
VMON||IINSEN||VSYS||ISYS
VCCS
PWM6
PG0
PWM1
VSEN0
PWM5
PWM4
PMSDA
RGND0
EN0
nPMALERT#
SVCLK
PG1
CS4
CS5
nVRHOT#
nSVALERT#
CS6
SVDATA
PMSCL
EN1
VCC
CS7
21 21
2
1
R6787
21
2
1
PR6812
21
PR6538
2
1 PC6544
2
1 PC6543
2
1 PC6545
2
1 PC6546
21
21
21
21
21
21
21PR6816
2
1
PR6815
21
2
1 PC523
2
1 PC819
2
1
PR6813
21
2
1
2
1
2
1
21
21
21
21
21
21
21
2
1 PC6600
21PR6601
21
21
2
1R663
2
1R665
21PR6533
21PR6808
21PR6809
21PR885
2
1 PC514
2
1
PR6821
21
1
SHEETDATE
23
7 3 2 16 5 4
E
A
B
C
E
D
C
B
A
7 6 5 4
D
DEPARTMENT
SIZE
PROJECT DOCUMENT NUMBER REV
REVIEWER
DESIGNER
IN
OUT
IN
OUT
OUT
IN
IN
BI
OUT
IN
PR6539
PR6540
PR6541
PR6542
PR6543
PR6544
PR6548
R6800
C



P0V9_CPU1_RT_2D_PHASE2
PGL6312.121AHLT
ESR=27M OHM
HCBS4545-101
6.5*6.5*10
ISAT=60 @100C
5*5.8
RI=3A
ESR=27M OHM
DCR=0.17MOHM
5*5.8
ISAT=60 @100C
PGL6312.121AHLT
RI=3A
4.5*4.5*4.5
ISAT = 13A @ 100C
DCR=0.17MOHM
6.5*6.5*10
DCR = 0.105M OHM
P0V9_CPU1_RT_2D_PHASE1
MAIN SOURCE: RENESAS BOM
BOM NOTE PU6511,PU6512 = AL099390004 / ISL99390FRZ-TR5935
PC6611_1,PC6646 = EMPTY
PC6621,PC6640 = CH4224K1B01
PR6626,PR6631,PR6625 = EMPTY
PR6623,PR6629,PR6622,PR6628 = CS00002JB13
PU6511,PU6512 = AL021590000 / TDA21590
2ND SOURCE: INFENEON BOM
2023/3/28 MODIFY
Thu Aug 24 14:09:49 2023<NAME_2>
<NAME_1>
MB FABCGTI V02
365 OF 365
P0V9_CPU1_RT_2D
P12V_AUX
P5V_AUX
P0V9_RETIMER_CPU1_PVCC
SW_P12V_AUX_P0V9_RETIMER_CPU1_FLT
P3V3_AUX
P0V9_RETIMER_CPU1_PVCC
P0V9_CPU1_RT_2D
SW_P12V_AUX_P0V9_RETIMER_CPU1_FLT
X 6S
100NF
5.6 SW_P0V9_RETIMER_CPU1_BOOT1_RCSW_P0V9_RETIMER_CPU1_BOOT1
CHIP 0402LF1/16W
1%
5.6 SW_P0V9_RETIMER_CPU1_BOOT2_RCSW_P0V9_RETIMER_CPU1_BOOT2
CHIP 0402LF
1%
1/16W
S P CA P
2.5V
470UF
S MLF
20%
S P CA P
2.5V
470UF
S MLF
20%
S P CA P
2.5V
S MLF
20%
470UF
S P CA P
2.5V
S MLF
20%
470UF
S P CA P
2.5V
470UF
S MLF
20%
S P CA P
2.5V
470UF
20%
S MLF
0402
10%
X7R
50V
3300PF
0402
X7R
3300PF
10%
50V
S MLF
O S CO N
16V
100UF
20%
S MLF
O S CO N
20%
100UF
16V
X6S
C0402
10V
2.2UF
16V
C0805
X 6S
20%
IND
SMLF
100NH/16A
1.5
0402LF
1%
1/8W
E MP TY
10%
C0402
560P F
50V
10%
E MP TY
C0402
1/16W
CHIP
0402LF
5%
2.2
E MP TY
0402LF
1%
1/8W
1.5
25V
10%
X 7R
0.1UF
ISL99390FRZ-TR5935
IC
SMLF
10%
10V
C0402
2.2UF
X6S
0402LF1/16W
5%
CHIP
0
C0402
50V
100NF
10%
X7R
1UF
X6S
C0402
120NH/69A
SMLF
IND
C0805
X6S
20%
22UF
X7R10%
50V100NF
C0805
20%
X6S
22UF
C0805
4V
C0805
20% 20%
X6S 20%
X 6S
C0805
50V
10%
100NF
X7R
C0402
1/16W
CHIP
0402LF
0
5%
0402LF
1/16W
8.87K
E MP TY
1%
1/16W
1%
8.87K
E MP TY
ISL99390FRZ-TR5935
IC
SMLF
C0402
X6S
10V
1/16W
2.2
5% 10V
2.2UF
0
5%
1/16W
0 5%
0402LF1/16WCHIP
C0402
25V
10%
120NH/69A
SMLF
IND
C0402
X 7R
50V
C0805
X 6S
C0805
X 6S
C0805
16V
20%
C0805
20%
16V
C0402
10% X7R
16V
X6S
20%
C0805
X6S
C0805
22UF
C0805
20%
20%
C0805
20%
16V
20%
S MLF
0603LF
499
1%
CHIP
CCBU
P0V9_RETIMER_CPU1_VOS1
SW_P0V9_RETIMER_CPU1_PH2
SW_P0V9_RETIMER_CPU1_SW2
P0V9_RETIMER_CPU1_VOS2
NC_PV09_RETIMER_CPU1_GL2_2
SW_P0V9_RETIMER_CPU1_PH1
SW_P0V9_RETIMER_CPU1_SW1
NC_PV09_RETIMER_CPU1_GL1_1
NC_PV09_RETIMER_CPU1_GL2_1
P0V9_RETIMER_CPU1_LSET1
S W _P 0V 9_RE TIME R_CP U1_S W 1_RC
2.2UF
20%
S MLF
390UF390UF
10%
X 7R
C0402
X 6S
C0805
22UF
C0805
X 6S
E MP TY
0402LF
P0V9_RETIMER_CPU1_IMON1
P0V9_RETIMER_CPU1_PWM1
PV09_RETIMER_CPU1_VCCS
P0V9_RETIMER_CPU1_VCC1
10%
1UF 22UF 22UF
22UF22UF
16V
16V
50V100NF
560P F
50V 10%
22UF 22UF
4V
20%
4V
20% 2.5V 2.5V 1/10W
A LUMA LUM
E MP TY
P0V9_RETIMER_CPU1_VCC2
P0V9_RETIMER_CPU1_IMON2
PV09_RETIMER_CPU1_VCCS
NC_PV09_RETIMER_CPU1_DNC2
P0V9_RETIMER_CPU1_LSET2
10%
25V 16V 16V 16V
16V
22UF22UF16V
X6S
C0402
50V
100NF
4V
22UF 22UF
X 6S
20% 20%
390UF
A LUM
S W _P 0V 9_RE TIME R_CP U1_S W 2_RC
NC_PV09_RETIMER_CPU1_GL1_2
0402
P0V9_CPU1_RT_2D VR PHASE1 & 2
0402LF
P0V9_RETIMER_CPU1_PWM2
P0V9_RETIMER_CPU1_TEMP0
P0V9_RETIMER_CPU1_TEMP0
NC_PV09_RETIMER_CPU1_DNC1
2.5V
S MLF
2.5V
S MLF
A LUM
20%
390UF
22UF
365
365
366 365
365
366 365
365
365
366
365
366
C0402
X6S X6S
20%
CHIP
0402LF
X6S
X6S
22UF
PC6620
PR6630
PC6641
PC6622
PR6624
PC6630PC6629PC6628
PC6632PC6631PC6815
PC6627PC6626PC6625_1PC6624_1
PR6623
PC6814PC6813PC6643_2PC6642_2
PR6629
21
21
1
30
25_29
3
36
10_19
39
34
4
32
40
7_9-20_24
5
37
38
41
6
35
31
33
2
21
1
30
25_29
3
36
10_19
39
34
4
32
40
7_9-20_24
5
37
38
41
6
35
31
33
2
PL6510
PL6511
PR6621
PU6511
PL6512
PU6512
PR6627
1 2
PGND2
GL2
GL1
DNC
EN
PGND3
VOS
VIN2
PGND1
SW
LSET
IOUT
TOUT_FLT
PVCC
PHASE
VIN1
BOOT
AGND
VCC
REFIN
PWM
1 2
PGND2
GL2
GL1
DNC
EN
PGND3
VOS
VIN2
PGND1
SW
LSET
IOUT
TOUT_FLT
PVCC
PHASE
VIN1
BOOT
AGND
VCC
REFIN
PWM
1 2
2
1
2
1
2
1
2
1
2
1
2
1 PC6619
2
1
2
1
PR6625
2
1
2
1
2
1
2
1 PC473
2
1
2
1
2
1
2
1
2
1
2
1
2
1
21
2
1
2
1
2
1
2
1
2
1
2
1
2
1
2
1
21
2
1
21
2
1
PR6620
2
1
2
1
2
1
2
1
2
1
PR6619
2
1
2
1
2
1
2
1
2
1
2
1
2
1
2
1
2
1
21
2
1
2
1
2
1
21
2
1
21
2
1
2
1
2
1
2
1
2
1
1
SHEETDATE
23
7 3 2 16 5 4
E
A
B
C
E
D
C
B
A
7 6 5 4
D
DEPARTMENT
SIZE
PROJECT DOCUMENT NUMBER REV
REVIEWER
DESIGNER
OUT
IN
IN
IN
OUT
IN
OUT
OUT
PC6819
PC6818
PC6618
PC6617_1PC6616_1
PC6621
PC6615_1PC6614_1
PC6623
PC6612_1PC6613_1
PR6626
PC6609_09P1_1
PC6610
PR6622
PC6611_1
PC6639
PC6638_2PC6637_2PC6636_2
PC6640
PC6635_2
PC6807
PC6633_2PC6634_2
PR6631
PC6644_09P1_2
PC6645
PR6628
PC6646
C